G04 ================== begin FILE IDENTIFICATION RECORD ==================*
G04 Layout Name:  15126-1b.brd*
G04 Film Name:    L3*
G04 File Format:  Gerber RS274X*
G04 File Origin:  Cadence Allegro 16.6-2015-S079*
G04 Origin Date:  Fri Feb 10 17:22:13 2017*
G04 *
G04 Layer:  VIA CLASS/L3*
G04 Layer:  PIN/L3*
G04 Layer:  ETCH/L3*
G04 Layer:  DRAWING FORMAT/LAYER_PCB_STORY*
G04 Layer:  DRAWING FORMAT/LAYER_L3*
G04 *
G04 Offset:    (0.00 0.00)*
G04 Mirror:    No*
G04 Mode:      Positive*
G04 Rotation:  0*
G04 FullContactRelief:  No*
G04 UndefLineWidth:     6.00*
G04 ================== end FILE IDENTIFICATION RECORD ====================*
%FSLAX35Y35*MOIN*%
%IR0*IPPOS*OFA0.00000B0.00000*MIA0B0*SFA1.00000B1.00000*%
%ADD11C,.02*%
%ADD10C,.022*%
%ADD13C,.032*%
%ADD22C,.052*%
%ADD15C,.044*%
%ADD19C,.018*%
%ADD21C,.064*%
%ADD20C,.019*%
%ADD18C,.028*%
%ADD12C,.046*%
%ADD17C,.039*%
%ADD16C,.057*%
%ADD14C,.14*%
%ADD23C,.01*%
%ADD24C,.015*%
%ADD25C,.025*%
%ADD26C,.016*%
%ADD27C,.004*%
%ADD28C,.006*%
%ADD29C,.005*%
%ADD30C,.008*%
%ADD31C,.0035*%
%ADD32C,.0045*%
%ADD33C,.00352*%
%ADD34C,.0056*%
%ADD47C,.03004*%
%ADD44C,.04004*%
%ADD40C,.03204*%
%ADD42C,.07004*%
%ADD48C,.03604*%
%ADD39C,.02804*%
%ADD49C,.07404*%
%ADD43C,.03804*%
%ADD36C,.05604*%
%ADD46C,.07504*%
%ADD41C,.08404*%
%ADD37C,.11204*%
%ADD38C,.15004*%
%ADD35C,.11404*%
%ADD45C,.17804*%
G75*
%LPD*%
G75*
G36*
G01X1973300Y-60000D02*
X-19810D01*
Y-34500D01*
X1973300D01*
Y-60000D01*
G37*
G36*
G01X-3870Y170100D02*
X-4220Y170450D01*
G02X-3838Y171121I282J283D01*
G03X-9234Y176517I1869J7265D01*
G02X-9905Y176135I-388J-100D01*
G01X-16042Y182272D01*
Y236120D01*
X-7477Y244685D01*
Y304322D01*
X-14653Y311498D01*
Y338524D01*
X-11277Y341900D01*
X4600D01*
X8800Y337700D01*
Y271800D01*
X2000Y265000D01*
Y234800D01*
X7000Y229800D01*
Y195800D01*
X11200Y191600D01*
X43400D01*
X51700Y183300D01*
Y182035D01*
G02X50945Y181850I-400J0D01*
G03Y174922I-6654J-3464D01*
G02X51700Y174737I355J-185D01*
G01Y173100D01*
X48700Y170100D01*
X-3870D01*
G37*
G36*
G01X-20868Y245515D02*
X-21599Y246246D01*
Y263846D01*
X-20957Y264488D01*
X-13750D01*
X-13324Y264062D01*
Y247000D01*
X-14810Y245515D01*
X-20868D01*
G37*
G36*
G01X-20621Y661811D02*
G02X-19685Y662747I936J0D01*
G01X1972600D01*
Y637600D01*
X-20412D01*
G02X-20621Y638189I726J589D01*
G01Y661811D01*
G37*
G36*
G01X44739Y139400D02*
G03I-539J0D01*
G37*
G36*
G01Y130700D02*
G03I-539J0D01*
G37*
G36*
G01Y111500D02*
G03I-539J0D01*
G37*
G36*
G01X44639Y97800D02*
G03I-539J0D01*
G37*
G36*
G01X44839Y102700D02*
G03I-539J0D01*
G37*
G36*
G01X44739Y116800D02*
G03I-539J0D01*
G37*
G36*
G01X44839Y125600D02*
G03I-539J0D01*
G37*
G36*
G01X45139Y154100D02*
G03I-539J0D01*
G37*
G36*
G01X44839Y144800D02*
G03I-539J0D01*
G37*
G36*
G01X13236Y197000D02*
X12100Y198136D01*
Y232900D01*
X9100Y235900D01*
Y264300D01*
X13900Y269100D01*
Y336942D01*
X16254Y339296D01*
X38740D01*
X39734Y338302D01*
Y275252D01*
X39710Y275196D01*
G03Y274098I1290J-549D01*
G01X39734Y274042D01*
Y265955D01*
X39710Y265899D01*
G03Y264801I1290J-549D01*
G01X39734Y264745D01*
Y199494D01*
X37240Y197000D01*
X13236D01*
G37*
G36*
G01X30820Y447400D02*
X27106Y451114D01*
X19941D01*
X14164Y456891D01*
Y466972D01*
X18492Y471300D01*
X28441D01*
G02X28638Y470552I0J-400D01*
G03X32386I1874J-3308D01*
G02X32583Y471300I197J348D01*
G01X38441D01*
G02X38638Y470552I0J-400D01*
G03X42386I1874J-3308D01*
G02X42583Y471300I197J348D01*
G01X54400D01*
X56100Y469600D01*
Y452837D01*
X50689Y447426D01*
X43058D01*
X43032Y447400D01*
X30820D01*
G37*
G36*
G01X26912Y498842D02*
X25908Y499846D01*
X25929Y499950D01*
G03X24437Y503530I-3438J668D01*
G01Y505457D01*
X18025Y511869D01*
Y530099D01*
G02X18542Y530482I400J0D01*
G03X20400Y530912I558J1818D01*
G03Y533688I1300J1388D01*
G03X19462Y534167I-1300J-1388D01*
G02X19138Y534580I76J393D01*
G03X18703Y535933I-1999J104D01*
G03X18025Y538978I-1564J1250D01*
G01Y539425D01*
G03X17790Y543079I-925J1775D01*
G03Y543521I-1990J221D01*
G03Y547279I-690J1879D01*
G03X17792Y547704I-1990J222D01*
G03X17769Y551420I-757J1853D01*
G03X17787Y551789I-1982J282D01*
G03X15139Y553594I-648J1894D01*
G03X15053Y549838I648J-1894D01*
G03X15043Y549354I1982J-283D01*
G03X14429Y546042I757J-1853D01*
G02X14437Y545467I-274J-291D01*
G01X14270Y545300D01*
X-200D01*
X-5575Y550675D01*
Y560825D01*
X-3000Y563400D01*
X3000D01*
X3403Y563803D01*
X3489Y563800D01*
G03X4900Y564048I112J3500D01*
G03X5302Y570685I1300J3252D01*
G02X4800Y571072I-102J387D01*
G01Y578700D01*
X2300Y581200D01*
X-3100D01*
X-6800Y584900D01*
Y594200D01*
X-5200Y595800D01*
X6120D01*
G03X21478I7679J14830D01*
G01X40919D01*
G02X41317Y595362I0J-400D01*
G03X44573Y593854I1893J-182D01*
G02X45145Y593855I286J-279D01*
G03X48394Y595364I1355J1335D01*
G02X48792Y595800I398J36D01*
G01X57659D01*
X64250Y589209D01*
Y565386D01*
G02X63814Y564988I-400J0D01*
G03X60625Y559500I-314J-3488D01*
G03X60336Y556000I2875J-1999D01*
G03X63814Y551012I3164J-1500D01*
G02X64250Y550614I36J-398D01*
G01Y539400D01*
X63657Y538807D01*
X63542Y538843D01*
G03X62550Y531998I-1042J-3343D01*
G01Y527015D01*
X62534Y526978D01*
G03X62400Y526496I1847J-773D01*
G02X62002Y526523I-198J29D01*
G03X61770Y525565I-2002J-22D01*
G02X62499Y525515I353J-187D01*
G03X62534Y525426I1880J688D01*
G01X62550Y525389D01*
Y524419D01*
X62534Y524382D01*
G03X62395Y523868I1846J-775D01*
G02X61782Y523584I-397J52D01*
G03X61909Y520304I-1082J-1684D01*
G02X62550Y519985I241J-319D01*
G01Y510182D01*
G02X61842Y509927I-400J0D01*
G03Y507373I-1542J-1277D01*
G02X62550Y507118I308J-255D01*
G01Y499951D01*
X61441Y498842D01*
X42468D01*
G02X42079Y499335I0J400D01*
G03X38185I-1947J465D01*
G02X37796Y498842I-389J-93D01*
G01X26912D01*
G37*
G36*
G01X61839Y89800D02*
G03I-539J0D01*
G37*
G36*
G01X71589Y89600D02*
G03I-539J0D01*
G37*
G36*
G01X49239Y90700D02*
G03I-539J0D01*
G37*
G36*
G01X69131Y132600D02*
G03I-539J0D01*
G37*
G36*
G01X69171Y137800D02*
G03I-539J0D01*
G37*
G36*
G01X64427Y140064D02*
G03I-539J0D01*
G37*
G36*
G01X49439Y132600D02*
G03I-539J0D01*
G37*
G36*
G01X49339Y137600D02*
G03I-539J0D01*
G37*
G36*
G01X64276Y130602D02*
G03I-539J0D01*
G37*
G36*
G01X49239Y95500D02*
G03I-539J0D01*
G37*
G36*
G01X49139Y104900D02*
G03I-539J0D01*
G37*
G36*
G01X64121Y116409D02*
G03I-539J0D01*
G37*
G36*
G01X62961Y109413D02*
G03I-539J0D01*
G37*
G36*
G01X63041Y105100D02*
G03I-539J0D01*
G37*
G36*
G01X64397Y97620D02*
G03I-539J0D01*
G37*
G36*
G01X49239Y109600D02*
G03I-539J0D01*
G37*
G36*
G01X69123Y123900D02*
G03I-539J0D01*
G37*
G36*
G01X63063Y123395D02*
G03I-539J0D01*
G37*
G36*
G01X49339Y118900D02*
G03I-539J0D01*
G37*
G36*
G01X69193Y118680D02*
G03I-539J0D01*
G37*
G36*
G01X49439Y123500D02*
G03I-539J0D01*
G37*
G36*
G01X71339Y151400D02*
G03I-539J0D01*
G37*
G36*
G01X64417Y144800D02*
G03I-539J0D01*
G37*
G36*
G01X60839Y151500D02*
G03I-539J0D01*
G37*
G36*
G01X53000Y223300D02*
X51800Y224500D01*
Y258900D01*
X59984Y267084D01*
X72912D01*
X74529Y265467D01*
Y265408D01*
X74988Y264949D01*
Y224634D01*
X73654Y223300D01*
X53000D01*
G37*
G36*
G01X56235Y368998D02*
G03I-619J0D01*
G37*
G36*
G01X141708Y204500D02*
X141678Y204665D01*
G03X139097Y205420I-1478J-265D01*
G02X138521Y205408I-294J271D01*
G01X136200Y207729D01*
Y365568D01*
X136892Y366260D01*
X168327D01*
X168942Y365645D01*
Y357521D01*
X167640Y356219D01*
Y350923D01*
X168942Y349621D01*
Y325548D01*
X167637Y324243D01*
Y318960D01*
X168942Y317655D01*
Y293526D01*
X167633Y292217D01*
Y286978D01*
X168942Y285669D01*
Y261394D01*
X167641Y260093D01*
Y254824D01*
X168942Y253523D01*
Y229377D01*
X167727Y228162D01*
Y223011D01*
X168942Y221796D01*
Y215300D01*
X169700Y214542D01*
Y210258D01*
X166142Y206700D01*
X162700D01*
X161800Y205800D01*
X156442D01*
X155142Y204500D01*
X141708D01*
G37*
G36*
G01X131300Y199900D02*
X121000Y210200D01*
Y214500D01*
X122000Y215500D01*
X123000D01*
X123500Y215000D01*
Y212173D01*
X123499Y212164D01*
G03Y211902I1396J-131D01*
G01X123500Y211893D01*
Y211000D01*
X131700Y202800D01*
X140125D01*
G03X140275I75J1600D01*
G01X146800D01*
X147498Y203498D01*
X155557D01*
X155558Y203500D01*
X156000D01*
X157298Y204798D01*
X162215D01*
X162916Y205500D01*
X167500D01*
X172100Y210100D01*
Y214600D01*
X171000Y215700D01*
Y365500D01*
X172446D01*
G03X174354I954J1287D01*
G01X175446D01*
G03X177354I954J1287D01*
G01X178446D01*
G03X180354I954J1287D01*
G01X181446D01*
G03X183354I954J1287D01*
G01X184446D01*
G03X186354I954J1287D01*
G01X187446D01*
G03X189354I954J1287D01*
G01X210989D01*
X247959Y328530D01*
X262378D01*
G02X262778Y328114I0J-400D01*
G03X265580I1401J-54D01*
G02X265980Y328530I400J16D01*
G01X269438D01*
G02X269838Y328114I0J-400D01*
G03X271677Y326728I1401J-54D01*
G01X271794Y326766D01*
X274352Y324208D01*
G02X274191Y323544I-283J-283D01*
G03X275954Y321781I428J-1335D01*
G02X276618Y321942I381J-122D01*
G01X277158Y321402D01*
X277016Y321260D01*
Y321259D01*
G03X278998Y319277I983J-999D01*
G02X279282Y319278I142J-141D01*
G01X279997Y318563D01*
X279986Y318467D01*
G03X282589Y317600I1393J-158D01*
G01X283165D01*
G02X283519Y317014I0J-400D01*
G03X285999I1240J-654D01*
G02X286353Y317600I354J186D01*
G01X286929D01*
G03X289349I1210J709D01*
G01X289925D01*
G02X290279Y317014I0J-400D01*
G03X292759I1240J-654D01*
G02X293113Y317600I354J186D01*
G01X293689D01*
G03X296109I1210J709D01*
G01X296685D01*
G02X297039Y317014I0J-400D01*
G03X299519I1240J-654D01*
G02X299873Y317600I354J186D01*
G01X300449D01*
G03X302869I1210J709D01*
G01X303445D01*
G02X303799Y317014I0J-400D01*
G03X306279I1240J-654D01*
G02X306633Y317600I354J186D01*
G01X307208D01*
G03X309628I1210J709D01*
G01X310204D01*
G02X310558Y317014I0J-400D01*
G03X313038I1240J-654D01*
G02X313392Y317600I354J186D01*
G01X313968D01*
G03X316388I1210J709D01*
G01X316964D01*
G02X317318Y317014I0J-400D01*
G03X319798I1240J-654D01*
G02X320152Y317600I354J186D01*
G01X320728D01*
G03X323148I1210J709D01*
G01X323724D01*
G02X324078Y317014I0J-400D01*
G03X326558I1240J-654D01*
G02X326912Y317600I354J186D01*
G01X327488D01*
G03X329908I1210J709D01*
G01X330484D01*
G02X330838Y317014I0J-400D01*
G03X332966Y317445I1240J-654D01*
G02X332937Y318037I254J309D01*
G01X333377Y318477D01*
G02X334059Y318220I283J-283D01*
G03X335547Y319708I1399J89D01*
G02X335290Y320390I26J399D01*
G01X335733Y320833D01*
X335788Y320846D01*
G03X336821Y321879I-330J1363D01*
G01X336834Y321934D01*
X337957Y323057D01*
X338092Y322973D01*
G03X339934Y325034I746J1187D01*
G01X340381Y325481D01*
G02X341009Y325401I283J-283D01*
G03X342927Y327319I1209J709D01*
G02X342847Y327947I203J345D01*
G01X345462Y330562D01*
X345549Y330559D01*
G03X346999Y332009I49J1401D01*
G01X346996Y332096D01*
X347762Y332862D01*
G02X348038Y332869I142J-141D01*
G03X350018Y334849I940J1040D01*
G01X349890Y334990D01*
X350393Y335493D01*
G02X351049Y335355I283J-283D01*
G03X352862Y337168I1308J505D01*
G02X352724Y337824I145J373D01*
G01X355279Y340379D01*
X355389Y340351D01*
G03X357095Y342057I348J1358D01*
G01X357067Y342167D01*
X357564Y342664D01*
G02X358129Y342665I283J-283D01*
G03X360112Y344648I988J995D01*
G02X360113Y345213I284J282D01*
G01X360500Y345600D01*
X361084D01*
X361107Y345426D01*
G03X363887I1390J183D01*
G01X363910Y345600D01*
X367844D01*
X367867Y345426D01*
G03X370647I1390J183D01*
G01X370670Y345600D01*
X374604D01*
X374627Y345426D01*
G03X377407I1390J183D01*
G01X377430Y345600D01*
X378300D01*
X388200Y335700D01*
X431261D01*
X432840Y337279D01*
Y343361D01*
X431716Y344485D01*
X423647D01*
X423044Y345088D01*
Y351911D01*
X425633Y354500D01*
X429071D01*
X429105Y354343D01*
G03X431843I1369J304D01*
G01X431877Y354500D01*
X435830D01*
X435864Y354343D01*
G03X438602I1369J304D01*
G01X438636Y354500D01*
X440000D01*
X440312Y354188D01*
X440141Y354017D01*
X440102Y354002D01*
G03X441817Y351978I511J-1306D01*
G02X442444Y352056I344J-205D01*
G01X450150Y344350D01*
Y336845D01*
X450044Y336789D01*
G03X449670Y336501I656J-1239D01*
G02X449027Y336579I-293J272D01*
G03X448830Y334949I-1227J-679D01*
G02X449473Y334871I293J-272D01*
G03X450044Y334311I1226J679D01*
G01X450150Y334255D01*
Y325624D01*
G03X449995Y325450I1115J-1150D01*
G02X449481Y325344I-318J243D01*
G03X447633Y325149I-787J-1395D01*
G02X447113Y325140I-265J299D01*
G03X447155Y322704I-1019J-1236D01*
G02X447675Y322713I265J-299D01*
G03X449539Y322588I1019J1236D01*
G02X450150Y322248I211J-340D01*
G01Y318570D01*
X443090Y311510D01*
Y311252D01*
X442922Y311225D01*
G03X441960Y310585I227J-1384D01*
G02X441282I-339J213D01*
G03Y309097I-1188J-744D01*
G02X441960I339J-213D01*
G03X442922Y308457I1189J744D01*
G01X443090Y308430D01*
Y297516D01*
X442913Y297496D01*
G03X441894Y296965I182J-1592D01*
G02X441294I-300J265D01*
G03X439160Y294602I-1200J-1061D01*
G02X439186Y293972I-233J-325D01*
G03X441261Y292127I908J-1068D01*
G02X441927I333J-222D01*
G03X442915Y291513I1167J777D01*
G01X443090Y291491D01*
Y280516D01*
X442913Y280496D01*
G03X441894Y279965I182J-1592D01*
G02X441294I-300J265D01*
G03Y277843I-1200J-1061D01*
G02X441894I300J-265D01*
G03X442913Y277312I1201J1061D01*
G01X443090Y277292D01*
Y270305D01*
X441224Y268439D01*
Y268438D01*
X440680Y267893D01*
X440589Y267899D01*
G03X439448Y265573I-89J-1399D01*
G02X439439Y265299I-150J-132D01*
G01X439039Y264899D01*
G03X438564Y264424I725J-1200D01*
G01X437576Y263436D01*
G03X434972Y262648I-1057J-1204D01*
G01X434932Y262500D01*
X428894D01*
X428230Y263164D01*
Y263174D01*
X427825Y263579D01*
Y266615D01*
X426990Y267450D01*
X389000D01*
X384050Y262500D01*
X373004D01*
X372967Y262653D01*
G03X370047I-1460J-353D01*
G01X370010Y262500D01*
X360424D01*
G03X357810I-1307J-740D01*
G01X353548D01*
G03X351166I-1191J-740D01*
G01X350588D01*
G02X350231Y263080I0J400D01*
G03X347725I-1253J629D01*
G02X347368Y262500I-357J-180D01*
G01X346789D01*
G03X344407I-1191J-740D01*
G01X343828D01*
G02X343471Y263080I0J400D01*
G03X340965I-1253J629D01*
G02X340608Y262500I-357J-180D01*
G01X340029D01*
G03X337647I-1191J-740D01*
G01X337068D01*
G02X336711Y263080I0J400D01*
G03X334205I-1253J629D01*
G02X333848Y262500I-357J-180D01*
G01X333269D01*
G03X330887I-1191J-740D01*
G01X330308D01*
G02X329951Y263080I0J400D01*
G03X327445I-1253J629D01*
G02X327088Y262500I-357J-180D01*
G01X326509D01*
G03X324127I-1191J-740D01*
G01X323548D01*
G02X323191Y263080I0J400D01*
G03X320685I-1253J629D01*
G02X320328Y262500I-357J-180D01*
G01X316788D01*
G02X316431Y263080I0J400D01*
G03X313925I-1253J629D01*
G02X313568Y262500I-357J-180D01*
G01X312989D01*
G03X310607I-1191J-740D01*
G01X310028D01*
G02X309671Y263080I0J400D01*
G03X307165I-1253J629D01*
G02X306808Y262500I-357J-180D01*
G01X306230D01*
G03X303848I-1191J-740D01*
G01X303269D01*
G02X302912Y263080I0J400D01*
G03X300406I-1253J629D01*
G02X300049Y262500I-357J-180D01*
G01X299470D01*
G03X297088I-1191J-740D01*
G01X296509D01*
G02X296152Y263080I0J400D01*
G03X293646I-1253J629D01*
G02X293289Y262500I-357J-180D01*
G01X292710D01*
G03X290328I-1191J-740D01*
G01X289749D01*
G02X289392Y263080I0J400D01*
G03X286886I-1253J629D01*
G02X286529Y262500I-357J-180D01*
G01X285950D01*
G03X283568I-1191J-740D01*
G01X282989D01*
G02X282632Y263080I0J400D01*
G03X280126I-1253J629D01*
G02X279769Y262500I-357J-180D01*
G01X279190D01*
G03X276808I-1191J-740D01*
G01X276229D01*
G02X275872Y263080I0J400D01*
G03X273366I-1253J629D01*
G02X273009Y262500I-357J-180D01*
G01X272430D01*
G03X270476Y262936I-1191J-740D01*
G01X269500D01*
Y264454D01*
G02X270197Y264722I400J0D01*
G03Y266598I1042J938D01*
G02X269500Y266866I-297J268D01*
G01Y268354D01*
G02X270197Y268622I400J0D01*
G03Y270498I1042J938D01*
G02X269500Y270766I-297J268D01*
G01Y272200D01*
X266200Y275500D01*
X242200D01*
X169100Y202400D01*
X161400D01*
X160500Y201500D01*
X148500D01*
X146900Y199900D01*
X131300D01*
G37*
G36*
G01X136640Y368264D02*
X136200Y368704D01*
Y392600D01*
X130600Y398200D01*
Y403100D01*
X131500Y404000D01*
X144700D01*
X147900Y400800D01*
X163249D01*
X168942Y395107D01*
Y369031D01*
X168175Y368264D01*
X136640D01*
G37*
G36*
G01X269287Y208920D02*
X269255Y209675D01*
X270008Y210110D01*
X270646Y209705D01*
X270734Y209553D01*
X269374Y208768D01*
X269287Y208920D01*
G37*
G36*
G01X272652Y210861D02*
X272620Y211616D01*
X273373Y212051D01*
X274011Y211646D01*
X274099Y211495D01*
X272739Y210709D01*
X272652Y210861D01*
G37*
G36*
G01X276039Y216717D02*
X276007Y217472D01*
X276760Y217906D01*
X277398Y217501D01*
X277486Y217350D01*
X276125Y216565D01*
X276039Y216717D01*
G37*
G36*
G01X275498Y214141D02*
X274828Y214491D01*
Y215360D01*
X275498Y215710D01*
X275673Y215711D01*
X275672Y214140D01*
X275498Y214141D01*
G37*
G36*
G01X273191Y209299D02*
X273223Y208544D01*
X272470Y208109D01*
X271832Y208514D01*
X271744Y208665D01*
X273104Y209451D01*
X273191Y209299D01*
G37*
G36*
G01X279899Y217080D02*
X279931Y216325D01*
X279178Y215890D01*
X278540Y216295D01*
X278452Y216447D01*
X279812Y217231D01*
X279899Y217080D01*
G37*
G36*
G01X276579Y211252D02*
X276611Y210497D01*
X275858Y210063D01*
X275220Y210468D01*
X275132Y210619D01*
X276493Y211404D01*
X276579Y211252D01*
G37*
G36*
G01X277120Y213828D02*
X277790Y213478D01*
Y212609D01*
X277120Y212259D01*
X276945Y212258D01*
X276946Y213829D01*
X277120Y213828D01*
G37*
G36*
G01X270627Y216470D02*
X270337Y217254D01*
X270974Y217891D01*
X271758Y217601D01*
X271882Y217477D01*
X270751Y216346D01*
X270627Y216470D01*
G37*
G36*
G01X267869Y213712D02*
X267579Y214497D01*
X268216Y215133D01*
X269001Y214843D01*
X269124Y214719D01*
X267993Y213588D01*
X267869Y213712D01*
G37*
G36*
G01X269777Y214067D02*
X270067Y213282D01*
X269431Y212645D01*
X268646Y212935D01*
X268522Y213059D01*
X269653Y214190D01*
X269777Y214067D01*
G37*
G36*
G01X272535Y216824D02*
X272825Y216040D01*
X272188Y215403D01*
X271404Y215693D01*
X271280Y215817D01*
X272411Y216948D01*
X272535Y216824D01*
G37*
G36*
G01X289567Y208920D02*
X289535Y209675D01*
X290288Y210110D01*
X290926Y209705D01*
X291014Y209553D01*
X289654Y208768D01*
X289567Y208920D01*
G37*
G36*
G01X286178Y206965D02*
X286146Y207720D01*
X286899Y208155D01*
X287537Y207750D01*
X287625Y207599D01*
X286265Y206813D01*
X286178Y206965D01*
G37*
G36*
G01X282792Y205012D02*
X282760Y205767D01*
X283513Y206202D01*
X284151Y205797D01*
X284239Y205645D01*
X282879Y204861D01*
X282792Y205012D01*
G37*
G36*
G01X276259Y200750D02*
X276161Y201500D01*
X276874Y201999D01*
X277545Y201651D01*
X277645Y201507D01*
X276359Y200607D01*
X276259Y200750D01*
G37*
G36*
G01X279427Y203070D02*
X279395Y203825D01*
X280148Y204260D01*
X280786Y203855D01*
X280874Y203703D01*
X279514Y202918D01*
X279427Y203070D01*
G37*
G36*
G01X293471Y209299D02*
X293503Y208544D01*
X292750Y208109D01*
X292112Y208514D01*
X292024Y208665D01*
X293384Y209451D01*
X293471Y209299D01*
G37*
G36*
G01X290106Y207357D02*
X290138Y206602D01*
X289385Y206167D01*
X288747Y206572D01*
X288659Y206723D01*
X290019Y207509D01*
X290106Y207357D01*
G37*
G36*
G01X286720Y205404D02*
X286752Y204649D01*
X285999Y204214D01*
X285361Y204619D01*
X285273Y204771D01*
X286633Y205556D01*
X286720Y205404D01*
G37*
G36*
G01X283331Y203449D02*
X283363Y202694D01*
X282610Y202259D01*
X281972Y202664D01*
X281884Y202815D01*
X283244Y203601D01*
X283331Y203449D01*
G37*
G36*
G01X276032Y205012D02*
X276000Y205767D01*
X276753Y206202D01*
X277391Y205797D01*
X277479Y205645D01*
X276119Y204861D01*
X276032Y205012D01*
G37*
G36*
G01X279418Y206965D02*
X279386Y207720D01*
X280139Y208155D01*
X280777Y207750D01*
X280865Y207599D01*
X279505Y206813D01*
X279418Y206965D01*
G37*
G36*
G01X282807Y208920D02*
X282775Y209675D01*
X283528Y210110D01*
X284166Y209705D01*
X284254Y209553D01*
X282894Y208768D01*
X282807Y208920D01*
G37*
G36*
G01X286172Y210861D02*
X286140Y211616D01*
X286893Y212051D01*
X287531Y211646D01*
X287619Y211495D01*
X286259Y210709D01*
X286172Y210861D01*
G37*
G36*
G01X289558Y212815D02*
X289526Y213570D01*
X290279Y214005D01*
X290917Y213600D01*
X291005Y213449D01*
X289645Y212663D01*
X289558Y212815D01*
G37*
G36*
G01X272667Y203070D02*
X272635Y203825D01*
X273388Y204260D01*
X274026Y203855D01*
X274114Y203703D01*
X272754Y202918D01*
X272667Y203070D01*
G37*
G36*
G01X293486Y213208D02*
X293518Y212453D01*
X292765Y212018D01*
X292127Y212423D01*
X292039Y212575D01*
X293399Y213360D01*
X293486Y213208D01*
G37*
G36*
G01X279960Y205404D02*
X279992Y204649D01*
X279239Y204214D01*
X278601Y204619D01*
X278513Y204771D01*
X279873Y205556D01*
X279960Y205404D01*
G37*
G36*
G01X283346Y207357D02*
X283378Y206602D01*
X282625Y206167D01*
X281987Y206572D01*
X281899Y206723D01*
X283259Y207509D01*
X283346Y207357D01*
G37*
G36*
G01X290100Y211254D02*
X290132Y210499D01*
X289379Y210064D01*
X288741Y210469D01*
X288653Y210621D01*
X290013Y211406D01*
X290100Y211254D01*
G37*
G36*
G01X286711Y209299D02*
X286743Y208544D01*
X285990Y208109D01*
X285352Y208514D01*
X285264Y208665D01*
X286624Y209451D01*
X286711Y209299D01*
G37*
G36*
G01X276571Y203449D02*
X276603Y202694D01*
X275850Y202259D01*
X275212Y202664D01*
X275124Y202815D01*
X276484Y203601D01*
X276571Y203449D01*
G37*
G36*
G01X291873Y194932D02*
X291113Y195282D01*
Y196182D01*
X291873Y196532D01*
X292048D01*
Y194932D01*
X291873D01*
G37*
G36*
G01X293480Y205404D02*
X293512Y204649D01*
X292759Y204214D01*
X292121Y204619D01*
X292033Y204771D01*
X293393Y205556D01*
X293480Y205404D01*
G37*
G36*
G01X282603Y195793D02*
X282893Y195009D01*
X282256Y194372D01*
X281472Y194662D01*
X281348Y194786D01*
X282479Y195917D01*
X282603Y195793D01*
G37*
G36*
G01X283353Y198250D02*
X284113Y197900D01*
Y197000D01*
X283353Y196650D01*
X283178D01*
Y198250D01*
X283353D01*
G37*
G36*
G01X290091Y203449D02*
X290123Y202694D01*
X289370Y202259D01*
X288732Y202664D01*
X288644Y202815D01*
X290004Y203601D01*
X290091Y203449D01*
G37*
G36*
G01X286726Y201508D02*
X286758Y200753D01*
X286005Y200318D01*
X285367Y200723D01*
X285279Y200875D01*
X286639Y201660D01*
X286726Y201508D01*
G37*
G36*
G01X289558Y201115D02*
X289526Y201870D01*
X290279Y202305D01*
X290917Y201900D01*
X291005Y201749D01*
X289645Y200963D01*
X289558Y201115D01*
G37*
G36*
G01X286172Y199161D02*
X286140Y199916D01*
X286893Y200351D01*
X287531Y199946D01*
X287619Y199795D01*
X286259Y199009D01*
X286172Y199161D01*
G37*
G36*
G01X289552Y205012D02*
X289520Y205767D01*
X290273Y206202D01*
X290911Y205797D01*
X290999Y205645D01*
X289639Y204861D01*
X289552Y205012D01*
G37*
G36*
G01X280694Y195440D02*
X280404Y196225D01*
X281040Y196861D01*
X281825Y196571D01*
X281949Y196448D01*
X280817Y195316D01*
X280694Y195440D01*
G37*
G36*
G01X282253Y197650D02*
X281493Y198000D01*
Y198900D01*
X282253Y199250D01*
X282428D01*
Y197650D01*
X282253D01*
G37*
G36*
G01X286187Y203070D02*
X286155Y203825D01*
X286908Y204260D01*
X287546Y203855D01*
X287634Y203703D01*
X286274Y202918D01*
X286187Y203070D01*
G37*
G36*
G01X282805Y201119D02*
X282773Y201874D01*
X283526Y202309D01*
X284164Y201904D01*
X284252Y201753D01*
X282892Y200967D01*
X282805Y201119D01*
G37*
G36*
G01X293486Y201508D02*
X293518Y200753D01*
X292765Y200318D01*
X292127Y200723D01*
X292039Y200875D01*
X293399Y201660D01*
X293486Y201508D01*
G37*
G36*
G01X290100Y199554D02*
X290132Y198799D01*
X289379Y198364D01*
X288741Y198769D01*
X288653Y198921D01*
X290013Y199706D01*
X290100Y199554D01*
G37*
G36*
G01X277214Y232310D02*
X277564Y232980D01*
X278434D01*
X278784Y232310D01*
Y232135D01*
X277214D01*
Y232310D01*
G37*
G36*
G01X270766Y231109D02*
X271116Y231869D01*
X272016D01*
X272366Y231109D01*
Y230934D01*
X270766D01*
Y231109D01*
G37*
G36*
G01X267597Y229696D02*
X267307Y230480D01*
X267944Y231117D01*
X268728Y230827D01*
X268852Y230703D01*
X267721Y229572D01*
X267597Y229696D01*
G37*
G36*
G01X264848Y229516D02*
X265198Y230276D01*
X266098D01*
X266448Y229516D01*
Y229341D01*
X264848D01*
Y229516D01*
G37*
G36*
G01X269505Y230050D02*
X269795Y229266D01*
X269158Y228629D01*
X268374Y228919D01*
X268250Y229043D01*
X269381Y230174D01*
X269505Y230050D01*
G37*
G36*
G01X266948Y228416D02*
X266598Y227656D01*
X265698D01*
X265348Y228416D01*
Y228591D01*
X266948D01*
Y228416D01*
G37*
G36*
G01X272366Y230009D02*
X272016Y229249D01*
X271116D01*
X270766Y230009D01*
Y230184D01*
X272366D01*
Y230009D01*
G37*
G36*
G01X278607Y229197D02*
X279245Y229602D01*
X279998Y229167D01*
X279966Y228412D01*
X279879Y228261D01*
X278519Y229045D01*
X278607Y229197D01*
G37*
G36*
G01X276038Y236215D02*
X276006Y236970D01*
X276759Y237405D01*
X277397Y237000D01*
X277485Y236849D01*
X276125Y236063D01*
X276038Y236215D01*
G37*
G36*
G01X263218Y232713D02*
X263568Y233473D01*
X264468D01*
X264818Y232713D01*
Y232538D01*
X263218D01*
Y232713D01*
G37*
G36*
G01X266646Y233244D02*
X266356Y234029D01*
X266992Y234665D01*
X267777Y234375D01*
X267901Y234252D01*
X266769Y233120D01*
X266646Y233244D01*
G37*
G36*
G01X270773Y235009D02*
X271123Y235769D01*
X272023D01*
X272373Y235009D01*
Y234834D01*
X270773D01*
Y235009D01*
G37*
G36*
G01X281987Y235046D02*
X282625Y235451D01*
X283378Y235016D01*
X283346Y234261D01*
X283259Y234109D01*
X281899Y234895D01*
X281987Y235046D01*
G37*
G36*
G01X264818Y231613D02*
X264468Y230853D01*
X263568D01*
X263218Y231613D01*
Y231788D01*
X264818D01*
Y231613D01*
G37*
G36*
G01X268553Y233599D02*
X268843Y232814D01*
X268207Y232178D01*
X267422Y232468D01*
X267298Y232591D01*
X268430Y233723D01*
X268553Y233599D01*
G37*
G36*
G01X272373Y233909D02*
X272023Y233149D01*
X271123D01*
X270773Y233909D01*
Y234084D01*
X272373D01*
Y233909D01*
G37*
G36*
G01X276580Y234654D02*
X276612Y233899D01*
X275859Y233464D01*
X275221Y233869D01*
X275133Y234021D01*
X276493Y234806D01*
X276580Y234654D01*
G37*
G36*
G01X280777Y233869D02*
X280139Y233464D01*
X279386Y233899D01*
X279418Y234654D01*
X279505Y234806D01*
X280865Y234021D01*
X280777Y233869D01*
G37*
G36*
G01X276038Y220615D02*
X276006Y221370D01*
X276759Y221805D01*
X277397Y221400D01*
X277485Y221249D01*
X276125Y220463D01*
X276038Y220615D01*
G37*
G36*
G01X276580Y219054D02*
X276612Y218299D01*
X275859Y217864D01*
X275221Y218269D01*
X275133Y218421D01*
X276493Y219206D01*
X276580Y219054D01*
G37*
G36*
G01X270506Y225751D02*
X270796Y224967D01*
X270159Y224330D01*
X269375Y224620D01*
X269251Y224744D01*
X270382Y225875D01*
X270506Y225751D01*
G37*
G36*
G01X267096Y224160D02*
X266746Y223400D01*
X265846D01*
X265496Y224160D01*
Y224335D01*
X267096D01*
Y224160D01*
G37*
G36*
G01X273530Y226109D02*
X273180Y225349D01*
X272280D01*
X271930Y226109D01*
Y226284D01*
X273530D01*
Y226109D01*
G37*
G36*
G01X261933Y222565D02*
X262224Y221781D01*
X261588Y221144D01*
X260803Y221433D01*
X260679Y221557D01*
X261809Y222689D01*
X261933Y222565D01*
G37*
G36*
G01X276038Y224515D02*
X276006Y225270D01*
X276759Y225705D01*
X277397Y225300D01*
X277485Y225149D01*
X276125Y224363D01*
X276038Y224515D01*
G37*
G36*
G01X269225Y220026D02*
X268935Y220811D01*
X269571Y221447D01*
X270356Y221157D01*
X270480Y221034D01*
X269348Y219902D01*
X269225Y220026D01*
G37*
G36*
G01X278594Y225304D02*
X279232Y225709D01*
X279985Y225274D01*
X279953Y224519D01*
X279866Y224367D01*
X278506Y225153D01*
X278594Y225304D01*
G37*
G36*
G01X268726Y225528D02*
X268436Y226313D01*
X269073Y226949D01*
X269858Y226659D01*
X269981Y226535D01*
X268850Y225404D01*
X268726Y225528D01*
G37*
G36*
G01X265496Y225260D02*
X265846Y226020D01*
X266746D01*
X267096Y225260D01*
Y225085D01*
X265496D01*
Y225260D01*
G37*
G36*
G01X271930Y227209D02*
X272280Y227969D01*
X273180D01*
X273530Y227209D01*
Y227034D01*
X271930D01*
Y227209D01*
G37*
G36*
G01X280786Y226064D02*
X280148Y225659D01*
X279395Y226094D01*
X279427Y226849D01*
X279514Y227001D01*
X280874Y226215D01*
X280786Y226064D01*
G37*
G36*
G01X260024Y222211D02*
X259733Y222996D01*
X260369Y223633D01*
X261154Y223343D01*
X261278Y223220D01*
X260147Y222087D01*
X260024Y222211D01*
G37*
G36*
G01X271134Y220379D02*
X271424Y219595D01*
X270787Y218958D01*
X270003Y219248D01*
X269879Y219372D01*
X271010Y220503D01*
X271134Y220379D01*
G37*
G36*
G01X276580Y222954D02*
X276612Y222199D01*
X275859Y221764D01*
X275221Y222169D01*
X275133Y222321D01*
X276493Y223106D01*
X276580Y222954D01*
G37*
G36*
G01X283310Y222936D02*
X283342Y222181D01*
X282589Y221746D01*
X281951Y222151D01*
X281863Y222303D01*
X283223Y223087D01*
X283310Y222936D01*
G37*
G36*
G01X279966Y365308D02*
X279998Y364553D01*
X279245Y364118D01*
X278607Y364523D01*
X278519Y364675D01*
X279879Y365460D01*
X279966Y365308D01*
G37*
G36*
G01X266597Y362609D02*
X266247Y361849D01*
X265347D01*
X264997Y362609D01*
Y362784D01*
X266597D01*
Y362609D01*
G37*
G36*
G01X270497D02*
X270147Y361849D01*
X269247D01*
X268897Y362609D01*
Y362784D01*
X270497D01*
Y362609D01*
G37*
G36*
G01X283331Y367249D02*
X283363Y366494D01*
X282610Y366059D01*
X281972Y366464D01*
X281884Y366615D01*
X283244Y367401D01*
X283331Y367249D01*
G37*
G36*
G01X286720Y369204D02*
X286752Y368449D01*
X285999Y368014D01*
X285361Y368419D01*
X285273Y368570D01*
X286633Y369355D01*
X286720Y369204D01*
G37*
G36*
G01X276038Y364915D02*
X276006Y365670D01*
X276759Y366105D01*
X277397Y365700D01*
X277485Y365549D01*
X276125Y364763D01*
X276038Y364915D01*
G37*
G36*
G01X265397Y363709D02*
X265747Y364469D01*
X266647D01*
X266997Y363709D01*
Y363534D01*
X265397D01*
Y363709D01*
G37*
G36*
G01X269297D02*
X269647Y364469D01*
X270547D01*
X270897Y363709D01*
Y363534D01*
X269297D01*
Y363709D01*
G37*
G36*
G01X260430Y386611D02*
X259645Y386321D01*
X259009Y386958D01*
X259299Y387743D01*
X259423Y387866D01*
X260554Y386735D01*
X260430Y386611D01*
G37*
G36*
G01X257672Y389369D02*
X256888Y389079D01*
X256251Y389716D01*
X256541Y390500D01*
X256665Y390624D01*
X257796Y389493D01*
X257672Y389369D01*
G37*
G36*
G01X261848Y381767D02*
X261088Y382117D01*
X261089Y383017D01*
X261849Y383367D01*
X262024Y383366D01*
Y381767D01*
X261848D01*
G37*
G36*
G01X270796Y377766D02*
X270446Y377006D01*
X269546D01*
X269196Y377766D01*
Y377941D01*
X270796D01*
Y377766D01*
G37*
G36*
G01X266896D02*
X266546Y377006D01*
X265646D01*
X265296Y377766D01*
Y377941D01*
X266896D01*
Y377766D01*
G37*
G36*
G01X257318Y391277D02*
X258102Y391567D01*
X258739Y390930D01*
X258449Y390146D01*
X258325Y390022D01*
X257194Y391153D01*
X257318Y391277D01*
G37*
G36*
G01X269196Y378864D02*
X269546Y379624D01*
X270446D01*
X270796Y378864D01*
Y378689D01*
X269196D01*
Y378864D01*
G37*
G36*
G01X265296D02*
X265646Y379624D01*
X266546D01*
X266896Y378864D01*
Y378689D01*
X265296D01*
Y378864D01*
G37*
G36*
G01X262947Y383367D02*
X263707Y383017D01*
Y382117D01*
X262947Y381767D01*
X262772D01*
Y383366D01*
X262947Y383367D01*
G37*
G36*
G01X260075Y388519D02*
X260860Y388809D01*
X261497Y388173D01*
X261207Y387388D01*
X261083Y387264D01*
X259952Y388395D01*
X260075Y388519D01*
G37*
G36*
G01X276580Y359454D02*
X276612Y358699D01*
X275859Y358264D01*
X275221Y358669D01*
X275133Y358820D01*
X276493Y359605D01*
X276580Y359454D01*
G37*
G36*
G01X270303Y358516D02*
X269953Y357756D01*
X269053D01*
X268703Y358516D01*
Y358691D01*
X270303D01*
Y358516D01*
G37*
G36*
G01X279966Y361408D02*
X279998Y360653D01*
X279245Y360218D01*
X278607Y360623D01*
X278519Y360775D01*
X279879Y361560D01*
X279966Y361408D01*
G37*
G36*
G01X283340Y363354D02*
X283372Y362599D01*
X282619Y362164D01*
X281981Y362569D01*
X281893Y362720D01*
X283253Y363505D01*
X283340Y363354D01*
G37*
G36*
G01X286726Y365308D02*
X286758Y364553D01*
X286005Y364118D01*
X285367Y364523D01*
X285279Y364675D01*
X286639Y365460D01*
X286726Y365308D01*
G37*
G36*
G01X279412Y362961D02*
X279380Y363716D01*
X280133Y364151D01*
X280771Y363746D01*
X280859Y363595D01*
X279499Y362809D01*
X279412Y362961D01*
G37*
G36*
G01X268703Y359614D02*
X269053Y360374D01*
X269953D01*
X270303Y359614D01*
Y359439D01*
X268703D01*
Y359614D01*
G37*
G36*
G01X276038Y361015D02*
X276006Y361770D01*
X276759Y362205D01*
X277397Y361800D01*
X277485Y361649D01*
X276125Y360863D01*
X276038Y361015D01*
G37*
G36*
G01X264803Y359614D02*
X265153Y360374D01*
X266053D01*
X266403Y359614D01*
Y359439D01*
X264803D01*
Y359614D01*
G37*
G36*
G01X279412Y374661D02*
X279380Y375416D01*
X280133Y375851D01*
X280771Y375446D01*
X280859Y375295D01*
X279499Y374509D01*
X279412Y374661D01*
G37*
G36*
G01X264909Y374766D02*
X264559Y374006D01*
X263659D01*
X263309Y374766D01*
Y374941D01*
X264909D01*
Y374766D01*
G37*
G36*
G01X268809D02*
X268459Y374006D01*
X267559D01*
X267209Y374766D01*
Y374941D01*
X268809D01*
Y374766D01*
G37*
G36*
G01X272709D02*
X272359Y374006D01*
X271459D01*
X271109Y374766D01*
Y374941D01*
X272709D01*
Y374766D01*
G37*
G36*
G01X260940Y376691D02*
X260155Y376401D01*
X259519Y377038D01*
X259809Y377823D01*
X259933Y377946D01*
X261064Y376815D01*
X260940Y376691D01*
G37*
G36*
G01X263309Y375864D02*
X263659Y376624D01*
X264559D01*
X264909Y375864D01*
Y375689D01*
X263309D01*
Y375864D01*
G37*
G36*
G01X267209D02*
X267559Y376624D01*
X268459D01*
X268809Y375864D01*
Y375689D01*
X267209D01*
Y375864D01*
G37*
G36*
G01X271109D02*
X271459Y376624D01*
X272359D01*
X272709Y375864D01*
Y375689D01*
X271109D01*
Y375864D01*
G37*
G36*
G01X260585Y378599D02*
X261370Y378889D01*
X262006Y378253D01*
X261717Y377468D01*
X261593Y377344D01*
X260461Y378475D01*
X260585Y378599D01*
G37*
G36*
G01X280786Y389864D02*
X280148Y389459D01*
X279395Y389894D01*
X279427Y390649D01*
X279514Y390801D01*
X280874Y390015D01*
X280786Y389864D01*
G37*
G36*
G01X287537Y385969D02*
X286899Y385564D01*
X286146Y385999D01*
X286178Y386754D01*
X286265Y386905D01*
X287625Y386120D01*
X287537Y385969D01*
G37*
G36*
G01X290911Y384023D02*
X290273Y383618D01*
X289520Y384053D01*
X289552Y384808D01*
X289639Y384960D01*
X290999Y384175D01*
X290911Y384023D01*
G37*
G36*
G01X284151Y387923D02*
X283513Y387518D01*
X282760Y387953D01*
X282792Y388708D01*
X282879Y388860D01*
X284239Y388075D01*
X284151Y387923D01*
G37*
G36*
G01X268365Y399156D02*
X267580Y398866D01*
X266944Y399503D01*
X267234Y400288D01*
X267358Y400411D01*
X268489Y399280D01*
X268365Y399156D01*
G37*
G36*
G01X265607Y401914D02*
X264823Y401624D01*
X264186Y402261D01*
X264476Y403045D01*
X264600Y403169D01*
X265731Y402038D01*
X265607Y401914D01*
G37*
G36*
G01X274011Y393772D02*
X273373Y393367D01*
X272620Y393802D01*
X272652Y394557D01*
X272739Y394709D01*
X274099Y393923D01*
X274011Y393772D01*
G37*
G36*
G01X277397Y391819D02*
X276759Y391414D01*
X276006Y391849D01*
X276038Y392604D01*
X276125Y392755D01*
X277485Y391970D01*
X277397Y391819D01*
G37*
G36*
G01X288747Y387146D02*
X289385Y387551D01*
X290138Y387116D01*
X290106Y386361D01*
X290019Y386209D01*
X288659Y386995D01*
X288747Y387146D01*
G37*
G36*
G01X285361Y389100D02*
X285999Y389505D01*
X286752Y389070D01*
X286720Y388315D01*
X286633Y388163D01*
X285273Y388949D01*
X285361Y389100D01*
G37*
G36*
G01X278607Y392997D02*
X279245Y393402D01*
X279998Y392967D01*
X279966Y392212D01*
X279879Y392061D01*
X278519Y392845D01*
X278607Y392997D01*
G37*
G36*
G01X271832Y396905D02*
X272470Y397310D01*
X273223Y396875D01*
X273191Y396120D01*
X273104Y395968D01*
X271744Y396753D01*
X271832Y396905D01*
G37*
G36*
G01X268010Y401064D02*
X268795Y401354D01*
X269432Y400718D01*
X269142Y399933D01*
X269018Y399809D01*
X267887Y400940D01*
X268010Y401064D01*
G37*
G36*
G01X275221Y394950D02*
X275859Y395355D01*
X276612Y394920D01*
X276580Y394165D01*
X276493Y394013D01*
X275133Y394799D01*
X275221Y394950D01*
G37*
G36*
G01X265253Y403822D02*
X266037Y404112D01*
X266674Y403475D01*
X266384Y402691D01*
X266260Y402567D01*
X265129Y403698D01*
X265253Y403822D01*
G37*
G36*
G01X281972Y391055D02*
X282610Y391460D01*
X283363Y391025D01*
X283331Y390270D01*
X283244Y390118D01*
X281884Y390903D01*
X281972Y391055D01*
G37*
G36*
G01X292121Y385200D02*
X292759Y385605D01*
X293512Y385170D01*
X293480Y384415D01*
X293393Y384263D01*
X292033Y385049D01*
X292121Y385200D01*
G37*
G36*
G01X286875Y402836D02*
X286090Y402547D01*
X285453Y403183D01*
X285743Y403968D01*
X285867Y404092D01*
X286998Y402960D01*
X286875Y402836D01*
G37*
G36*
G01X291467Y400441D02*
X290683Y400151D01*
X290046Y400788D01*
X290336Y401572D01*
X290460Y401696D01*
X291591Y400565D01*
X291467Y400441D01*
G37*
G36*
G01X291115Y402351D02*
X291899Y402641D01*
X292536Y402004D01*
X292246Y401220D01*
X292122Y401096D01*
X290991Y402227D01*
X291115Y402351D01*
G37*
G36*
G01X259298Y401143D02*
X258514Y400853D01*
X257877Y401490D01*
X258167Y402274D01*
X258291Y402398D01*
X259422Y401267D01*
X259298Y401143D01*
G37*
G36*
G01X280777Y385969D02*
X280139Y385564D01*
X279386Y385999D01*
X279418Y386754D01*
X279505Y386905D01*
X280865Y386120D01*
X280777Y385969D01*
G37*
G36*
G01X274011Y389873D02*
X273373Y389468D01*
X272620Y389903D01*
X272652Y390658D01*
X272739Y390810D01*
X274099Y390025D01*
X274011Y389873D01*
G37*
G36*
G01X277391Y387923D02*
X276753Y387518D01*
X276000Y387953D01*
X276032Y388708D01*
X276119Y388860D01*
X277479Y388075D01*
X277391Y387923D01*
G37*
G36*
G01X287537Y382069D02*
X286899Y381664D01*
X286146Y382099D01*
X286178Y382854D01*
X286265Y383005D01*
X287625Y382220D01*
X287537Y382069D01*
G37*
G36*
G01X284151Y384023D02*
X283513Y383618D01*
X282760Y384053D01*
X282792Y384808D01*
X282879Y384960D01*
X284239Y384175D01*
X284151Y384023D01*
G37*
G36*
G01X290911Y380123D02*
X290273Y379718D01*
X289520Y380153D01*
X289552Y380908D01*
X289639Y381060D01*
X290999Y380275D01*
X290911Y380123D01*
G37*
G36*
G01X264332Y397289D02*
X263547Y396999D01*
X262911Y397635D01*
X263201Y398420D01*
X263325Y398544D01*
X264456Y397412D01*
X264332Y397289D01*
G37*
G36*
G01X267090Y394531D02*
X266305Y394241D01*
X265669Y394877D01*
X265959Y395662D01*
X266083Y395786D01*
X267214Y394654D01*
X267090Y394531D01*
G37*
G36*
G01X270637Y391819D02*
X269999Y391414D01*
X269246Y391849D01*
X269278Y392604D01*
X269365Y392755D01*
X270725Y391970D01*
X270637Y391819D01*
G37*
G36*
G01X258944Y403051D02*
X259728Y403341D01*
X260365Y402704D01*
X260075Y401920D01*
X259951Y401796D01*
X258820Y402927D01*
X258944Y403051D01*
G37*
G36*
G01X278601Y389100D02*
X279239Y389505D01*
X279992Y389070D01*
X279960Y388315D01*
X279873Y388163D01*
X278513Y388949D01*
X278601Y389100D01*
G37*
G36*
G01X285361Y385200D02*
X285999Y385605D01*
X286752Y385170D01*
X286720Y384415D01*
X286633Y384263D01*
X285273Y385049D01*
X285361Y385200D01*
G37*
G36*
G01X288747Y383246D02*
X289385Y383651D01*
X290138Y383216D01*
X290106Y382461D01*
X290019Y382309D01*
X288659Y383095D01*
X288747Y383246D01*
G37*
G36*
G01X281987Y387146D02*
X282625Y387551D01*
X283378Y387116D01*
X283346Y386361D01*
X283259Y386209D01*
X281899Y386995D01*
X281987Y387146D01*
G37*
G36*
G01X266736Y396438D02*
X267521Y396728D01*
X268157Y396092D01*
X267867Y395307D01*
X267743Y395183D01*
X266612Y396315D01*
X266736Y396438D01*
G37*
G36*
G01X263978Y399196D02*
X264763Y399486D01*
X265399Y398850D01*
X265109Y398065D01*
X264985Y397941D01*
X263854Y399073D01*
X263978Y399196D01*
G37*
G36*
G01X271847Y392997D02*
X272485Y393402D01*
X273238Y392967D01*
X273206Y392212D01*
X273119Y392061D01*
X271759Y392845D01*
X271847Y392997D01*
G37*
G36*
G01X275227Y391047D02*
X275865Y391452D01*
X276618Y391017D01*
X276586Y390262D01*
X276499Y390111D01*
X275139Y390895D01*
X275227Y391047D01*
G37*
G36*
G01X292121Y381300D02*
X292759Y381705D01*
X293512Y381270D01*
X293480Y380515D01*
X293393Y380363D01*
X292033Y381149D01*
X292121Y381300D01*
G37*
G36*
G01X282475Y402682D02*
X281690Y402392D01*
X281054Y403028D01*
X281344Y403813D01*
X281467Y403937D01*
X282599Y402805D01*
X282475Y402682D01*
G37*
G36*
G01X285233Y399924D02*
X284448Y399634D01*
X283812Y400270D01*
X284102Y401055D01*
X284225Y401179D01*
X285357Y400047D01*
X285233Y399924D01*
G37*
G36*
G01X287539Y397667D02*
X286901Y397262D01*
X286148Y397697D01*
X286180Y398452D01*
X286267Y398603D01*
X287627Y397818D01*
X287539Y397667D01*
G37*
G36*
G01X290926Y395714D02*
X290288Y395309D01*
X289535Y395744D01*
X289567Y396499D01*
X289654Y396651D01*
X291014Y395865D01*
X290926Y395714D01*
G37*
G36*
G01X284878Y401831D02*
X285663Y402121D01*
X286299Y401485D01*
X286009Y400700D01*
X285886Y400576D01*
X284754Y401708D01*
X284878Y401831D01*
G37*
G36*
G01X288747Y398846D02*
X289385Y399251D01*
X290138Y398816D01*
X290106Y398061D01*
X290019Y397909D01*
X288659Y398695D01*
X288747Y398846D01*
G37*
G36*
G01X292112Y396905D02*
X292750Y397310D01*
X293503Y396875D01*
X293471Y396120D01*
X293384Y395968D01*
X292024Y396753D01*
X292112Y396905D01*
G37*
G36*
G01X279418Y370765D02*
X279386Y371520D01*
X280139Y371955D01*
X280777Y371550D01*
X280865Y371399D01*
X279505Y370613D01*
X279418Y370765D01*
G37*
G36*
G01X276071Y368839D02*
X276039Y369594D01*
X276792Y370029D01*
X277430Y369624D01*
X277518Y369473D01*
X276158Y368687D01*
X276071Y368839D01*
G37*
G36*
G01X269002Y367200D02*
X269352Y367960D01*
X270252D01*
X270602Y367200D01*
Y367025D01*
X269002D01*
Y367200D01*
G37*
G36*
G01X261293Y369466D02*
X261643Y370226D01*
X262543D01*
X262893Y369466D01*
Y369291D01*
X261293D01*
Y369466D01*
G37*
G36*
G01X282807Y372720D02*
X282775Y373475D01*
X283528Y373910D01*
X284166Y373505D01*
X284254Y373353D01*
X282894Y372568D01*
X282807Y372720D01*
G37*
G36*
G01X278592Y396905D02*
X279230Y397310D01*
X279983Y396875D01*
X279951Y396120D01*
X279864Y395968D01*
X278504Y396753D01*
X278592Y396905D01*
G37*
G36*
G01X275227Y398846D02*
X275865Y399251D01*
X276618Y398816D01*
X276586Y398061D01*
X276499Y397909D01*
X275139Y398695D01*
X275227Y398846D01*
G37*
G36*
G01X271585Y401535D02*
X272306Y401761D01*
X272921Y401146D01*
X272695Y400425D01*
X272571Y400301D01*
X271461Y401412D01*
X271585Y401535D01*
G37*
G36*
G01X281981Y394950D02*
X282619Y395355D01*
X283372Y394920D01*
X283340Y394165D01*
X283253Y394013D01*
X281893Y394799D01*
X281981Y394950D01*
G37*
G36*
G01X285367Y392997D02*
X286005Y393402D01*
X286758Y392967D01*
X286726Y392212D01*
X286639Y392061D01*
X285279Y392845D01*
X285367Y392997D01*
G37*
G36*
G01X288732Y391055D02*
X289370Y391460D01*
X290123Y391025D01*
X290091Y390270D01*
X290004Y390118D01*
X288644Y390903D01*
X288732Y391055D01*
G37*
G36*
G01X292121Y389100D02*
X292759Y389505D01*
X293512Y389070D01*
X293480Y388315D01*
X293393Y388163D01*
X292033Y388949D01*
X292121Y389100D01*
G37*
G36*
G01X257966Y375276D02*
X257181Y374986D01*
X256545Y375622D01*
X256835Y376407D01*
X256958Y376531D01*
X258090Y375399D01*
X257966Y375276D01*
G37*
G36*
G01X260724Y372518D02*
X259939Y372228D01*
X259303Y372864D01*
X259593Y373649D01*
X259716Y373773D01*
X260848Y372641D01*
X260724Y372518D01*
G37*
G36*
G01X265748Y371666D02*
X265398Y370906D01*
X264498D01*
X264148Y371666D01*
Y371841D01*
X265748D01*
Y371666D01*
G37*
G36*
G01X269648D02*
X269298Y370906D01*
X268398D01*
X268048Y371666D01*
Y371841D01*
X269648D01*
Y371666D01*
G37*
G36*
G01X273554Y370410D02*
X273204Y369650D01*
X272304D01*
X271954Y370410D01*
Y370585D01*
X273554D01*
Y370410D01*
G37*
G36*
G01X277697Y401251D02*
X276911Y400963D01*
X276276Y401601D01*
X276568Y402385D01*
X276692Y402509D01*
X277821Y401375D01*
X277697Y401251D01*
G37*
G36*
G01X280777Y397668D02*
X280139Y397263D01*
X279386Y397698D01*
X279418Y398453D01*
X279505Y398605D01*
X280865Y397819D01*
X280777Y397668D01*
G37*
G36*
G01X284166Y395714D02*
X283528Y395309D01*
X282775Y395744D01*
X282807Y396499D01*
X282894Y396651D01*
X284254Y395865D01*
X284166Y395714D01*
G37*
G36*
G01X287531Y393772D02*
X286893Y393367D01*
X286140Y393802D01*
X286172Y394557D01*
X286259Y394709D01*
X287619Y393923D01*
X287531Y393772D01*
G37*
G36*
G01X290917Y391819D02*
X290279Y391414D01*
X289526Y391849D01*
X289558Y392604D01*
X289645Y392755D01*
X291005Y391970D01*
X290917Y391819D01*
G37*
G36*
G01X279960Y369204D02*
X279992Y368449D01*
X279239Y368014D01*
X278601Y368419D01*
X278513Y368570D01*
X279873Y369355D01*
X279960Y369204D01*
G37*
G36*
G01X270602Y366100D02*
X270252Y365340D01*
X269352D01*
X269002Y366100D01*
Y366275D01*
X270602D01*
Y366100D01*
G37*
G36*
G01X276571Y367249D02*
X276603Y366494D01*
X275850Y366059D01*
X275212Y366464D01*
X275124Y366615D01*
X276484Y367401D01*
X276571Y367249D01*
G37*
G36*
G01X262893Y368366D02*
X262543Y367606D01*
X261643D01*
X261293Y368366D01*
Y368541D01*
X262893D01*
Y368366D01*
G37*
G36*
G01X283346Y371157D02*
X283378Y370402D01*
X282625Y369967D01*
X281987Y370372D01*
X281899Y370523D01*
X283259Y371309D01*
X283346Y371157D01*
G37*
G36*
G01X287546Y389864D02*
X286908Y389459D01*
X286155Y389894D01*
X286187Y390649D01*
X286274Y390801D01*
X287634Y390015D01*
X287546Y389864D01*
G37*
G36*
G01X290911Y387923D02*
X290273Y387518D01*
X289520Y387953D01*
X289552Y388708D01*
X289639Y388860D01*
X290999Y388075D01*
X290911Y387923D01*
G37*
G36*
G01X280771Y393772D02*
X280133Y393367D01*
X279380Y393802D01*
X279412Y394557D01*
X279499Y394709D01*
X280859Y393923D01*
X280771Y393772D01*
G37*
G36*
G01X274017Y397669D02*
X273379Y397264D01*
X272626Y397699D01*
X272658Y398454D01*
X272745Y398605D01*
X274105Y397820D01*
X274017Y397669D01*
G37*
G36*
G01X277406Y395714D02*
X276768Y395309D01*
X276015Y395744D01*
X276047Y396499D01*
X276134Y396651D01*
X277494Y395865D01*
X277406Y395714D01*
G37*
G36*
G01X284157Y391819D02*
X283519Y391414D01*
X282766Y391849D01*
X282798Y392604D01*
X282885Y392755D01*
X284245Y391970D01*
X284157Y391819D01*
G37*
G36*
G01X257613Y377185D02*
X258397Y377475D01*
X259034Y376838D01*
X258744Y376054D01*
X258620Y375930D01*
X257489Y377061D01*
X257613Y377185D01*
G37*
G36*
G01X264148Y372766D02*
X264498Y373526D01*
X265398D01*
X265748Y372766D01*
Y372591D01*
X264148D01*
Y372766D01*
G37*
G36*
G01X268048D02*
X268398Y373526D01*
X269298D01*
X269648Y372766D01*
Y372591D01*
X268048D01*
Y372766D01*
G37*
G36*
G01X271954Y371510D02*
X272304Y372270D01*
X273204D01*
X273554Y371510D01*
Y371335D01*
X271954D01*
Y371510D01*
G37*
G36*
G01X260371Y374427D02*
X261155Y374717D01*
X261792Y374080D01*
X261502Y373296D01*
X261378Y373172D01*
X260247Y374303D01*
X260371Y374427D01*
G37*
G36*
G01X277348Y403163D02*
X278134Y403451D01*
X278769Y402813D01*
X278477Y402029D01*
X278353Y401905D01*
X277224Y403039D01*
X277348Y403163D01*
G37*
G36*
G01X281987Y398846D02*
X282625Y399251D01*
X283378Y398816D01*
X283346Y398061D01*
X283259Y397909D01*
X281899Y398695D01*
X281987Y398846D01*
G37*
G36*
G01X285352Y396905D02*
X285990Y397310D01*
X286743Y396875D01*
X286711Y396120D01*
X286624Y395968D01*
X285264Y396753D01*
X285352Y396905D01*
G37*
G36*
G01X288741Y394950D02*
X289379Y395355D01*
X290132Y394920D01*
X290100Y394165D01*
X290013Y394013D01*
X288653Y394799D01*
X288741Y394950D01*
G37*
G36*
G01X292127Y392997D02*
X292765Y393402D01*
X293518Y392967D01*
X293486Y392212D01*
X293399Y392061D01*
X292039Y392845D01*
X292127Y392997D01*
G37*
G36*
G01X262850Y404672D02*
X262065Y404382D01*
X261428Y405018D01*
X261718Y405803D01*
X261842Y405927D01*
X262973Y404796D01*
X262850Y404672D01*
G37*
G36*
G01X262495Y406580D02*
X263280Y406870D01*
X263916Y406233D01*
X263626Y405448D01*
X263502Y405325D01*
X262371Y406456D01*
X262495Y406580D01*
G37*
G36*
G01X284823Y407569D02*
X284038Y407279D01*
X283402Y407915D01*
X283692Y408700D01*
X283815Y408824D01*
X284947Y407692D01*
X284823Y407569D01*
G37*
G36*
G01X282065Y410327D02*
X281280Y410037D01*
X280644Y410673D01*
X280934Y411458D01*
X281057Y411582D01*
X282189Y410450D01*
X282065Y410327D01*
G37*
G36*
G01X284468Y409476D02*
X285253Y409766D01*
X285889Y409130D01*
X285599Y408345D01*
X285476Y408221D01*
X284344Y409353D01*
X284468Y409476D01*
G37*
G36*
G01X286520Y404744D02*
X287305Y405034D01*
X287941Y404398D01*
X287651Y403613D01*
X287528Y403489D01*
X286396Y404621D01*
X286520Y404744D01*
G37*
G36*
G01X281710Y412234D02*
X282495Y412524D01*
X283131Y411888D01*
X282841Y411103D01*
X282718Y410979D01*
X281586Y412111D01*
X281710Y412234D01*
G37*
G36*
G01X279717Y405440D02*
X278932Y405150D01*
X278296Y405786D01*
X278586Y406571D01*
X278709Y406695D01*
X279841Y405563D01*
X279717Y405440D01*
G37*
G36*
G01X276959Y408198D02*
X276174Y407908D01*
X275538Y408544D01*
X275828Y409329D01*
X275951Y409453D01*
X277083Y408321D01*
X276959Y408198D01*
G37*
G36*
G01X279362Y407347D02*
X280147Y407637D01*
X280783Y407001D01*
X280493Y406216D01*
X280370Y406092D01*
X279238Y407224D01*
X279362Y407347D01*
G37*
G36*
G01X276604Y410105D02*
X277389Y410395D01*
X278025Y409759D01*
X277735Y408974D01*
X277612Y408850D01*
X276480Y409982D01*
X276604Y410105D01*
G37*
G36*
G01X282120Y404589D02*
X282905Y404879D01*
X283541Y404243D01*
X283251Y403458D01*
X283128Y403334D01*
X281996Y404466D01*
X282120Y404589D01*
G37*
G36*
G01X269437Y409538D02*
X268651Y409250D01*
X268016Y409888D01*
X268308Y410672D01*
X268432Y410795D01*
X269561Y409661D01*
X269437Y409538D01*
G37*
G36*
G01X274939Y404009D02*
X274153Y403721D01*
X273518Y404359D01*
X273810Y405143D01*
X273934Y405267D01*
X275063Y404133D01*
X274939Y404009D01*
G37*
G36*
G01X272188Y406774D02*
X271402Y406485D01*
X270767Y407123D01*
X271059Y407908D01*
X271183Y408031D01*
X272312Y406897D01*
X272188Y406774D01*
G37*
G36*
G01X269088Y411449D02*
X269874Y411737D01*
X270509Y411100D01*
X270217Y410315D01*
X270093Y410192D01*
X268964Y411326D01*
X269088Y411449D01*
G37*
G36*
G01X274590Y405921D02*
X275376Y406209D01*
X276011Y405571D01*
X275719Y404787D01*
X275595Y404663D01*
X274466Y405797D01*
X274590Y405921D01*
G37*
G36*
G01X271839Y408685D02*
X272625Y408973D01*
X273260Y408335D01*
X272968Y407551D01*
X272844Y407428D01*
X271715Y408562D01*
X271839Y408685D01*
G37*
G36*
G01X292932Y210861D02*
X292900Y211616D01*
X293653Y212051D01*
X294291Y211646D01*
X294379Y211495D01*
X293019Y210709D01*
X292932Y210861D01*
G37*
G36*
G01X296860Y211254D02*
X296892Y210499D01*
X296139Y210064D01*
X295501Y210469D01*
X295413Y210621D01*
X296773Y211406D01*
X296860Y211254D01*
G37*
G36*
G01X298424Y216897D02*
X299062Y217302D01*
X299816Y216867D01*
X299784Y216111D01*
X299696Y215960D01*
X298337Y216745D01*
X298424Y216897D01*
G37*
G36*
G01X307147Y204392D02*
X306857Y205177D01*
X307493Y205814D01*
X308278Y205524D01*
X308402Y205400D01*
X307271Y204269D01*
X307147Y204392D01*
G37*
G36*
G01X309295Y207179D02*
X308535Y207529D01*
Y208429D01*
X309295Y208779D01*
X309470D01*
Y207179D01*
X309295D01*
G37*
G36*
G01X297178Y195274D02*
X296888Y196058D01*
X297525Y196695D01*
X298309Y196405D01*
X298433Y196281D01*
X297302Y195150D01*
X297178Y195274D01*
G37*
G36*
G01X304389Y201635D02*
X304099Y202419D01*
X304736Y203056D01*
X305520Y202766D01*
X305644Y202642D01*
X304513Y201511D01*
X304389Y201635D01*
G37*
G36*
G01X301631Y198877D02*
X301341Y199662D01*
X301978Y200298D01*
X302763Y200008D01*
X302886Y199884D01*
X301755Y198753D01*
X301631Y198877D01*
G37*
G36*
G01X295723Y191038D02*
X294963Y191388D01*
Y192288D01*
X295723Y192638D01*
X295898D01*
Y191038D01*
X295723D01*
G37*
G36*
G01X310920Y213818D02*
X311590Y213468D01*
Y212598D01*
X310920Y212248D01*
X310745D01*
Y213818D01*
X310920D01*
G37*
G36*
G01X310395Y208779D02*
X311155Y208429D01*
Y207529D01*
X310395Y207179D01*
X310220D01*
Y208779D01*
X310395D01*
G37*
G36*
G01X299087Y195627D02*
X299377Y194842D01*
X298741Y194206D01*
X297956Y194496D01*
X297832Y194619D01*
X298964Y195751D01*
X299087Y195627D01*
G37*
G36*
G01X306298Y201988D02*
X306588Y201203D01*
X305952Y200567D01*
X305167Y200857D01*
X305043Y200980D01*
X306175Y202112D01*
X306298Y201988D01*
G37*
G36*
G01X309056Y204746D02*
X309346Y203961D01*
X308710Y203324D01*
X307925Y203614D01*
X307801Y203738D01*
X308932Y204869D01*
X309056Y204746D01*
G37*
G36*
G01X303541Y199230D02*
X303831Y198445D01*
X303194Y197809D01*
X302409Y198099D01*
X302286Y198223D01*
X303417Y199354D01*
X303541Y199230D01*
G37*
G36*
G01X296823Y192638D02*
X297583Y192288D01*
Y191388D01*
X296823Y191038D01*
X296648D01*
Y192638D01*
X296823D01*
G37*
G36*
G01X304324Y205846D02*
X304034Y206631D01*
X304670Y207267D01*
X305455Y206977D01*
X305579Y206854D01*
X304447Y205722D01*
X304324Y205846D01*
G37*
G36*
G01X306440Y208490D02*
X305680Y208839D01*
X305679Y209739D01*
X306439Y210090D01*
X306614D01*
X306615Y208490D01*
X306440D01*
G37*
G36*
G01X296318Y201115D02*
X296286Y201870D01*
X297039Y202305D01*
X297677Y201900D01*
X297765Y201749D01*
X296405Y200963D01*
X296318Y201115D01*
G37*
G36*
G01X292932Y199161D02*
X292900Y199916D01*
X293653Y200351D01*
X294291Y199946D01*
X294379Y199795D01*
X293019Y199009D01*
X292932Y199161D01*
G37*
G36*
G01X301824Y203346D02*
X301534Y204131D01*
X302170Y204767D01*
X302955Y204477D01*
X303079Y204354D01*
X301947Y203222D01*
X301824Y203346D01*
G37*
G36*
G01X306233Y206199D02*
X306523Y205415D01*
X305886Y204778D01*
X305102Y205068D01*
X304978Y205192D01*
X306109Y206323D01*
X306233Y206199D01*
G37*
G36*
G01X307540Y210090D02*
X308300Y209740D01*
X308301Y208840D01*
X307541Y208490D01*
X307366D01*
X307365Y210090D01*
X307540D01*
G37*
G36*
G01Y215745D02*
X308210Y215395D01*
Y214525D01*
X307540Y214175D01*
X307365D01*
Y215745D01*
X307540D01*
G37*
G36*
G01X292973Y196532D02*
X293733Y196182D01*
Y195282D01*
X292973Y194932D01*
X292798D01*
Y196532D01*
X292973D01*
G37*
G36*
G01X296860Y199554D02*
X296892Y198799D01*
X296139Y198364D01*
X295501Y198769D01*
X295413Y198921D01*
X296773Y199706D01*
X296860Y199554D01*
G37*
G36*
G01X303733Y203699D02*
X304023Y202915D01*
X303386Y202278D01*
X302602Y202568D01*
X302478Y202692D01*
X303609Y203823D01*
X303733Y203699D01*
G37*
G36*
G01X296866Y207357D02*
X296898Y206602D01*
X296145Y206167D01*
X295507Y206572D01*
X295419Y206723D01*
X296779Y207509D01*
X296866Y207357D01*
G37*
G36*
G01X300231Y209299D02*
X300263Y208544D01*
X299510Y208109D01*
X298872Y208514D01*
X298784Y208665D01*
X300144Y209451D01*
X300231Y209299D01*
G37*
G36*
G01X323295Y204945D02*
X324055Y204595D01*
Y203695D01*
X323295Y203345D01*
X323120D01*
Y204945D01*
X323295D01*
G37*
G36*
G01X320873Y213556D02*
X321633Y213206D01*
Y212306D01*
X320873Y211956D01*
X320698D01*
Y213556D01*
X320873D01*
G37*
G36*
G01Y216956D02*
X321633Y216606D01*
Y215706D01*
X320873Y215356D01*
X320698D01*
Y216956D01*
X320873D01*
G37*
G36*
G01X321248Y207910D02*
X322032Y208200D01*
X322669Y207563D01*
X322379Y206779D01*
X322255Y206655D01*
X321124Y207786D01*
X321248Y207910D01*
G37*
G36*
G01X319449Y198216D02*
X319739Y197431D01*
X319103Y196795D01*
X318318Y197085D01*
X318194Y197208D01*
X319326Y198340D01*
X319449Y198216D01*
G37*
G36*
G01X322207Y200974D02*
X322497Y200189D01*
X321861Y199552D01*
X321076Y199842D01*
X320952Y199966D01*
X322083Y201097D01*
X322207Y200974D01*
G37*
G36*
G01X296318Y205015D02*
X296286Y205770D01*
X297039Y206205D01*
X297677Y205800D01*
X297765Y205649D01*
X296405Y204863D01*
X296318Y205015D01*
G37*
G36*
G01X299692Y206961D02*
X299660Y207716D01*
X300413Y208151D01*
X301051Y207746D01*
X301139Y207595D01*
X299779Y206809D01*
X299692Y206961D01*
G37*
G36*
G01X302537Y210250D02*
X301867Y210600D01*
Y211470D01*
X302537Y211820D01*
X302712D01*
Y210250D01*
X302537D01*
G37*
G36*
G01Y214150D02*
X301867Y214500D01*
Y215370D01*
X302537Y215720D01*
X302712D01*
Y214150D01*
X302537D01*
G37*
G36*
G01X292932Y203061D02*
X292900Y203816D01*
X293653Y204251D01*
X294291Y203846D01*
X294379Y203695D01*
X293019Y202909D01*
X292932Y203061D01*
G37*
G36*
G01X325613Y204186D02*
X324853Y204536D01*
Y205436D01*
X325613Y205786D01*
X325788D01*
Y204186D01*
X325613D01*
G37*
G36*
G01X322815Y209675D02*
X322055Y210025D01*
Y210925D01*
X322815Y211275D01*
X322990D01*
Y209675D01*
X322815D01*
G37*
G36*
G01Y213575D02*
X322055Y213925D01*
Y214825D01*
X322815Y215175D01*
X322990D01*
Y213575D01*
X322815D01*
G37*
G36*
G01Y217475D02*
X322055Y217825D01*
Y218725D01*
X322815Y219075D01*
X322990D01*
Y217475D01*
X322815D01*
G37*
G36*
G01X322589Y197699D02*
X322299Y198484D01*
X322935Y199120D01*
X323720Y198830D01*
X323844Y198707D01*
X322712Y197575D01*
X322589Y197699D01*
G37*
G36*
G01X292938Y206965D02*
X292906Y207720D01*
X293659Y208155D01*
X294297Y207750D01*
X294385Y207599D01*
X293025Y206813D01*
X292938Y206965D01*
G37*
G36*
G01X296327Y208920D02*
X296295Y209675D01*
X297048Y210110D01*
X297686Y209705D01*
X297774Y209553D01*
X296414Y208768D01*
X296327Y208920D01*
G37*
G36*
G01X321601Y206001D02*
X320816Y205711D01*
X320180Y206347D01*
X320470Y207132D01*
X320593Y207256D01*
X321725Y206124D01*
X321601Y206001D01*
G37*
G36*
G01X319773Y208056D02*
X319013Y208406D01*
Y209306D01*
X319773Y209656D01*
X319948D01*
Y208056D01*
X319773D01*
G37*
G36*
G01Y211956D02*
X319013Y212306D01*
Y213206D01*
X319773Y213556D01*
X319948D01*
Y211956D01*
X319773D01*
G37*
G36*
G01Y215856D02*
X319013Y216206D01*
Y217106D01*
X319773Y217456D01*
X319948D01*
Y215856D01*
X319773D01*
G37*
G36*
G01X315782Y196105D02*
X315492Y196890D01*
X316129Y197526D01*
X316914Y197236D01*
X317037Y197112D01*
X315906Y195981D01*
X315782Y196105D01*
G37*
G36*
G01X318540Y198863D02*
X318250Y199647D01*
X318887Y200284D01*
X319671Y199994D01*
X319795Y199870D01*
X318664Y198739D01*
X318540Y198863D01*
G37*
G36*
G01X300246Y205408D02*
X300278Y204653D01*
X299525Y204218D01*
X298887Y204623D01*
X298799Y204775D01*
X300159Y205560D01*
X300246Y205408D01*
G37*
G36*
G01X304161Y209928D02*
X304830Y209578D01*
Y208709D01*
X304160Y208359D01*
X303985Y208358D01*
X303986Y209929D01*
X304161Y209928D01*
G37*
G36*
G01Y213819D02*
X304831Y213469D01*
Y212599D01*
X304161Y212249D01*
X303986D01*
Y213819D01*
X304161D01*
G37*
G36*
G01Y217676D02*
X304830Y217326D01*
X304831Y216457D01*
X304161Y216107D01*
X303986Y216106D01*
X303985Y217677D01*
X304161Y217676D01*
G37*
G36*
G01X296860Y203454D02*
X296892Y202699D01*
X296139Y202264D01*
X295501Y202669D01*
X295413Y202821D01*
X296773Y203606D01*
X296860Y203454D01*
G37*
G36*
G01X326713Y205786D02*
X327473Y205436D01*
Y204536D01*
X326713Y204186D01*
X326538D01*
Y205786D01*
X326713D01*
G37*
G36*
G01X324478Y208940D02*
X325262Y209230D01*
X325899Y208593D01*
X325609Y207809D01*
X325485Y207685D01*
X324354Y208816D01*
X324478Y208940D01*
G37*
G36*
G01X323915Y214175D02*
X324675Y213825D01*
Y212925D01*
X323915Y212575D01*
X323740D01*
Y214175D01*
X323915D01*
G37*
G36*
G01Y218075D02*
X324675Y217725D01*
Y216825D01*
X323915Y216475D01*
X323740D01*
Y218075D01*
X323915D01*
G37*
G36*
G01X324498Y198052D02*
X324788Y197268D01*
X324151Y196631D01*
X323367Y196921D01*
X323243Y197045D01*
X324374Y198176D01*
X324498Y198052D01*
G37*
G36*
G01X317163Y204756D02*
X316403Y205106D01*
Y206006D01*
X317163Y206356D01*
X317338D01*
Y204756D01*
X317163D01*
G37*
G36*
G01X316698Y210199D02*
X315938Y210549D01*
Y211449D01*
X316698Y211799D01*
X316873D01*
Y210199D01*
X316698D01*
G37*
G36*
G01Y214099D02*
X315938Y214449D01*
Y215349D01*
X316698Y215699D01*
X316873D01*
Y214099D01*
X316698D01*
G37*
G36*
G01X311311Y197871D02*
X311021Y198656D01*
X311657Y199293D01*
X312442Y199003D01*
X312566Y198879D01*
X311435Y197748D01*
X311311Y197871D01*
G37*
G36*
G01X314069Y200629D02*
X313779Y201414D01*
X314415Y202050D01*
X315200Y201760D01*
X315324Y201637D01*
X314192Y200505D01*
X314069Y200629D01*
G37*
G36*
G01X318261Y206356D02*
X319021Y206006D01*
Y205106D01*
X318261Y204756D01*
X318086D01*
Y206356D01*
X318261D01*
G37*
G36*
G01X317798Y211799D02*
X318558Y211449D01*
Y210549D01*
X317798Y210199D01*
X317623D01*
Y211799D01*
X317798D01*
G37*
G36*
G01Y215699D02*
X318558Y215349D01*
Y214449D01*
X317798Y214099D01*
X317623D01*
Y215699D01*
X317798D01*
G37*
G36*
G01X313219Y198226D02*
X313509Y197441D01*
X312872Y196805D01*
X312087Y197095D01*
X311964Y197219D01*
X313095Y198350D01*
X313219Y198226D01*
G37*
G36*
G01X315976Y200984D02*
X316266Y200199D01*
X315630Y199563D01*
X314845Y199853D01*
X314721Y199976D01*
X315853Y201108D01*
X315976Y200984D01*
G37*
G36*
G01X331451Y204520D02*
X330691Y204870D01*
Y205770D01*
X331451Y206120D01*
X331626D01*
Y204520D01*
X331451D01*
G37*
G36*
G01Y208420D02*
X330691Y208770D01*
Y209670D01*
X331451Y210020D01*
X331626D01*
Y208420D01*
X331451D01*
G37*
G36*
G01Y212320D02*
X330691Y212670D01*
Y213570D01*
X331451Y213920D01*
X331626D01*
Y212320D01*
X331451D01*
G37*
G36*
G01X330361Y195720D02*
X329601Y196070D01*
Y196970D01*
X330361Y197320D01*
X330536D01*
Y195720D01*
X330361D01*
G37*
G36*
G01X332551Y206120D02*
X333311Y205770D01*
Y204870D01*
X332551Y204520D01*
X332376D01*
Y206120D01*
X332551D01*
G37*
G36*
G01Y210020D02*
X333311Y209670D01*
Y208770D01*
X332551Y208420D01*
X332376D01*
Y210020D01*
X332551D01*
G37*
G36*
G01Y213920D02*
X333311Y213570D01*
Y212670D01*
X332551Y212320D01*
X332376D01*
Y213920D01*
X332551D01*
G37*
G36*
G01X331461Y197320D02*
X332221Y196970D01*
Y196070D01*
X331461Y195720D01*
X331286D01*
Y197320D01*
X331461D01*
G37*
G36*
G01X311133Y204021D02*
X310373Y204371D01*
Y205271D01*
X311133Y205621D01*
X311308D01*
Y204021D01*
X311133D01*
G37*
G36*
G01X312676Y212249D02*
X312006Y212599D01*
Y213469D01*
X312676Y213819D01*
X312851D01*
Y212249D01*
X312676D01*
G37*
G36*
G01Y216149D02*
X312006Y216499D01*
Y217369D01*
X312676Y217719D01*
X312851D01*
Y216149D01*
X312676D01*
G37*
G36*
G01X312404Y207404D02*
X311644Y207754D01*
Y208654D01*
X312404Y209004D01*
X312579D01*
Y207404D01*
X312404D01*
G37*
G36*
G01X306179Y197060D02*
X305889Y197845D01*
X306525Y198482D01*
X307310Y198192D01*
X307434Y198068D01*
X306303Y196937D01*
X306179Y197060D01*
G37*
G36*
G01X310137Y201018D02*
X309847Y201803D01*
X310483Y202439D01*
X311268Y202149D01*
X311392Y202026D01*
X310260Y200894D01*
X310137Y201018D01*
G37*
G36*
G01X314673Y205921D02*
X315433Y205571D01*
Y204671D01*
X314673Y204321D01*
X314498D01*
Y205921D01*
X314673D01*
G37*
G36*
G01X314300Y211820D02*
X314970Y211470D01*
Y210600D01*
X314300Y210250D01*
X314125D01*
Y211820D01*
X314300D01*
G37*
G36*
G01Y215720D02*
X314970Y215370D01*
Y214500D01*
X314300Y214150D01*
X314125D01*
Y215720D01*
X314300D01*
G37*
G36*
G01X308093Y197409D02*
X308383Y196624D01*
X307746Y195988D01*
X306961Y196278D01*
X306838Y196402D01*
X307969Y197533D01*
X308093Y197409D01*
G37*
G36*
G01X310850Y200167D02*
X311140Y199382D01*
X310504Y198746D01*
X309719Y199036D01*
X309595Y199159D01*
X310727Y200291D01*
X310850Y200167D01*
G37*
G36*
G01X313607Y202925D02*
X313897Y202140D01*
X313261Y201504D01*
X312476Y201794D01*
X312352Y201917D01*
X313484Y203049D01*
X313607Y202925D01*
G37*
G36*
G01X328433Y205971D02*
X327673Y206321D01*
Y207221D01*
X328433Y207571D01*
X328608D01*
Y205971D01*
X328433D01*
G37*
G36*
G01Y209871D02*
X327673Y210221D01*
Y211121D01*
X328433Y211471D01*
X328608D01*
Y209871D01*
X328433D01*
G37*
G36*
G01X327273Y215367D02*
X326513Y215717D01*
Y216617D01*
X327273Y216967D01*
X327448D01*
Y215367D01*
X327273D01*
G37*
G36*
G01X325880Y195950D02*
X325590Y196735D01*
X326226Y197371D01*
X327011Y197081D01*
X327135Y196958D01*
X326003Y195826D01*
X325880Y195950D01*
G37*
G36*
G01X328433Y202071D02*
X327673Y202421D01*
Y203321D01*
X328433Y203671D01*
X328608D01*
Y202071D01*
X328433D01*
G37*
G36*
G01X329531Y207571D02*
X330291Y207221D01*
Y206321D01*
X329531Y205971D01*
X329356D01*
Y207571D01*
X329531D01*
G37*
G36*
G01Y211471D02*
X330291Y211121D01*
Y210221D01*
X329531Y209871D01*
X329356D01*
Y211471D01*
X329531D01*
G37*
G36*
G01X328373Y217667D02*
X329133Y217317D01*
Y216417D01*
X328373Y216067D01*
X328198D01*
Y217667D01*
X328373D01*
G37*
G36*
G01X327789Y196303D02*
X328079Y195519D01*
X327442Y194882D01*
X326658Y195172D01*
X326534Y195296D01*
X327665Y196427D01*
X327789Y196303D01*
G37*
G36*
G01X329531Y204071D02*
X330291Y203721D01*
Y202821D01*
X329531Y202471D01*
X329356D01*
Y204071D01*
X329531D01*
G37*
G36*
G01X327279Y232705D02*
X327311Y231950D01*
X326558Y231515D01*
X325920Y231920D01*
X325832Y232071D01*
X327192Y232857D01*
X327279Y232705D01*
G37*
G36*
G01X323906Y230758D02*
X323938Y230003D01*
X323185Y229568D01*
X322547Y229973D01*
X322459Y230125D01*
X323819Y230910D01*
X323906Y230758D01*
G37*
G36*
G01X321059Y223518D02*
X321729Y223168D01*
Y222298D01*
X321059Y221948D01*
X320884D01*
Y223518D01*
X321059D01*
G37*
G36*
G01Y227418D02*
X321729Y227068D01*
Y226198D01*
X321059Y225848D01*
X320884D01*
Y227418D01*
X321059D01*
G37*
G36*
G01X301117Y218239D02*
X300479Y217834D01*
X299726Y218269D01*
X299758Y219024D01*
X299845Y219175D01*
X301205Y218390D01*
X301117Y218239D01*
G37*
G36*
G01X329576Y237550D02*
X328906Y237900D01*
Y238770D01*
X329576Y239120D01*
X329751D01*
Y237550D01*
X329576D01*
G37*
G36*
G01X328182Y241644D02*
X327544Y241239D01*
X326791Y241674D01*
X326823Y242429D01*
X326910Y242580D01*
X328270Y241795D01*
X328182Y241644D01*
G37*
G36*
G01X322816Y221950D02*
X322146Y222300D01*
Y223170D01*
X322816Y223520D01*
X322991D01*
Y221950D01*
X322816D01*
G37*
G36*
G01X323351Y228412D02*
X323319Y229167D01*
X324072Y229602D01*
X324710Y229197D01*
X324798Y229046D01*
X323438Y228260D01*
X323351Y228412D01*
G37*
G36*
G01X322817Y225832D02*
X322147Y226182D01*
Y227052D01*
X322817Y227402D01*
X322992Y227403D01*
Y225832D01*
X322817D01*
G37*
G36*
G01X329576Y233650D02*
X328906Y234000D01*
Y234870D01*
X329576Y235220D01*
X329751D01*
Y233650D01*
X329576D01*
G37*
G36*
G01X326737Y230365D02*
X326705Y231120D01*
X327458Y231555D01*
X328096Y231150D01*
X328184Y230999D01*
X326824Y230213D01*
X326737Y230365D01*
G37*
G36*
G01X323366Y232320D02*
X323334Y233075D01*
X324087Y233510D01*
X324725Y233105D01*
X324813Y232953D01*
X323453Y232168D01*
X323366Y232320D01*
G37*
G36*
G01X319437Y227791D02*
X318767Y228141D01*
Y229010D01*
X319437Y229360D01*
X319611D01*
X319612Y227790D01*
X319437Y227791D01*
G37*
G36*
G01X319978Y230367D02*
X319946Y231122D01*
X320699Y231556D01*
X321337Y231151D01*
X321424Y231000D01*
X320065Y230214D01*
X319978Y230367D01*
G37*
G36*
G01X319436Y223949D02*
X318766Y224299D01*
Y225169D01*
X319436Y225519D01*
X319611D01*
Y223949D01*
X319436D01*
G37*
G36*
G01Y220053D02*
X318766Y220403D01*
Y221273D01*
X319436Y221623D01*
X319611D01*
Y220053D01*
X319436D01*
G37*
G36*
G01X302246Y219459D02*
X302883Y219864D01*
X303637Y219430D01*
X303605Y218675D01*
X303518Y218523D01*
X302157Y219308D01*
X302246Y219459D01*
G37*
G36*
G01X331200Y241076D02*
X331869Y240726D01*
X331870Y239857D01*
X331200Y239507D01*
X331024Y239506D01*
Y241077D01*
X331200Y241076D01*
G37*
G36*
G01Y237219D02*
X331870Y236869D01*
Y235999D01*
X331200Y235649D01*
X331025D01*
Y237219D01*
X331200D01*
G37*
G36*
G01X324440Y225519D02*
X325110Y225169D01*
Y224299D01*
X324440Y223949D01*
X324265D01*
Y225519D01*
X324440D01*
G37*
G36*
G01Y221619D02*
X325110Y221269D01*
Y220399D01*
X324440Y220049D01*
X324265D01*
Y221619D01*
X324440D01*
G37*
G36*
G01X327279Y228804D02*
X327311Y228049D01*
X326558Y227614D01*
X325920Y228019D01*
X325832Y228171D01*
X327192Y228956D01*
X327279Y228804D01*
G37*
G36*
G01X331199Y233337D02*
X331869Y232987D01*
Y232117D01*
X331199Y231767D01*
X331025D01*
Y233337D01*
X331199D01*
G37*
G36*
G01X330665Y230757D02*
X330697Y230002D01*
X329944Y229567D01*
X329306Y229972D01*
X329219Y230123D01*
X330579Y230908D01*
X330665Y230757D01*
G37*
G36*
G01X316056Y221950D02*
X315386Y222300D01*
Y223170D01*
X316056Y223520D01*
X316231D01*
Y221950D01*
X316056D01*
G37*
G36*
G01X316057Y218075D02*
X315387Y218425D01*
Y219295D01*
X316057Y219645D01*
X316232D01*
Y218075D01*
X316057D01*
G37*
G36*
G01X316056Y225875D02*
X315386Y226225D01*
Y227095D01*
X316056Y227445D01*
X316231D01*
Y225875D01*
X316056D01*
G37*
G36*
G01X319971Y234261D02*
X319939Y235016D01*
X320692Y235451D01*
X321330Y235046D01*
X321418Y234895D01*
X320058Y234109D01*
X319971Y234261D01*
G37*
G36*
G01X316627Y232333D02*
X316596Y233088D01*
X317349Y233523D01*
X317987Y233117D01*
X318075Y232966D01*
X316714Y232181D01*
X316627Y232333D01*
G37*
G36*
G01X316056Y229774D02*
X315387Y230124D01*
Y230994D01*
X316057Y231343D01*
X316232Y231344D01*
X316231Y229773D01*
X316056Y229774D01*
G37*
G36*
G01X323899Y234653D02*
X323931Y233898D01*
X323178Y233463D01*
X322540Y233868D01*
X322452Y234019D01*
X323812Y234805D01*
X323899Y234653D01*
G37*
G36*
G01X317680Y225519D02*
X318350Y225169D01*
Y224299D01*
X317680Y223949D01*
X317505D01*
Y225519D01*
X317680D01*
G37*
G36*
G01Y221619D02*
X318350Y221269D01*
Y220399D01*
X317680Y220049D01*
X317505D01*
Y221619D01*
X317680D01*
G37*
G36*
G01Y229370D02*
X318350Y229020D01*
Y228150D01*
X317680Y227800D01*
X317505D01*
Y229370D01*
X317680D01*
G37*
G36*
G01X320510Y232699D02*
X320542Y231944D01*
X319789Y231509D01*
X319151Y231914D01*
X319063Y232065D01*
X320423Y232851D01*
X320510Y232699D01*
G37*
G36*
G01X330118Y224517D02*
X330086Y225272D01*
X330839Y225706D01*
X331477Y225301D01*
X331564Y225150D01*
X330205Y224364D01*
X330118Y224517D01*
G37*
G36*
G01X329577Y221941D02*
X328907Y222291D01*
Y223160D01*
X329577Y223510D01*
X329751D01*
X329752Y221940D01*
X329577Y221941D01*
G37*
G36*
G01Y218075D02*
X328907Y218425D01*
Y219295D01*
X329577Y219645D01*
X329752D01*
Y218075D01*
X329577D01*
G37*
G36*
G01X333506Y226470D02*
X333474Y227225D01*
X334227Y227660D01*
X334865Y227255D01*
X334953Y227103D01*
X333593Y226318D01*
X333506Y226470D01*
G37*
G36*
G01X336336Y233650D02*
X335666Y234000D01*
Y234870D01*
X336336Y235220D01*
X336511D01*
Y233650D01*
X336336D01*
G37*
G36*
G01Y229799D02*
X335666Y230149D01*
Y231019D01*
X336336Y231369D01*
X336511D01*
Y229799D01*
X336336D01*
G37*
G36*
G01X337960Y237219D02*
X338630Y236869D01*
Y235999D01*
X337960Y235649D01*
X337785D01*
Y237219D01*
X337960D01*
G37*
G36*
G01X337955Y241120D02*
X338628Y240774D01*
X338632Y239904D01*
X337964Y239550D01*
X337788D01*
X337781Y241119D01*
X337955Y241120D01*
G37*
G36*
G01X331200Y221619D02*
X331870Y221269D01*
Y220399D01*
X331200Y220049D01*
X331025D01*
Y221619D01*
X331200D01*
G37*
G36*
G01X334045Y224908D02*
X334077Y224153D01*
X333324Y223718D01*
X332686Y224123D01*
X332598Y224274D01*
X333958Y225060D01*
X334045Y224908D01*
G37*
G36*
G01X337670Y227202D02*
X337834Y226464D01*
X337168Y225904D01*
X336469Y226192D01*
X336356Y226325D01*
X337557Y227336D01*
X337670Y227202D01*
G37*
G36*
G01X337962Y229389D02*
X338631Y229037D01*
X338628Y228167D01*
X337957Y227819D01*
X337782D01*
X337786Y229389D01*
X337962D01*
G37*
G36*
G01X337960Y233294D02*
X338630Y232944D01*
Y232074D01*
X337960Y231724D01*
X337785D01*
Y233294D01*
X337960D01*
G37*
G36*
G01X316597Y236215D02*
X316565Y236970D01*
X317318Y237405D01*
X317956Y237000D01*
X318044Y236849D01*
X316684Y236063D01*
X316597Y236215D01*
G37*
G36*
G01X312676Y223949D02*
X312006Y224299D01*
Y225169D01*
X312676Y225519D01*
X312851D01*
Y223949D01*
X312676D01*
G37*
G36*
G01Y220049D02*
X312006Y220399D01*
Y221269D01*
X312676Y221619D01*
X312851D01*
Y220049D01*
X312676D01*
G37*
G36*
G01Y227800D02*
X312006Y228150D01*
Y229020D01*
X312676Y229370D01*
X312851D01*
Y227800D01*
X312676D01*
G37*
G36*
G01X313211Y234261D02*
X313179Y235016D01*
X313932Y235451D01*
X314570Y235046D01*
X314657Y234895D01*
X313298Y234109D01*
X313211Y234261D01*
G37*
G36*
G01X312677Y231681D02*
X312007Y232031D01*
Y232901D01*
X312677Y233251D01*
X312851D01*
X312852Y231681D01*
X312677D01*
G37*
G36*
G01X320525Y236608D02*
X320557Y235853D01*
X319804Y235418D01*
X319166Y235823D01*
X319078Y235975D01*
X320438Y236760D01*
X320525Y236608D01*
G37*
G36*
G01X314300Y219620D02*
X314970Y219270D01*
Y218400D01*
X314300Y218050D01*
X314125D01*
Y219620D01*
X314300D01*
G37*
G36*
G01Y223520D02*
X314970Y223170D01*
Y222300D01*
X314300Y221950D01*
X314125D01*
Y223520D01*
X314300D01*
G37*
G36*
G01Y227445D02*
X314970Y227095D01*
Y226225D01*
X314300Y225875D01*
X314125D01*
Y227445D01*
X314300D01*
G37*
G36*
G01X317139Y234654D02*
X317171Y233899D01*
X316418Y233464D01*
X315780Y233869D01*
X315692Y234021D01*
X317052Y234806D01*
X317139Y234654D01*
G37*
G36*
G01X314300Y231369D02*
X314970Y231019D01*
Y230149D01*
X314300Y229799D01*
X314125D01*
Y231369D01*
X314300D01*
G37*
G36*
G01X326195Y223924D02*
X325526Y224274D01*
Y225143D01*
X326196Y225493D01*
X326371Y225494D01*
Y223923D01*
X326195Y223924D01*
G37*
G36*
G01X326196Y220049D02*
X325526Y220399D01*
Y221269D01*
X326196Y221619D01*
X326371D01*
Y220049D01*
X326196D01*
G37*
G36*
G01X330111Y228412D02*
X330079Y229167D01*
X330832Y229602D01*
X331470Y229197D01*
X331558Y229045D01*
X330198Y228261D01*
X330111Y228412D01*
G37*
G36*
G01X326766Y226484D02*
X326735Y227239D01*
X327488Y227673D01*
X328126Y227268D01*
X328214Y227117D01*
X326854Y226331D01*
X326766Y226484D01*
G37*
G36*
G01X332956Y231724D02*
X332286Y232074D01*
Y232944D01*
X332956Y233294D01*
X333131D01*
Y231724D01*
X332956D01*
G37*
G36*
G01X334580Y239120D02*
X335250Y238770D01*
Y237900D01*
X334580Y237550D01*
X334405D01*
Y239120D01*
X334580D01*
G37*
G36*
G01X327820Y223520D02*
X328490Y223170D01*
Y222300D01*
X327820Y221950D01*
X327645D01*
Y223520D01*
X327820D01*
G37*
G36*
G01X334038Y228802D02*
X334070Y228047D01*
X333317Y227613D01*
X332679Y228018D01*
X332592Y228169D01*
X333951Y228955D01*
X334038Y228802D01*
G37*
G36*
G01X330650Y226849D02*
X330682Y226094D01*
X329929Y225659D01*
X329291Y226064D01*
X329203Y226215D01*
X330563Y227001D01*
X330650Y226849D01*
G37*
G36*
G01X334579Y231378D02*
X335249Y231028D01*
Y230159D01*
X334579Y229809D01*
X334405D01*
X334404Y231379D01*
X334579Y231378D01*
G37*
G36*
G01X334580Y235220D02*
X335250Y234870D01*
Y234000D01*
X334580Y233650D01*
X334405D01*
Y235220D01*
X334580D01*
G37*
G36*
G01X294297Y382069D02*
X293659Y381664D01*
X292906Y382099D01*
X292938Y382854D01*
X293025Y383005D01*
X294385Y382220D01*
X294297Y382069D01*
G37*
G36*
G01X296647Y381489D02*
X297318Y381141D01*
X297321Y380272D01*
X296652Y379920D01*
X296476Y379919D01*
X296472Y381489D01*
X296647D01*
G37*
G36*
G01X297437Y375616D02*
X296689Y375507D01*
X296180Y376212D01*
X296518Y376888D01*
X296660Y376991D01*
X297579Y375718D01*
X297437Y375616D01*
G37*
G36*
G01X307796Y378161D02*
X307125Y377813D01*
X306412Y378311D01*
X306510Y379061D01*
X306610Y379204D01*
X307896Y378304D01*
X307796Y378161D01*
G37*
G36*
G01X305945Y379923D02*
X305275Y380273D01*
Y381142D01*
X305945Y381492D01*
X306119D01*
X306120Y379922D01*
X305945Y379923D01*
G37*
G36*
G01X305916Y387760D02*
X305246Y388110D01*
Y388980D01*
X305916Y389330D01*
X306091D01*
Y387760D01*
X305916D01*
G37*
G36*
G01X294291Y397671D02*
X293653Y397266D01*
X292900Y397701D01*
X292932Y398456D01*
X293019Y398607D01*
X294379Y397822D01*
X294291Y397671D01*
G37*
G36*
G01X297677Y395718D02*
X297039Y395313D01*
X296286Y395748D01*
X296318Y396503D01*
X296405Y396655D01*
X297765Y395869D01*
X297677Y395718D01*
G37*
G36*
G01X301066Y393763D02*
X300428Y393358D01*
X299675Y393793D01*
X299707Y394548D01*
X299794Y394699D01*
X301154Y393914D01*
X301066Y393763D01*
G37*
G36*
G01X304431Y391822D02*
X303793Y391417D01*
X303040Y391852D01*
X303072Y392607D01*
X303159Y392759D01*
X304519Y391973D01*
X304431Y391822D01*
G37*
G36*
G01X307541Y383409D02*
X308211Y383059D01*
Y382189D01*
X307541Y381839D01*
X307366D01*
Y383409D01*
X307541D01*
G37*
G36*
G01Y387309D02*
X308211Y386959D01*
Y386089D01*
X307541Y385739D01*
X307366D01*
Y387309D01*
X307541D01*
G37*
G36*
G01X295501Y398849D02*
X296139Y399254D01*
X296892Y398819D01*
X296860Y398064D01*
X296773Y397912D01*
X295413Y398697D01*
X295501Y398849D01*
G37*
G36*
G01X298887Y396896D02*
X299525Y397301D01*
X300278Y396866D01*
X300246Y396111D01*
X300159Y395959D01*
X298799Y396745D01*
X298887Y396896D01*
G37*
G36*
G01X302252Y394954D02*
X302890Y395359D01*
X303643Y394924D01*
X303611Y394169D01*
X303524Y394017D01*
X302164Y394803D01*
X302252Y394954D01*
G37*
G36*
G01X306830Y392359D02*
X307585Y392391D01*
X308020Y391638D01*
X307615Y391000D01*
X307464Y390912D01*
X306678Y392272D01*
X306830Y392359D01*
G37*
G36*
G01X294289Y378156D02*
X293618Y377808D01*
X292905Y378307D01*
X293003Y379057D01*
X293103Y379200D01*
X294389Y378300D01*
X294289Y378156D01*
G37*
G36*
G01X303288Y377955D02*
X302618Y378305D01*
Y379175D01*
X303288Y379525D01*
X303463D01*
Y377955D01*
X303288D01*
G37*
G36*
G01X304161Y381519D02*
X304831Y381169D01*
Y380299D01*
X304161Y379949D01*
X303986D01*
Y381519D01*
X304161D01*
G37*
G36*
G01X301083Y389870D02*
X300445Y389465D01*
X299692Y389900D01*
X299724Y390655D01*
X299811Y390806D01*
X301171Y390022D01*
X301083Y389870D01*
G37*
G36*
G01X294291Y393772D02*
X293653Y393367D01*
X292900Y393802D01*
X292932Y394557D01*
X293019Y394709D01*
X294379Y393923D01*
X294291Y393772D01*
G37*
G36*
G01X297677Y391819D02*
X297039Y391414D01*
X296286Y391849D01*
X296318Y392604D01*
X296405Y392755D01*
X297765Y391970D01*
X297677Y391819D01*
G37*
G36*
G01X304402Y387045D02*
X305157Y387011D01*
X305525Y386223D01*
X305065Y385623D01*
X304907Y385549D01*
X304243Y386971D01*
X304402Y387045D01*
G37*
G36*
G01X302903Y390803D02*
X303624Y391029D01*
X304239Y390414D01*
X304013Y389693D01*
X303889Y389569D01*
X302779Y390679D01*
X302903Y390803D01*
G37*
G36*
G01X295501Y394950D02*
X296139Y395355D01*
X296892Y394920D01*
X296860Y394165D01*
X296773Y394013D01*
X295413Y394799D01*
X295501Y394950D01*
G37*
G36*
G01X298881Y393000D02*
X299519Y393405D01*
X300272Y392970D01*
X300240Y392215D01*
X300153Y392063D01*
X298793Y392849D01*
X298881Y393000D01*
G37*
G36*
G01X298880Y385201D02*
X299518Y385606D01*
X300271Y385172D01*
X300239Y384416D01*
X300153Y384265D01*
X298792Y385050D01*
X298880Y385201D01*
G37*
G36*
G01X300781Y379520D02*
X301451Y379170D01*
Y378300D01*
X300781Y377950D01*
X300606D01*
Y379520D01*
X300781D01*
G37*
G36*
G01X295507Y387146D02*
X296145Y387551D01*
X296898Y387116D01*
X296866Y386361D01*
X296779Y386209D01*
X295419Y386995D01*
X295507Y387146D01*
G37*
G36*
G01X319343Y400823D02*
X320103Y400473D01*
Y399573D01*
X319343Y399223D01*
X319168D01*
Y400823D01*
X319343D01*
G37*
G36*
G01X320596Y396759D02*
X321380Y397049D01*
X322017Y396412D01*
X321727Y395628D01*
X321603Y395504D01*
X320472Y396635D01*
X320596Y396759D01*
G37*
G36*
G01X327820Y356120D02*
X328490Y355770D01*
Y354900D01*
X327820Y354550D01*
X327645D01*
Y356120D01*
X327820D01*
G37*
G36*
G01Y360020D02*
X328490Y359670D01*
Y358800D01*
X327820Y358450D01*
X327645D01*
Y360020D01*
X327820D01*
G37*
G36*
G01X324440Y373694D02*
X325110Y373344D01*
Y372474D01*
X324440Y372124D01*
X324265D01*
Y373694D01*
X324440D01*
G37*
G36*
G01Y369770D02*
X325110Y369420D01*
Y368550D01*
X324440Y368200D01*
X324265D01*
Y369770D01*
X324440D01*
G37*
G36*
G01X325919Y365701D02*
X326557Y366106D01*
X327310Y365672D01*
X327278Y364916D01*
X327191Y364764D01*
X325832Y365550D01*
X325919Y365701D01*
G37*
G36*
G01X327819Y363910D02*
X328489Y363560D01*
Y362691D01*
X327819Y362341D01*
X327644Y362340D01*
X327645Y363910D01*
X327819D01*
G37*
G36*
G01X324440Y381519D02*
X325110Y381169D01*
Y380299D01*
X324440Y379949D01*
X324265D01*
Y381519D01*
X324440D01*
G37*
G36*
G01X323521Y385361D02*
X324281Y385011D01*
Y384111D01*
X323521Y383761D01*
X323346D01*
Y385361D01*
X323521D01*
G37*
G36*
G01X324440Y377619D02*
X325110Y377269D01*
Y376399D01*
X324440Y376049D01*
X324265D01*
Y377619D01*
X324440D01*
G37*
G36*
G01X323521Y389261D02*
X324281Y388911D01*
Y388011D01*
X323521Y387661D01*
X323346D01*
Y389261D01*
X323521D01*
G37*
G36*
G01X294306Y389864D02*
X293668Y389459D01*
X292915Y389894D01*
X292947Y390649D01*
X293034Y390801D01*
X294394Y390015D01*
X294306Y389864D01*
G37*
G36*
G01X297671Y387923D02*
X297033Y387518D01*
X296280Y387953D01*
X296312Y388708D01*
X296399Y388860D01*
X297759Y388075D01*
X297671Y387923D01*
G37*
G36*
G01X326196Y372124D02*
X325526Y372474D01*
Y373344D01*
X326196Y373694D01*
X326371D01*
Y372124D01*
X326196D01*
G37*
G36*
G01Y368226D02*
X325526Y368576D01*
X325525Y369445D01*
X326195Y369796D01*
X326371D01*
Y368225D01*
X326196Y368226D01*
G37*
G36*
G01X328126Y366451D02*
X327488Y366046D01*
X326735Y366480D01*
X326766Y367235D01*
X326854Y367388D01*
X328214Y366602D01*
X328126Y366451D01*
G37*
G36*
G01X326767Y379755D02*
X326007Y380105D01*
Y381005D01*
X326767Y381355D01*
X326942D01*
Y379755D01*
X326767D01*
G37*
G36*
G01Y383655D02*
X326007Y384005D01*
Y384905D01*
X326767Y385255D01*
X326942D01*
Y383655D01*
X326767D01*
G37*
G36*
G01X326196Y376048D02*
X325526Y376398D01*
Y377268D01*
X326196Y377618D01*
X326371D01*
Y376048D01*
X326196D01*
G37*
G36*
G01X326767Y387555D02*
X326007Y387905D01*
Y388805D01*
X326767Y389155D01*
X326942D01*
Y387555D01*
X326767D01*
G37*
G36*
G01X325492Y394927D02*
X324707Y394637D01*
X324070Y395274D01*
X324360Y396059D01*
X324484Y396182D01*
X325616Y395051D01*
X325492Y394927D01*
G37*
G36*
G01X326767Y391455D02*
X326007Y391805D01*
Y392705D01*
X326767Y393055D01*
X326942D01*
Y391455D01*
X326767D01*
G37*
G36*
G01X294297Y385969D02*
X293659Y385564D01*
X292906Y385999D01*
X292938Y386754D01*
X293025Y386905D01*
X294385Y386120D01*
X294297Y385969D01*
G37*
G36*
G01X297671Y384023D02*
X297033Y383618D01*
X296280Y384053D01*
X296312Y384808D01*
X296399Y384960D01*
X297759Y384175D01*
X297671Y384023D01*
G37*
G36*
G01X299157Y379949D02*
X298487Y380299D01*
Y381169D01*
X299157Y381519D01*
X299332D01*
Y379949D01*
X299157D01*
G37*
G36*
G01X301024Y374256D02*
X300354Y373908D01*
X299641Y374407D01*
X299739Y375156D01*
X299839Y375299D01*
X301125Y374400D01*
X301024Y374256D01*
G37*
G36*
G01X299157Y376049D02*
X298487Y376399D01*
Y377269D01*
X299157Y377619D01*
X299332D01*
Y376049D01*
X299157D01*
G37*
G36*
G01X321349Y394450D02*
X320564Y394160D01*
X319928Y394796D01*
X320218Y395581D01*
X320341Y395705D01*
X321473Y394573D01*
X321349Y394450D01*
G37*
G36*
G01X318243Y399223D02*
X317483Y399573D01*
Y400473D01*
X318243Y400823D01*
X318418D01*
Y399223D01*
X318243D01*
G37*
G36*
G01X326196Y352649D02*
X325526Y352999D01*
Y353869D01*
X326196Y354219D01*
X326371D01*
Y352649D01*
X326196D01*
G37*
G36*
G01Y356549D02*
X325526Y356899D01*
Y357769D01*
X326196Y358119D01*
X326371D01*
Y356549D01*
X326196D01*
G37*
G36*
G01X322817Y366318D02*
X322147Y366668D01*
Y367538D01*
X322817Y367887D01*
X322992Y367888D01*
Y366317D01*
X322817Y366318D01*
G37*
G36*
G01X322816Y370199D02*
X322146Y370549D01*
Y371419D01*
X322816Y371769D01*
X322991D01*
Y370199D01*
X322816D01*
G37*
G36*
G01Y377950D02*
X322146Y378300D01*
Y379170D01*
X322816Y379520D01*
X322991D01*
Y377950D01*
X322816D01*
G37*
G36*
G01X322421Y383761D02*
X321661Y384111D01*
Y385011D01*
X322421Y385361D01*
X322596D01*
Y383761D01*
X322421D01*
G37*
G36*
G01X322816Y374050D02*
X322146Y374400D01*
Y375270D01*
X322816Y375620D01*
X322991D01*
Y374050D01*
X322816D01*
G37*
G36*
G01X322421Y387661D02*
X321661Y388011D01*
Y388911D01*
X322421Y389261D01*
X322596D01*
Y387661D01*
X322421D01*
G37*
G36*
G01X324710Y364523D02*
X324072Y364118D01*
X323319Y364553D01*
X323351Y365308D01*
X323438Y365460D01*
X324798Y364674D01*
X324710Y364523D01*
G37*
G36*
G01X326196Y360449D02*
X325526Y360799D01*
Y361669D01*
X326196Y362019D01*
X326371D01*
Y360449D01*
X326196D01*
G37*
G36*
G01X298881Y389100D02*
X299519Y389505D01*
X300272Y389070D01*
X300240Y388315D01*
X300153Y388163D01*
X298793Y388949D01*
X298881Y389100D01*
G37*
G36*
G01X295492Y391055D02*
X296130Y391460D01*
X296883Y391025D01*
X296851Y390270D01*
X296764Y390118D01*
X295404Y390903D01*
X295492Y391055D01*
G37*
G36*
G01X329270Y367668D02*
X329908Y368073D01*
X330661Y367639D01*
X330629Y366884D01*
X330542Y366731D01*
X329182Y367517D01*
X329270Y367668D01*
G37*
G36*
G01X331200Y365893D02*
X331870Y365543D01*
Y364674D01*
X331201Y364324D01*
X331025Y364323D01*
Y365894D01*
X331200Y365893D01*
G37*
G36*
G01X327820Y371769D02*
X328490Y371419D01*
Y370549D01*
X327820Y370199D01*
X327645D01*
Y371769D01*
X327820D01*
G37*
G36*
G01X327867Y381355D02*
X328627Y381005D01*
Y380105D01*
X327867Y379755D01*
X327692D01*
Y381355D01*
X327867D01*
G37*
G36*
G01Y385255D02*
X328627Y384905D01*
Y384005D01*
X327867Y383655D01*
X327692D01*
Y385255D01*
X327867D01*
G37*
G36*
G01X327820Y375620D02*
X328490Y375270D01*
Y374400D01*
X327820Y374050D01*
X327645D01*
Y375620D01*
X327820D01*
G37*
G36*
G01X327867Y389155D02*
X328627Y388805D01*
Y387905D01*
X327867Y387555D01*
X327692D01*
Y389155D01*
X327867D01*
G37*
G36*
G01Y393055D02*
X328627Y392705D01*
Y391805D01*
X327867Y391455D01*
X327692D01*
Y393055D01*
X327867D01*
G37*
G36*
G01X325138Y396837D02*
X325923Y397127D01*
X326560Y396491D01*
X326270Y395706D01*
X326146Y395582D01*
X325015Y396713D01*
X325138Y396837D01*
G37*
G36*
G01X319436Y372124D02*
X318766Y372474D01*
Y373344D01*
X319436Y373694D01*
X319611D01*
Y372124D01*
X319436D01*
G37*
G36*
G01X319437Y364359D02*
X318767Y364709D01*
Y365578D01*
X319436Y365928D01*
X319612Y365929D01*
X319611Y364359D01*
X319437D01*
G37*
G36*
G01X319436Y368200D02*
X318766Y368550D01*
Y369420D01*
X319436Y369770D01*
X319611D01*
Y368200D01*
X319436D01*
G37*
G36*
G01X321337Y362568D02*
X320699Y362163D01*
X319946Y362597D01*
X319978Y363352D01*
X320065Y363505D01*
X321424Y362719D01*
X321337Y362568D01*
G37*
G36*
G01X319436Y383824D02*
X318766Y384174D01*
Y385044D01*
X319436Y385394D01*
X319611D01*
Y383824D01*
X319436D01*
G37*
G36*
G01Y379949D02*
X318766Y380299D01*
Y381169D01*
X319436Y381519D01*
X319611D01*
Y379949D01*
X319436D01*
G37*
G36*
G01Y376049D02*
X318766Y376399D01*
Y377269D01*
X319436Y377619D01*
X319611D01*
Y376049D01*
X319436D01*
G37*
G36*
G01Y387749D02*
X318766Y388099D01*
Y388969D01*
X319436Y389319D01*
X319611D01*
Y387749D01*
X319436D01*
G37*
G36*
G01X313919Y396691D02*
X313159Y397041D01*
Y397941D01*
X313919Y398291D01*
X314094D01*
Y396691D01*
X313919D01*
G37*
G36*
G01X317956Y391819D02*
X317318Y391414D01*
X316565Y391849D01*
X316597Y392604D01*
X316684Y392755D01*
X318044Y391970D01*
X317956Y391819D01*
G37*
G36*
G01X322816Y358450D02*
X322146Y358800D01*
Y359670D01*
X322816Y360020D01*
X322991D01*
Y358450D01*
X322816D01*
G37*
G36*
G01X323689Y358114D02*
X324359Y357764D01*
Y356894D01*
X323689Y356544D01*
X323514D01*
Y358114D01*
X323689D01*
G37*
G36*
G01X321060Y371769D02*
X321730Y371419D01*
Y370549D01*
X321060Y370199D01*
X320885D01*
Y371769D01*
X321060D01*
G37*
G36*
G01Y367845D02*
X321730Y367495D01*
Y366625D01*
X321060Y366275D01*
X320885D01*
Y367845D01*
X321060D01*
G37*
G36*
G01Y387320D02*
X321730Y386970D01*
Y386100D01*
X321060Y385750D01*
X320885D01*
Y387320D01*
X321060D01*
G37*
G36*
G01Y383469D02*
X321730Y383119D01*
Y382249D01*
X321060Y381899D01*
X320885D01*
Y383469D01*
X321060D01*
G37*
G36*
G01Y379520D02*
X321730Y379170D01*
Y378300D01*
X321060Y377950D01*
X320885D01*
Y379520D01*
X321060D01*
G37*
G36*
G01Y375620D02*
X321730Y375270D01*
Y374400D01*
X321060Y374050D01*
X320885D01*
Y375620D01*
X321060D01*
G37*
G36*
G01Y391220D02*
X321730Y390870D01*
Y390000D01*
X321060Y389650D01*
X320885D01*
Y391220D01*
X321060D01*
G37*
G36*
G01X315713Y395549D02*
X316498Y395839D01*
X317134Y395203D01*
X316844Y394418D01*
X316721Y394294D01*
X315589Y395426D01*
X315713Y395549D01*
G37*
G36*
G01X315017Y398291D02*
X315777Y397941D01*
Y397041D01*
X315017Y396691D01*
X314842D01*
Y398291D01*
X315017D01*
G37*
G36*
G01X322546Y363746D02*
X323184Y364151D01*
X323937Y363716D01*
X323905Y362961D01*
X323818Y362809D01*
X322458Y363595D01*
X322546Y363746D01*
G37*
G36*
G01X333877Y358418D02*
X333845Y359173D01*
X334598Y359608D01*
X335236Y359203D01*
X335324Y359051D01*
X333964Y358266D01*
X333877Y358418D01*
G37*
G36*
G01X332957Y372167D02*
X332287Y372517D01*
Y373387D01*
X332957Y373736D01*
X333131Y373737D01*
Y372167D01*
X332957D01*
G37*
G36*
G01X334850Y370372D02*
X334212Y369967D01*
X333459Y370402D01*
X333491Y371157D01*
X333577Y371308D01*
X334937Y370523D01*
X334850Y370372D01*
G37*
G36*
G01X336336Y366275D02*
X335666Y366625D01*
Y367495D01*
X336336Y367845D01*
X336511D01*
Y366275D01*
X336336D01*
G37*
G36*
G01Y362350D02*
X335666Y362700D01*
Y363570D01*
X336336Y363920D01*
X336511D01*
Y362350D01*
X336336D01*
G37*
G36*
G01X332905Y381794D02*
X332145Y382144D01*
Y383044D01*
X332905Y383394D01*
X333080D01*
Y381794D01*
X332905D01*
G37*
G36*
G01Y385694D02*
X332145Y386044D01*
Y386944D01*
X332905Y387294D01*
X333080D01*
Y385694D01*
X332905D01*
G37*
G36*
G01X332956Y376049D02*
X332286Y376399D01*
Y377269D01*
X332956Y377619D01*
X333131D01*
Y376049D01*
X332956D01*
G37*
G36*
G01X332905Y389594D02*
X332145Y389944D01*
Y390844D01*
X332905Y391194D01*
X333080D01*
Y389594D01*
X332905D01*
G37*
G36*
G01Y397394D02*
X332145Y397744D01*
Y398644D01*
X332905Y398994D01*
X333080D01*
Y397394D01*
X332905D01*
G37*
G36*
G01Y393494D02*
X332145Y393844D01*
Y394744D01*
X332905Y395094D01*
X333080D01*
Y393494D01*
X332905D01*
G37*
G36*
G01X337959Y369760D02*
X338629Y369410D01*
Y368541D01*
X337959Y368191D01*
X337784Y368190D01*
X337785Y369760D01*
X337959D01*
G37*
G36*
G01X337960Y365919D02*
X338630Y365569D01*
Y364699D01*
X337960Y364349D01*
X337785D01*
Y365919D01*
X337960D01*
G37*
G36*
G01Y362019D02*
X338630Y361669D01*
Y360799D01*
X337960Y360449D01*
X337785D01*
Y362019D01*
X337960D01*
G37*
G36*
G01X336059Y371551D02*
X336697Y371956D01*
X337450Y371522D01*
X337418Y370766D01*
X337331Y370614D01*
X335972Y371400D01*
X336059Y371551D01*
G37*
G36*
G01X334003Y383394D02*
X334763Y383044D01*
Y382144D01*
X334003Y381794D01*
X333828D01*
Y383394D01*
X334003D01*
G37*
G36*
G01Y387294D02*
X334763Y386944D01*
Y386044D01*
X334003Y385694D01*
X333828D01*
Y387294D01*
X334003D01*
G37*
G36*
G01X334580Y379520D02*
X335250Y379170D01*
Y378300D01*
X334580Y377950D01*
X334405D01*
Y379520D01*
X334580D01*
G37*
G36*
G01Y375620D02*
X335250Y375270D01*
Y374400D01*
X334580Y374050D01*
X334405D01*
Y375620D01*
X334580D01*
G37*
G36*
G01X334003Y391194D02*
X334763Y390844D01*
Y389944D01*
X334003Y389594D01*
X333828D01*
Y391194D01*
X334003D01*
G37*
G36*
G01Y398994D02*
X334763Y398644D01*
Y397744D01*
X334003Y397394D01*
X333828D01*
Y398994D01*
X334003D01*
G37*
G36*
G01Y395094D02*
X334763Y394744D01*
Y393844D01*
X334003Y393494D01*
X333828D01*
Y395094D01*
X334003D01*
G37*
G36*
G01X321328Y354724D02*
X320658Y354376D01*
X319945Y354875D01*
X320043Y355624D01*
X320143Y355767D01*
X321429Y354868D01*
X321328Y354724D01*
G37*
G36*
G01X319440Y356482D02*
X318770Y356828D01*
X318766Y357699D01*
X319435Y358050D01*
X319610Y358051D01*
X319616Y356482D01*
X319440D01*
G37*
G36*
G01X316056Y362393D02*
X315387Y362743D01*
X315386Y363612D01*
X316056Y363962D01*
X316232Y363963D01*
X316231Y362392D01*
X316056Y362393D01*
G37*
G36*
G01Y370199D02*
X315386Y370549D01*
Y371419D01*
X316056Y371769D01*
X316231D01*
Y370199D01*
X316056D01*
G37*
G36*
G01Y366275D02*
X315386Y366625D01*
Y367495D01*
X316056Y367845D01*
X316231D01*
Y366275D01*
X316056D01*
G37*
G36*
G01Y385750D02*
X315386Y386100D01*
Y386970D01*
X316056Y387320D01*
X316231D01*
Y385750D01*
X316056D01*
G37*
G36*
G01Y381850D02*
X315386Y382200D01*
Y383070D01*
X316056Y383420D01*
X316231D01*
Y381850D01*
X316056D01*
G37*
G36*
G01Y377950D02*
X315386Y378300D01*
Y379170D01*
X316056Y379520D01*
X316231D01*
Y377950D01*
X316056D01*
G37*
G36*
G01Y374050D02*
X315386Y374400D01*
Y375270D01*
X316056Y375620D01*
X316231D01*
Y374050D01*
X316056D01*
G37*
G36*
G01X317971Y360610D02*
X317334Y360205D01*
X316580Y360639D01*
X316612Y361394D01*
X316700Y361547D01*
X318060Y360761D01*
X317971Y360610D01*
G37*
G36*
G01X309348Y395181D02*
X308589Y395530D01*
Y396431D01*
X309348Y396780D01*
X309524D01*
Y395181D01*
X309348D01*
G37*
G36*
G01X311991Y391450D02*
X311207Y391160D01*
X310570Y391797D01*
X310860Y392581D01*
X310984Y392705D01*
X312115Y391574D01*
X311991Y391450D01*
G37*
G36*
G01X321059Y360010D02*
X321729Y359660D01*
Y358791D01*
X321059Y358441D01*
X320884Y358440D01*
X320885Y360010D01*
X321059D01*
G37*
G36*
G01X317680Y373694D02*
X318350Y373344D01*
Y372474D01*
X317680Y372124D01*
X317505D01*
Y373694D01*
X317680D01*
G37*
G36*
G01X319159Y361801D02*
X319797Y362206D01*
X320550Y361772D01*
X320518Y361016D01*
X320431Y360864D01*
X319072Y361650D01*
X319159Y361801D01*
G37*
G36*
G01X317680Y369770D02*
X318350Y369420D01*
Y368550D01*
X317680Y368200D01*
X317505D01*
Y369770D01*
X317680D01*
G37*
G36*
G01Y365919D02*
X318350Y365569D01*
Y364699D01*
X317680Y364349D01*
X317505D01*
Y365919D01*
X317680D01*
G37*
G36*
G01Y385419D02*
X318350Y385069D01*
Y384199D01*
X317680Y383849D01*
X317505D01*
Y385419D01*
X317680D01*
G37*
G36*
G01Y381519D02*
X318350Y381169D01*
Y380299D01*
X317680Y379949D01*
X317505D01*
Y381519D01*
X317680D01*
G37*
G36*
G01Y377619D02*
X318350Y377269D01*
Y376399D01*
X317680Y376049D01*
X317505D01*
Y377619D01*
X317680D01*
G37*
G36*
G01Y389283D02*
X318350Y388933D01*
Y388063D01*
X317680Y387713D01*
X317506Y387712D01*
X317505Y389283D01*
X317680D01*
G37*
G36*
G01X310450Y396780D02*
X311210Y396430D01*
Y395531D01*
X310450Y395181D01*
X310275Y395180D01*
Y396781D01*
X310450Y396780D01*
G37*
G36*
G01X311639Y393360D02*
X312424Y393650D01*
X313060Y393014D01*
X312770Y392229D01*
X312647Y392105D01*
X311515Y393237D01*
X311639Y393360D01*
G37*
G36*
G01X315759Y391063D02*
X316397Y391468D01*
X317150Y391033D01*
X317118Y390278D01*
X317032Y390127D01*
X315671Y390911D01*
X315759Y391063D01*
G37*
G36*
G01X329577Y370209D02*
X328907Y370559D01*
Y371428D01*
X329576Y371778D01*
X329752Y371779D01*
X329751Y370209D01*
X329577D01*
G37*
G36*
G01X331477Y368418D02*
X330839Y368013D01*
X330086Y368447D01*
X330118Y369202D01*
X330205Y369355D01*
X331564Y368569D01*
X331477Y368418D01*
G37*
G36*
G01X332956Y364349D02*
X332286Y364699D01*
Y365569D01*
X332956Y365919D01*
X333131D01*
Y364349D01*
X332956D01*
G37*
G36*
G01X329805Y381504D02*
X329045Y381854D01*
Y382754D01*
X329805Y383104D01*
X329980D01*
Y381504D01*
X329805D01*
G37*
G36*
G01Y385404D02*
X329045Y385754D01*
Y386654D01*
X329805Y387004D01*
X329980D01*
Y385404D01*
X329805D01*
G37*
G36*
G01X329576Y374050D02*
X328906Y374400D01*
Y375270D01*
X329576Y375620D01*
X329751D01*
Y374050D01*
X329576D01*
G37*
G36*
G01X329805Y389304D02*
X329045Y389654D01*
Y390554D01*
X329805Y390904D01*
X329980D01*
Y389304D01*
X329805D01*
G37*
G36*
G01X326855Y401630D02*
X326095Y401980D01*
Y402880D01*
X326855Y403230D01*
X327030D01*
Y401630D01*
X326855D01*
G37*
G36*
G01X329031Y396919D02*
X328247Y396629D01*
X327610Y397265D01*
X327900Y398050D01*
X328024Y398174D01*
X329155Y397043D01*
X329031Y396919D01*
G37*
G36*
G01X329805Y393204D02*
X329045Y393554D01*
Y394454D01*
X329805Y394804D01*
X329980D01*
Y393204D01*
X329805D01*
G37*
G36*
G01X330345Y354630D02*
X329674Y354978D01*
X329672Y355848D01*
X330341Y356200D01*
X330517Y356199D01*
X330520Y354630D01*
X330345D01*
G37*
G36*
G01X331200Y373694D02*
X331870Y373344D01*
Y372474D01*
X331200Y372124D01*
X331025D01*
Y373694D01*
X331200D01*
G37*
G36*
G01X332686Y369597D02*
X333324Y370002D01*
X334077Y369567D01*
X334046Y368812D01*
X333958Y368660D01*
X332598Y369446D01*
X332686Y369597D01*
G37*
G36*
G01X334579Y367802D02*
X335249Y367452D01*
Y366582D01*
X334579Y366232D01*
X334404D01*
Y367803D01*
X334579Y367802D01*
G37*
G36*
G01X334580Y363920D02*
X335250Y363570D01*
Y362700D01*
X334580Y362350D01*
X334405D01*
Y363920D01*
X334580D01*
G37*
G36*
G01X330903Y387004D02*
X331663Y386654D01*
Y385754D01*
X330903Y385404D01*
X330728D01*
Y387004D01*
X330903D01*
G37*
G36*
G01Y383104D02*
X331663Y382754D01*
Y381854D01*
X330903Y381504D01*
X330728D01*
Y383104D01*
X330903D01*
G37*
G36*
G01X331200Y377619D02*
X331870Y377269D01*
Y376399D01*
X331200Y376049D01*
X331025D01*
Y377619D01*
X331200D01*
G37*
G36*
G01X330903Y390904D02*
X331663Y390554D01*
Y389654D01*
X330903Y389304D01*
X330728D01*
Y390904D01*
X330903D01*
G37*
G36*
G01X327953Y403230D02*
X328713Y402880D01*
Y401980D01*
X327953Y401630D01*
X327778D01*
Y403230D01*
X327953D01*
G37*
G36*
G01X328676Y398827D02*
X329461Y399117D01*
X330098Y398480D01*
X329808Y397695D01*
X329684Y397572D01*
X328553Y398703D01*
X328676Y398827D01*
G37*
G36*
G01X330903Y394804D02*
X331663Y394454D01*
Y393554D01*
X330903Y393204D01*
X330728D01*
Y394804D01*
X330903D01*
G37*
G36*
G01X322206Y403228D02*
X321446Y403578D01*
Y404478D01*
X322206Y404828D01*
X322381D01*
Y403228D01*
X322206D01*
G37*
G36*
G01X323306Y404828D02*
X324066Y404478D01*
Y403578D01*
X323306Y403228D01*
X323131D01*
Y404828D01*
X323306D01*
G37*
G36*
G01X331873Y402819D02*
X331113Y403169D01*
Y404069D01*
X331873Y404419D01*
X332048D01*
Y402819D01*
X331873D01*
G37*
G36*
G01X332971Y404419D02*
X333731Y404069D01*
Y403169D01*
X332971Y402819D01*
X332796D01*
Y404419D01*
X332971D01*
G37*
G36*
G01X431580Y208141D02*
X431291Y208926D01*
X431927Y209562D01*
X432712Y209272D01*
X432836Y209149D01*
X431704Y208017D01*
X431580Y208141D01*
G37*
G36*
G01X433611Y215412D02*
X432941Y215762D01*
Y216632D01*
X433611Y216982D01*
X433786D01*
Y215412D01*
X433611D01*
G37*
G36*
G01X433471Y210263D02*
X432711Y210613D01*
Y211513D01*
X433471Y211863D01*
X433646D01*
Y210263D01*
X433471D01*
G37*
G36*
G01X426301Y194960D02*
X425541Y195310D01*
Y196210D01*
X426301Y196560D01*
X426476D01*
Y194960D01*
X426301D01*
G37*
G36*
G01Y191060D02*
X425541Y191410D01*
Y192310D01*
X426301Y192660D01*
X426476D01*
Y191060D01*
X426301D01*
G37*
G36*
G01X428202Y200391D02*
X427912Y201176D01*
X428548Y201812D01*
X429333Y201522D01*
X429457Y201399D01*
X428325Y200267D01*
X428202Y200391D01*
G37*
G36*
G01X430694Y203877D02*
X429934Y204227D01*
Y205127D01*
X430694Y205477D01*
X430869D01*
Y203877D01*
X430694D01*
G37*
G36*
G01X434571Y211463D02*
X435331Y211113D01*
Y210213D01*
X434571Y209863D01*
X434396D01*
Y211463D01*
X434571D01*
G37*
G36*
G01X433490Y208494D02*
X433780Y207709D01*
X433143Y207073D01*
X432358Y207363D01*
X432235Y207487D01*
X433366Y208618D01*
X433490Y208494D01*
G37*
G36*
G01X435234Y215032D02*
X435904Y214682D01*
Y213812D01*
X435234Y213462D01*
X435059D01*
Y215032D01*
X435234D01*
G37*
G36*
G01X427401Y196560D02*
X428161Y196210D01*
Y195310D01*
X427401Y194960D01*
X427226D01*
Y196560D01*
X427401D01*
G37*
G36*
G01Y192660D02*
X428161Y192310D01*
Y191410D01*
X427401Y191060D01*
X427226D01*
Y192660D01*
X427401D01*
G37*
G36*
G01X429811Y200444D02*
X430101Y199660D01*
X429464Y199023D01*
X428680Y199313D01*
X428556Y199437D01*
X429687Y200568D01*
X429811Y200444D01*
G37*
G36*
G01X431794Y205477D02*
X432554Y205127D01*
Y204227D01*
X431794Y203877D01*
X431619D01*
Y205477D01*
X431794D01*
G37*
G36*
G01X447133Y209539D02*
X446373Y209889D01*
Y210789D01*
X447133Y211139D01*
X447308D01*
Y209539D01*
X447133D01*
G37*
G36*
G01Y213439D02*
X446373Y213789D01*
Y214689D01*
X447133Y215039D01*
X447308D01*
Y213439D01*
X447133D01*
G37*
G36*
G01X438843Y189914D02*
X438083Y190264D01*
Y191164D01*
X438843Y191514D01*
X439018D01*
Y189914D01*
X438843D01*
G37*
G36*
G01X440892Y194538D02*
X440602Y195323D01*
X441238Y195959D01*
X442023Y195669D01*
X442147Y195546D01*
X441015Y194414D01*
X440892Y194538D01*
G37*
G36*
G01X443782Y197582D02*
X443022Y197932D01*
Y198832D01*
X443782Y199182D01*
X443957D01*
Y197582D01*
X443782D01*
G37*
G36*
G01X445287Y203458D02*
X444997Y204242D01*
X445634Y204879D01*
X446418Y204589D01*
X446542Y204465D01*
X445411Y203334D01*
X445287Y203458D01*
G37*
G36*
G01X448755Y218907D02*
X449425Y218557D01*
Y217687D01*
X448755Y217337D01*
X448580D01*
Y218907D01*
X448755D01*
G37*
G36*
G01X448233Y215039D02*
X448993Y214689D01*
Y213789D01*
X448233Y213439D01*
X448058D01*
Y215039D01*
X448233D01*
G37*
G36*
G01Y211139D02*
X448993Y210789D01*
Y209889D01*
X448233Y209539D01*
X448058D01*
Y211139D01*
X448233D01*
G37*
G36*
G01X447205Y203817D02*
X447495Y203033D01*
X446858Y202396D01*
X446074Y202686D01*
X445950Y202810D01*
X447081Y203941D01*
X447205Y203817D01*
G37*
G36*
G01X439943Y191514D02*
X440703Y191164D01*
Y190264D01*
X439943Y189914D01*
X439768D01*
Y191514D01*
X439943D01*
G37*
G36*
G01X442801Y194891D02*
X443091Y194107D01*
X442454Y193470D01*
X441670Y193760D01*
X441546Y193884D01*
X442677Y195015D01*
X442801Y194891D01*
G37*
G36*
G01X444882Y199682D02*
X445642Y199332D01*
Y198432D01*
X444882Y198082D01*
X444707D01*
Y199682D01*
X444882D01*
G37*
G36*
G01X430231Y217319D02*
X429561Y217669D01*
Y218539D01*
X430231Y218889D01*
X430406D01*
Y217319D01*
X430231D01*
G37*
G36*
G01X428316Y208907D02*
X428027Y209692D01*
X428663Y210328D01*
X429448Y210038D01*
X429572Y209915D01*
X428440Y208783D01*
X428316Y208907D01*
G37*
G36*
G01X430231Y213419D02*
X429561Y213769D01*
Y214639D01*
X430231Y214989D01*
X430406D01*
Y213419D01*
X430231D01*
G37*
G36*
G01X423351Y193425D02*
X422591Y193775D01*
Y194675D01*
X423351Y195025D01*
X423526D01*
Y193425D01*
X423351D01*
G37*
G36*
G01Y189525D02*
X422591Y189875D01*
Y190775D01*
X423351Y191125D01*
X423526D01*
Y189525D01*
X423351D01*
G37*
G36*
G01Y197325D02*
X422591Y197675D01*
Y198575D01*
X423351Y198925D01*
X423526D01*
Y197325D01*
X423351D01*
G37*
G36*
G01X425303Y201523D02*
X425013Y202308D01*
X425649Y202944D01*
X426434Y202654D01*
X426558Y202531D01*
X425426Y201399D01*
X425303Y201523D01*
G37*
G36*
G01X430226Y209260D02*
X430516Y208475D01*
X429879Y207839D01*
X429094Y208129D01*
X428971Y208253D01*
X430102Y209384D01*
X430226Y209260D01*
G37*
G36*
G01X431856Y217017D02*
X432526Y216667D01*
Y215797D01*
X431856Y215447D01*
X431681D01*
Y217017D01*
X431856D01*
G37*
G36*
G01X428944Y206977D02*
X429704Y206627D01*
Y205727D01*
X428944Y205377D01*
X428769D01*
Y206977D01*
X428944D01*
G37*
G36*
G01X424451Y195025D02*
X425211Y194675D01*
Y193775D01*
X424451Y193425D01*
X424276D01*
Y195025D01*
X424451D01*
G37*
G36*
G01Y191125D02*
X425211Y190775D01*
Y189875D01*
X424451Y189525D01*
X424276D01*
Y191125D01*
X424451D01*
G37*
G36*
G01Y198925D02*
X425211Y198575D01*
Y197675D01*
X424451Y197325D01*
X424276D01*
Y198925D01*
X424451D01*
G37*
G36*
G01X426912Y201576D02*
X427202Y200792D01*
X426565Y200155D01*
X425781Y200445D01*
X425657Y200569D01*
X426788Y201700D01*
X426912Y201576D01*
G37*
G36*
G01X444274Y213473D02*
X443514Y213823D01*
Y214723D01*
X444274Y215073D01*
X444449D01*
Y213473D01*
X444274D01*
G37*
G36*
G01Y209573D02*
X443514Y209923D01*
Y210823D01*
X444274Y211173D01*
X444449D01*
Y209573D01*
X444274D01*
G37*
G36*
G01X442465Y206878D02*
X442175Y207662D01*
X442812Y208299D01*
X443596Y208009D01*
X443720Y207885D01*
X442589Y206754D01*
X442465Y206878D01*
G37*
G36*
G01X439707Y204120D02*
X439417Y204904D01*
X440054Y205541D01*
X440838Y205251D01*
X440962Y205127D01*
X439831Y203996D01*
X439707Y204120D01*
G37*
G36*
G01X435585Y190354D02*
X434825Y190704D01*
Y191604D01*
X435585Y191954D01*
X435760D01*
Y190354D01*
X435585D01*
G37*
G36*
G01X437118Y194796D02*
X436828Y195580D01*
X437465Y196217D01*
X438249Y195927D01*
X438373Y195803D01*
X437242Y194672D01*
X437118Y194796D01*
G37*
G36*
G01X439243Y199106D02*
X438483Y199456D01*
Y200356D01*
X439243Y200706D01*
X439418D01*
Y199106D01*
X439243D01*
G37*
G36*
G01X443372Y206223D02*
X443662Y205438D01*
X443026Y204802D01*
X442241Y205092D01*
X442117Y205215D01*
X443249Y206347D01*
X443372Y206223D01*
G37*
G36*
G01X445374Y212573D02*
X446134Y212223D01*
Y211323D01*
X445374Y210973D01*
X445199D01*
Y212573D01*
X445374D01*
G37*
G36*
G01X436685Y191954D02*
X437445Y191604D01*
Y190704D01*
X436685Y190354D01*
X436510D01*
Y191954D01*
X436685D01*
G37*
G36*
G01X439027Y195149D02*
X439317Y194364D01*
X438681Y193728D01*
X437896Y194018D01*
X437772Y194141D01*
X438904Y195273D01*
X439027Y195149D01*
G37*
G36*
G01X440343Y202606D02*
X441103Y202256D01*
Y201356D01*
X440343Y201006D01*
X440168D01*
Y202606D01*
X440343D01*
G37*
G36*
G01X445374Y216473D02*
X446134Y216123D01*
Y215223D01*
X445374Y214873D01*
X445199D01*
Y216473D01*
X445374D01*
G37*
G36*
G01X454097Y205076D02*
X453337Y205426D01*
Y206326D01*
X454097Y206676D01*
X454272D01*
Y205076D01*
X454097D01*
G37*
G36*
G01Y208976D02*
X453337Y209326D01*
Y210226D01*
X454097Y210576D01*
X454272D01*
Y208976D01*
X454097D01*
G37*
G36*
G01X453891Y215436D02*
X453221Y215786D01*
Y216656D01*
X453891Y217006D01*
X454066D01*
Y215436D01*
X453891D01*
G37*
G36*
G01X452923Y194309D02*
X452163Y194659D01*
Y195559D01*
X452923Y195909D01*
X453098D01*
Y194309D01*
X452923D01*
G37*
G36*
G01Y190409D02*
X452163Y190759D01*
Y191659D01*
X452923Y192009D01*
X453098D01*
Y190409D01*
X452923D01*
G37*
G36*
G01X453219Y200688D02*
X452459Y201038D01*
Y201938D01*
X453219Y202288D01*
X453394D01*
Y200688D01*
X453219D01*
G37*
G36*
G01X455197Y206676D02*
X455957Y206326D01*
Y205426D01*
X455197Y205076D01*
X455022D01*
Y206676D01*
X455197D01*
G37*
G36*
G01Y210576D02*
X455957Y210226D01*
Y209326D01*
X455197Y208976D01*
X455022D01*
Y210576D01*
X455197D01*
G37*
G36*
G01X455515Y215007D02*
X456185Y214657D01*
Y213787D01*
X455515Y213437D01*
X455340D01*
Y215007D01*
X455515D01*
G37*
G36*
G01X454023Y195909D02*
X454783Y195559D01*
Y194659D01*
X454023Y194309D01*
X453848D01*
Y195909D01*
X454023D01*
G37*
G36*
G01Y192009D02*
X454783Y191659D01*
Y190759D01*
X454023Y190409D01*
X453848D01*
Y192009D01*
X454023D01*
G37*
G36*
G01X454319Y202288D02*
X455079Y201938D01*
Y201038D01*
X454319Y200688D01*
X454144D01*
Y202288D01*
X454319D01*
G37*
G36*
G01X467369Y213515D02*
X466609Y213865D01*
Y214765D01*
X467369Y215115D01*
X467544D01*
Y213515D01*
X467369D01*
G37*
G36*
G01X468023Y208244D02*
X467263Y208594D01*
Y209494D01*
X468023Y209844D01*
X468198D01*
Y208244D01*
X468023D01*
G37*
G36*
G01Y203844D02*
X467263Y204194D01*
Y205094D01*
X468023Y205444D01*
X468198D01*
Y203844D01*
X468023D01*
G37*
G36*
G01X469468Y201849D02*
X468684Y201559D01*
X468047Y202196D01*
X468337Y202980D01*
X468461Y203104D01*
X469592Y201973D01*
X469468Y201849D01*
G37*
G36*
G01X471298Y195793D02*
X470514Y195503D01*
X469877Y196140D01*
X470167Y196924D01*
X470291Y197048D01*
X471422Y195917D01*
X471298Y195793D01*
G37*
G36*
G01X469680Y198797D02*
X468920Y199147D01*
Y200047D01*
X469680Y200397D01*
X469855D01*
Y198797D01*
X469680D01*
G37*
G36*
G01X468469Y215115D02*
X469229Y214765D01*
Y213865D01*
X468469Y213515D01*
X468294D01*
Y215115D01*
X468469D01*
G37*
G36*
G01X469123Y209844D02*
X469883Y209494D01*
Y208594D01*
X469123Y208244D01*
X468948D01*
Y209844D01*
X469123D01*
G37*
G36*
G01Y205944D02*
X469883Y205594D01*
Y204694D01*
X469123Y204344D01*
X468948D01*
Y205944D01*
X469123D01*
G37*
G36*
G01X469035Y218907D02*
X469705Y218557D01*
Y217687D01*
X469035Y217337D01*
X468860D01*
Y218907D01*
X469035D01*
G37*
G36*
G01X471070Y197579D02*
X471854Y197869D01*
X472491Y197232D01*
X472201Y196448D01*
X472077Y196324D01*
X470946Y197455D01*
X471070Y197579D01*
G37*
G36*
G01X470780Y201397D02*
X471540Y201047D01*
Y200147D01*
X470780Y199797D01*
X470605D01*
Y201397D01*
X470780D01*
G37*
G36*
G01X450511Y217337D02*
X449841Y217687D01*
Y218557D01*
X450511Y218907D01*
X450686D01*
Y217337D01*
X450511D01*
G37*
G36*
G01X451077Y205598D02*
X450317Y205948D01*
Y206848D01*
X451077Y207198D01*
X451252D01*
Y205598D01*
X451077D01*
G37*
G36*
G01Y209498D02*
X450317Y209848D01*
Y210748D01*
X451077Y211098D01*
X451252D01*
Y209498D01*
X451077D01*
G37*
G36*
G01X450511Y213437D02*
X449841Y213787D01*
Y214657D01*
X450511Y215007D01*
X450686D01*
Y213437D01*
X450511D01*
G37*
G36*
G01X448255Y195940D02*
X447965Y196725D01*
X448601Y197361D01*
X449386Y197071D01*
X449510Y196948D01*
X448378Y195816D01*
X448255Y195940D01*
G37*
G36*
G01X449601Y198941D02*
X448841Y199291D01*
Y200191D01*
X449601Y200541D01*
X449776D01*
Y198941D01*
X449601D01*
G37*
G36*
G01X450371Y202181D02*
X449611Y202531D01*
Y203431D01*
X450371Y203781D01*
X450546D01*
Y202181D01*
X450371D01*
G37*
G36*
G01X452177Y207198D02*
X452937Y206848D01*
Y205948D01*
X452177Y205598D01*
X452002D01*
Y207198D01*
X452177D01*
G37*
G36*
G01Y211098D02*
X452937Y210748D01*
Y209848D01*
X452177Y209498D01*
X452002D01*
Y211098D01*
X452177D01*
G37*
G36*
G01X452135Y217006D02*
X452805Y216656D01*
Y215786D01*
X452135Y215436D01*
X451960D01*
Y217006D01*
X452135D01*
G37*
G36*
G01X450405Y196533D02*
X450695Y195748D01*
X450059Y195112D01*
X449274Y195402D01*
X449150Y195525D01*
X450282Y196657D01*
X450405Y196533D01*
G37*
G36*
G01X451471Y203781D02*
X452231Y203431D01*
Y202531D01*
X451471Y202181D01*
X451296D01*
Y203781D01*
X451471D01*
G37*
G36*
G01X450701Y199541D02*
X451461Y199191D01*
Y198291D01*
X450701Y197941D01*
X450526D01*
Y199541D01*
X450701D01*
G37*
G36*
G01X464032Y207455D02*
X463272Y207805D01*
Y208705D01*
X464032Y209055D01*
X464207D01*
Y207455D01*
X464032D01*
G37*
G36*
G01Y203955D02*
X463272Y204305D01*
Y205205D01*
X464032Y205555D01*
X464207D01*
Y203955D01*
X464032D01*
G37*
G36*
G01X464554Y212615D02*
X463794Y212965D01*
Y213865D01*
X464554Y214215D01*
X464729D01*
Y212615D01*
X464554D01*
G37*
G36*
G01X466660Y197042D02*
X465900Y197392D01*
Y198292D01*
X466660Y198642D01*
X466835D01*
Y197042D01*
X466660D01*
G37*
G36*
G01Y193142D02*
X465900Y193492D01*
Y194392D01*
X466660Y194742D01*
X466835D01*
Y193142D01*
X466660D01*
G37*
G36*
G01X465819Y201196D02*
X465034Y200906D01*
X464397Y201542D01*
X464687Y202327D01*
X464811Y202451D01*
X465942Y201320D01*
X465819Y201196D01*
G37*
G36*
G01X465133Y209055D02*
X465893Y208705D01*
Y207805D01*
X465133Y207455D01*
X464958D01*
Y209055D01*
X465133D01*
G37*
G36*
G01X465655Y213415D02*
X466415Y213065D01*
Y212165D01*
X465655Y211815D01*
X465480D01*
Y213415D01*
X465655D01*
G37*
G36*
G01X467760Y198642D02*
X468520Y198292D01*
Y197392D01*
X467760Y197042D01*
X467585D01*
Y198642D01*
X467760D01*
G37*
G36*
G01Y194742D02*
X468520Y194392D01*
Y193492D01*
X467760Y193142D01*
X467585D01*
Y194742D01*
X467760D01*
G37*
G36*
G01X465469Y203134D02*
X466253Y203424D01*
X466890Y202787D01*
X466600Y202003D01*
X466476Y201879D01*
X465345Y203010D01*
X465469Y203134D01*
G37*
G36*
G01X477540Y206045D02*
X476780Y206395D01*
Y207295D01*
X477540Y207645D01*
X477715D01*
Y206045D01*
X477540D01*
G37*
G36*
G01X476668Y208690D02*
X475884Y208400D01*
X475247Y209037D01*
X475537Y209821D01*
X475661Y209945D01*
X476792Y208814D01*
X476668Y208690D01*
G37*
G36*
G01X474170Y215436D02*
X473500Y215786D01*
Y216656D01*
X474170Y217006D01*
X474345D01*
Y215436D01*
X474170D01*
G37*
G36*
G01X476612Y210303D02*
X477396Y210593D01*
X478033Y209956D01*
X477743Y209172D01*
X477619Y209048D01*
X476488Y210179D01*
X476612Y210303D01*
G37*
G36*
G01X475794Y215007D02*
X476464Y214657D01*
Y213787D01*
X475794Y213437D01*
X475619D01*
Y215007D01*
X475794D01*
G37*
G36*
G01X470790Y213437D02*
X470120Y213787D01*
Y214657D01*
X470790Y215007D01*
X470965D01*
Y213437D01*
X470790D01*
G37*
G36*
G01Y217337D02*
X470120Y217687D01*
Y218557D01*
X470790Y218907D01*
X470965D01*
Y217337D01*
X470790D01*
G37*
G36*
G01X473788Y207613D02*
X473003Y207323D01*
X472367Y207959D01*
X472657Y208744D01*
X472780Y208868D01*
X473912Y207736D01*
X473788Y207613D01*
G37*
G36*
G01X474686Y204500D02*
X473926Y204850D01*
Y205750D01*
X474686Y206100D01*
X474861D01*
Y204500D01*
X474686D01*
G37*
G36*
G01X476340Y201942D02*
X475555Y201652D01*
X474919Y202288D01*
X475209Y203073D01*
X475332Y203197D01*
X476464Y202065D01*
X476340Y201942D01*
G37*
G36*
G01X476987Y202851D02*
X477771Y203141D01*
X478408Y202504D01*
X478118Y201720D01*
X477994Y201596D01*
X476863Y202727D01*
X476987Y202851D01*
G37*
G36*
G01X472414Y217006D02*
X473084Y216656D01*
Y215786D01*
X472414Y215436D01*
X472239D01*
Y217006D01*
X472414D01*
G37*
G36*
G01X473435Y209522D02*
X474219Y209812D01*
X474856Y209175D01*
X474566Y208391D01*
X474442Y208267D01*
X473311Y209398D01*
X473435Y209522D01*
G37*
G36*
G01X475786Y206100D02*
X476546Y205750D01*
Y204850D01*
X475786Y204500D01*
X475611D01*
Y206100D01*
X475786D01*
G37*
G36*
G01X436614Y207559D02*
X436904Y206774D01*
X436268Y206138D01*
X435483Y206428D01*
X435359Y206551D01*
X436491Y207683D01*
X436614Y207559D01*
G37*
G36*
G01X438614Y213082D02*
X439284Y212732D01*
Y211862D01*
X438614Y211512D01*
X438439D01*
Y213082D01*
X438614D01*
G37*
G36*
G01X430477Y196156D02*
X431237Y195806D01*
Y194906D01*
X430477Y194556D01*
X430302D01*
Y196156D01*
X430477D01*
G37*
G36*
G01Y192256D02*
X431237Y191906D01*
Y191006D01*
X430477Y190656D01*
X430302D01*
Y192256D01*
X430477D01*
G37*
G36*
G01X434644Y203977D02*
X435404Y203627D01*
Y202727D01*
X434644Y202377D01*
X434469D01*
Y203977D01*
X434644D01*
G37*
G36*
G01X432856Y199459D02*
X433146Y198674D01*
X432510Y198038D01*
X431725Y198328D01*
X431601Y198451D01*
X432733Y199583D01*
X432856Y199459D01*
G37*
G36*
G01X458913Y208582D02*
X459673Y208232D01*
Y207332D01*
X458913Y206982D01*
X458738D01*
Y208582D01*
X458913D01*
G37*
G36*
G01Y212482D02*
X459673Y212132D01*
Y211232D01*
X458913Y210882D01*
X458738D01*
Y212482D01*
X458913D01*
G37*
G36*
G01X458522Y192811D02*
X459282Y192461D01*
Y191561D01*
X458522Y191211D01*
X458347D01*
Y192811D01*
X458522D01*
G37*
G36*
G01Y196711D02*
X459282Y196361D01*
Y195461D01*
X458522Y195111D01*
X458347D01*
Y196711D01*
X458522D01*
G37*
G36*
G01X458689Y203422D02*
X458979Y202637D01*
X458343Y202001D01*
X457558Y202291D01*
X457434Y202414D01*
X458566Y203546D01*
X458689Y203422D01*
G37*
G36*
G01X440923Y211456D02*
X440163Y211806D01*
Y212706D01*
X440923Y213056D01*
X441098D01*
Y211456D01*
X440923D01*
G37*
G36*
G01X438844Y207285D02*
X438554Y208069D01*
X439191Y208706D01*
X439975Y208416D01*
X440099Y208292D01*
X438968Y207161D01*
X438844Y207285D01*
G37*
G36*
G01X434170Y195877D02*
X433880Y196662D01*
X434516Y197298D01*
X435301Y197008D01*
X435425Y196885D01*
X434293Y195753D01*
X434170Y195877D01*
G37*
G36*
G01X432537Y190939D02*
X431777Y191289D01*
Y192189D01*
X432537Y192539D01*
X432712D01*
Y190939D01*
X432537D01*
G37*
G36*
G01X436394Y200595D02*
X435634Y200945D01*
Y201845D01*
X436394Y202195D01*
X436569D01*
Y200595D01*
X436394D01*
G37*
G36*
G01X461012Y206635D02*
X460252Y206985D01*
Y207885D01*
X461012Y208235D01*
X461187D01*
Y206635D01*
X461012D01*
G37*
G36*
G01Y210535D02*
X460252Y210885D01*
Y211785D01*
X461012Y212135D01*
X461187D01*
Y210535D01*
X461012D01*
G37*
G36*
G01X460651Y215412D02*
X459981Y215762D01*
Y216632D01*
X460651Y216982D01*
X460826D01*
Y215412D01*
X460651D01*
G37*
G36*
G01X462353Y192353D02*
X461593Y192703D01*
Y193603D01*
X462353Y193953D01*
X462528D01*
Y192353D01*
X462353D01*
G37*
G36*
G01X461012Y202735D02*
X460252Y203085D01*
Y203985D01*
X461012Y204335D01*
X461187D01*
Y202735D01*
X461012D01*
G37*
G36*
G01X434705Y207206D02*
X434415Y207990D01*
X435052Y208627D01*
X435836Y208337D01*
X435960Y208213D01*
X434829Y207082D01*
X434705Y207206D01*
G37*
G36*
G01X436991Y213437D02*
X436321Y213787D01*
Y214657D01*
X436991Y215007D01*
X437166D01*
Y213437D01*
X436991D01*
G37*
G36*
G01X429379Y194556D02*
X428619Y194906D01*
Y195806D01*
X429379Y196156D01*
X429554D01*
Y194556D01*
X429379D01*
G37*
G36*
G01Y190656D02*
X428619Y191006D01*
Y191906D01*
X429379Y192256D01*
X429554D01*
Y190656D01*
X429379D01*
G37*
G36*
G01X430947Y199106D02*
X430657Y199890D01*
X431294Y200527D01*
X432078Y200237D01*
X432202Y200113D01*
X431071Y198982D01*
X430947Y199106D01*
G37*
G36*
G01X433544Y202377D02*
X432784Y202727D01*
Y203627D01*
X433544Y203977D01*
X433719D01*
Y202377D01*
X433544D01*
G37*
G36*
G01X457813Y205482D02*
X457053Y205832D01*
Y206732D01*
X457813Y207082D01*
X457988D01*
Y205482D01*
X457813D01*
G37*
G36*
G01Y208882D02*
X457053Y209232D01*
Y210132D01*
X457813Y210482D01*
X457988D01*
Y208882D01*
X457813D01*
G37*
G36*
G01X457271Y213437D02*
X456601Y213787D01*
Y214657D01*
X457271Y215007D01*
X457446D01*
Y213437D01*
X457271D01*
G37*
G36*
G01X457422Y191211D02*
X456662Y191561D01*
Y192461D01*
X457422Y192811D01*
X457597D01*
Y191211D01*
X457422D01*
G37*
G36*
G01Y195111D02*
X456662Y195461D01*
Y196361D01*
X457422Y196711D01*
X457597D01*
Y195111D01*
X457422D01*
G37*
G36*
G01X456427Y202715D02*
X456137Y203500D01*
X456773Y204136D01*
X457558Y203846D01*
X457682Y203723D01*
X456550Y202591D01*
X456427Y202715D01*
G37*
G36*
G01X477550Y213437D02*
X476880Y213787D01*
Y214657D01*
X477550Y215007D01*
X477725D01*
Y213437D01*
X477550D01*
G37*
G36*
G01X441995Y218932D02*
X442665Y218582D01*
Y217712D01*
X441995Y217362D01*
X441820D01*
Y218932D01*
X441995D01*
G37*
G36*
G01X442023Y213056D02*
X442783Y212706D01*
Y211806D01*
X442023Y211456D01*
X441848D01*
Y213056D01*
X442023D01*
G37*
G36*
G01X440753Y207638D02*
X441043Y206853D01*
X440407Y206217D01*
X439622Y206507D01*
X439498Y206630D01*
X440630Y207762D01*
X440753Y207638D01*
G37*
G36*
G01X433635Y192539D02*
X434395Y192189D01*
Y191289D01*
X433635Y190939D01*
X433460D01*
Y192539D01*
X433635D01*
G37*
G36*
G01X436079Y196230D02*
X436369Y195446D01*
X435732Y194809D01*
X434948Y195099D01*
X434824Y195223D01*
X435955Y196354D01*
X436079Y196230D01*
G37*
G36*
G01X437494Y202195D02*
X438254Y201845D01*
Y200945D01*
X437494Y200595D01*
X437319D01*
Y202195D01*
X437494D01*
G37*
G36*
G01X462275Y218932D02*
X462945Y218582D01*
Y217712D01*
X462275Y217362D01*
X462100D01*
Y218932D01*
X462275D01*
G37*
G36*
G01X462112Y208235D02*
X462872Y207885D01*
Y206985D01*
X462112Y206635D01*
X461937D01*
Y208235D01*
X462112D01*
G37*
G36*
G01Y212135D02*
X462872Y211785D01*
Y210885D01*
X462112Y210535D01*
X461937D01*
Y212135D01*
X462112D01*
G37*
G36*
G01Y204335D02*
X462872Y203985D01*
Y203085D01*
X462112Y202735D01*
X461937D01*
Y204335D01*
X462112D01*
G37*
G36*
G01X463453Y193953D02*
X464213Y193603D01*
Y192703D01*
X463453Y192353D01*
X463278D01*
Y193953D01*
X463453D01*
G37*
G36*
G01X436100Y222471D02*
X436799Y222759D01*
X437465Y222200D01*
X437303Y221461D01*
X437190Y221327D01*
X435988Y222337D01*
X436100Y222471D01*
G37*
G36*
G01X447131Y219336D02*
X446461Y219686D01*
Y220556D01*
X447131Y220906D01*
X447306D01*
Y219336D01*
X447131D01*
G37*
G36*
G01X448755Y222807D02*
X449425Y222457D01*
Y221587D01*
X448755Y221237D01*
X448580D01*
Y222807D01*
X448755D01*
G37*
G36*
G01X444460Y225075D02*
X445181Y224847D01*
X445332Y223990D01*
X444733Y223529D01*
X444560Y223499D01*
X444288Y225045D01*
X444460Y225075D01*
G37*
G36*
G01X445375Y220882D02*
X446045Y220532D01*
Y219662D01*
X445375Y219312D01*
X445200D01*
Y220882D01*
X445375D01*
G37*
G36*
G01X456614Y222218D02*
X457313Y222506D01*
X457979Y221947D01*
X457816Y221209D01*
X457704Y221075D01*
X456501Y222084D01*
X456614Y222218D01*
G37*
G36*
G01X469035Y222807D02*
X469705Y222457D01*
Y221587D01*
X469035Y221237D01*
X468860D01*
Y222807D01*
X469035D01*
G37*
G36*
G01X464740Y225075D02*
X465461Y224847D01*
X465612Y223990D01*
X465013Y223529D01*
X464840Y223499D01*
X464568Y225045D01*
X464740Y225075D01*
G37*
G36*
G01X465655Y220882D02*
X466325Y220532D01*
Y219662D01*
X465655Y219312D01*
X465480D01*
Y220882D01*
X465655D01*
G37*
G36*
G01X477550Y221237D02*
X476880Y221587D01*
Y222457D01*
X477550Y222807D01*
X477725D01*
Y221237D01*
X477550D01*
G37*
G36*
G01X475218Y222220D02*
X475728Y221662D01*
X475430Y220844D01*
X474681Y220744D01*
X474517Y220804D01*
X475053Y222280D01*
X475218Y222220D01*
G37*
G36*
G01X440371Y219312D02*
X439701Y219662D01*
Y220532D01*
X440371Y220882D01*
X440546D01*
Y219312D01*
X440371D01*
G37*
G36*
G01X438924Y223415D02*
X438286Y223009D01*
X437533Y223444D01*
X437564Y224200D01*
X437652Y224351D01*
X439012Y223566D01*
X438924Y223415D01*
G37*
G36*
G01X460651Y219312D02*
X459981Y219662D01*
Y220532D01*
X460651Y220882D01*
X460826D01*
Y219312D01*
X460651D01*
G37*
G36*
G01X441994Y222789D02*
X442664Y222439D01*
Y221569D01*
X441994Y221219D01*
X441820D01*
X441819Y222790D01*
X441994Y222789D01*
G37*
G36*
G01X440101Y224584D02*
X440739Y224989D01*
X441492Y224554D01*
X441460Y223799D01*
X441374Y223648D01*
X440013Y224433D01*
X440101Y224584D01*
G37*
G36*
G01X462274Y222789D02*
X462944Y222439D01*
Y221569D01*
X462274Y221219D01*
X462100D01*
X462099Y222790D01*
X462274Y222789D01*
G37*
G36*
G01X500075Y208980D02*
G02X499692Y209495I0J400D01*
G03X497377Y210909I-1342J405D01*
G02X496816Y210914I-278J288D01*
G01X495986Y211744D01*
X496025Y211860D01*
G03X493929Y213472I-1333J436D01*
G01X493879Y213440D01*
X493710D01*
X493544Y213606D01*
Y214556D01*
G02X494110Y214920I400J0D01*
G03Y217472I582J1276D01*
G02X493544Y217836I-166J364D01*
G01Y218456D01*
G02X494110Y218820I400J0D01*
G03X494351Y221456I582J1276D01*
G01X494327Y221450D01*
X494000D01*
X493800Y221650D01*
Y221800D01*
X492220Y223380D01*
X492223Y223387D01*
X491223Y224387D01*
X491216Y224384D01*
X489950Y225650D01*
X489100D01*
X487006Y227744D01*
Y228450D01*
X487156Y228488D01*
G03X485753Y230766I-344J1359D01*
G02X485485Y230735I-151J131D01*
G03X484865Y231093I-2053J-2839D01*
G02X484758Y231341I82J182D01*
G03X482032Y231722I-1326J456D01*
G02X481633Y231300I-399J-22D01*
G01X478471D01*
G02X478072Y231722I0J400D01*
G03X475273Y231702I-1400J74D01*
G02X474874Y231275I-399J-27D01*
G01X471711D01*
G02X471312Y231702I0J400D01*
G03X468514I-1399J95D01*
G02X468115Y231275I-399J-27D01*
G01X464951D01*
G02X464552Y231702I0J400D01*
G03X461754I-1399J95D01*
G02X461355Y231275I-399J-27D01*
G01X458191D01*
G02X457792Y231702I0J400D01*
G03X454994I-1399J95D01*
G02X454595Y231275I-399J-27D01*
G01X451431D01*
G02X451032Y231702I0J400D01*
G03X448234I-1399J95D01*
G02X447835Y231275I-399J-27D01*
G01X444671D01*
G02X444272Y231702I0J400D01*
G03X441474I-1399J95D01*
G02X441075Y231275I-399J-27D01*
G01X437911D01*
G02X437512Y231702I0J400D01*
G03X434714I-1399J95D01*
G02X434315Y231275I-399J-27D01*
G01X431152D01*
G02X430753Y231702I0J400D01*
G03X428511Y232917I-1399J95D01*
G02X427870Y233236I-241J319D01*
G01Y234257D01*
G02X428511Y234576I400J0D01*
G03Y236816I843J1120D01*
G02X427870Y237135I-241J319D01*
G01Y238157D01*
G02X428511Y238476I400J0D01*
G03Y240716I843J1120D01*
G02X427870Y241035I-241J319D01*
G01Y242057D01*
G02X428511Y242376I400J0D01*
G03Y244616I843J1120D01*
G02X427870Y244935I-241J319D01*
G01Y245957D01*
G02X428511Y246276I400J0D01*
G03X429881Y248695I843J1120D01*
G02X429749Y249349I150J371D01*
G01X431200Y250800D01*
Y253500D01*
X432971Y255271D01*
G02X433638Y255101I283J-282D01*
G03X435379Y256842I1345J396D01*
G02X435209Y257509I112J384D01*
G01X440000Y262300D01*
X441700D01*
X442755Y263355D01*
X443624D01*
G03X444054Y262972I1128J833D01*
G02X444136Y262342I-200J-346D01*
G03X445821Y262562I987J-996D01*
G02X445739Y263192I200J346D01*
G03X445824Y263284I-986J997D01*
G01X445884Y263355D01*
X445895D01*
X446924Y264384D01*
X447169D01*
G02X447335Y264073I0J-200D01*
G03X449849Y262906I1168J-776D01*
G01X449891Y263050D01*
X450667D01*
X450828Y262888D01*
X452947D01*
X453108Y263050D01*
X454980D01*
X454997Y262868D01*
G03X456921Y264295I1396J128D01*
G02X456788Y264948I150J371D01*
G01X457684Y265844D01*
X458041D01*
G02X458425Y265334I0J-400D01*
G03X461121I1348J-387D01*
G02X461505Y265844I384J110D01*
G01X463386D01*
X468215Y261015D01*
Y258413D01*
G02X467530Y258132I-400J0D01*
G03Y256162I-997J-985D01*
G02X468215Y255881I285J-281D01*
G01Y254513D01*
G02X467530Y254232I-400J0D01*
G03Y252262I-997J-985D01*
G02X468215Y251981I285J-281D01*
G01Y250885D01*
X469691Y249409D01*
G02X469520Y248742I-283J-283D01*
G03X471259Y247003I393J-1346D01*
G02X471926Y247174I384J-112D01*
G01X472202Y246898D01*
G02X472224Y246356I-283J-283D01*
G03X474527Y246111I1068J-909D01*
G02X474879Y246700I352J189D01*
G01X475455D01*
G03X477889I1217J696D01*
G01X478465D01*
G02X478817Y246111I0J-400D01*
G03X481287I1235J-664D01*
G02X481639Y246700I352J189D01*
G01X482215D01*
G03X484649I1217J696D01*
G01X485225D01*
G02X485577Y246111I0J-400D01*
G03X488047I1235J-664D01*
G02X488399Y246700I352J189D01*
G01X490750D01*
X493399Y244051D01*
X493360Y243934D01*
G03X495130Y242164I1332J-438D01*
G01X495247Y242203D01*
X497450Y240000D01*
X498850D01*
X500775Y238075D01*
X502450D01*
X503686Y236839D01*
X503696Y236826D01*
G03X504011Y236511I1136J821D01*
G01X504024Y236501D01*
X504825Y235700D01*
X506150D01*
X508250Y233600D01*
X510188D01*
X510223Y233443D01*
G03X512639Y232813I1369J303D01*
G02X513220Y232830I299J-266D01*
G01X513500Y232550D01*
Y223000D01*
X514991Y221509D01*
X515002Y221448D01*
G03X516000Y219587I3350J599D01*
G01Y218400D01*
X517750Y216650D01*
X521940D01*
G02X522164Y216446I-209J-454D01*
G03X523650Y215073I2948J1700D01*
G01Y213700D01*
X524200Y213150D01*
Y211412D01*
G03X523763Y209959I911J-1066D01*
G01X523796Y209846D01*
X523313Y209363D01*
G02X522742Y209369I-283J283D01*
G03X520456Y208980I-1011J-972D01*
G01X519874D01*
G02X519536Y209594I0J400D01*
G03X517168I-1184J751D01*
G02X516830Y208980I-338J-214D01*
G01X516247D01*
G03X513697I-1275J-583D01*
G01X513113D01*
G02X512776Y209594I1J400D01*
G03X510408I-1184J752D01*
G02X510071Y208980I-338J-214D01*
G01X500075D01*
G37*
G36*
G01X473331Y273776D02*
X469781Y277326D01*
X467569D01*
X465842Y275600D01*
X460157D01*
G02X459767Y276089I0J400D01*
G03X459398Y277385I-1367J311D01*
G02X459399Y277949I284J281D01*
G03X457410Y277955I-992J991D01*
G02X457409Y277391I-284J-281D01*
G03X457033Y276089I991J-991D01*
G02X456643Y275600I-390J-89D01*
G01X454800D01*
X453976Y274776D01*
X447054D01*
X444740Y277090D01*
Y291149D01*
G02X445354Y291488I400J1D01*
G03X447385Y291754I856J1354D01*
G02X447972Y291753I293J-272D01*
G03X449695Y291335I1176J1088D01*
G02X450200Y291115I137J-376D01*
G03X452999Y290837I1475J624D01*
G02X453622Y290884I330J-225D01*
G03X454094Y290552I1026J957D01*
G03X455207Y293288I1132J1134D01*
G02X454802Y293687I-5J400D01*
G03X454796Y293819I-1402J2D01*
G02X455139Y294254I398J39D01*
G03X453532Y296638I-217J1587D01*
G02X453204Y296762I-37J398D01*
G03X453031Y296948I-1110J-859D01*
G03X450615Y296965I-1215J-1044D01*
G02X450045Y296935I-300J265D01*
G03X448124Y296917I-951J-1031D01*
G02X447555Y296933I-277J289D01*
G03X445486Y297168I-1172J-1092D01*
G03X445326Y297078I606J-1265D01*
G02X444740Y297432I-186J354D01*
G01Y310210D01*
X453765Y319235D01*
Y326601D01*
X463650Y336486D01*
X465266Y338103D01*
X465476Y338313D01*
Y339713D01*
X465943Y340179D01*
G02X466531Y340153I282J-283D01*
G03X469019Y341317I1122J843D01*
G02X469414Y341770I396J53D01*
G01X470266D01*
X470325Y341736D01*
G03Y344158I708J1211D01*
G01X470266Y344124D01*
X466560D01*
X466073Y343637D01*
G02X465468Y343683I-283J283D01*
G03X464082Y344337I-1195J-736D01*
G02X463658Y344736I-24J399D01*
G01Y345058D01*
G02X464082Y345457I400J0D01*
G03X464073Y348236I191J1390D01*
G02X463650Y348635I-23J399D01*
G01Y348959D01*
G02X464073Y349358I400J0D01*
G03Y352136I200J1389D01*
G02X463650Y352535I-23J399D01*
G01Y352859D01*
G02X464073Y353258I400J0D01*
G03Y356036I200J1389D01*
G02X463650Y356435I-23J399D01*
G01Y356759D01*
G02X464073Y357158I400J0D01*
G03X465572Y359076I200J1389D01*
G01X465510Y359230D01*
X465950Y359670D01*
G02X466532Y359652I283J-283D01*
G03X468497Y361617I1121J844D01*
G02X468479Y362199I265J299D01*
G01X468949Y362669D01*
G02X469630Y362427I283J-283D01*
G03X471053Y363850I1403J20D01*
G02X470811Y364531I41J398D01*
G01X471237Y364957D01*
X471311Y364972D01*
G03X472408Y366069I-278J1375D01*
G01X472423Y366143D01*
X473506Y367226D01*
G03X474100Y366928I908J1069D01*
G03X475505Y367415I313J1367D01*
G03X475549Y369120I-1092J881D01*
G01X475489Y369209D01*
X475934Y369654D01*
G02X476552Y369591I283J-282D01*
G03X478448Y371487I1240J656D01*
G02X478385Y372105I219J335D01*
G01X480981Y374701D01*
X481093Y374695D01*
G03X482573Y376175I79J1401D01*
G01X482567Y376287D01*
X483273Y376993D01*
G02X483449Y377066I177J-177D01*
G01X483615Y377002D01*
X483641Y376980D01*
G03X485619Y378958I911J1067D01*
G01X485597Y378984D01*
X485533Y379150D01*
G02X485607Y379327I250J-1D01*
G01X485952Y379672D01*
G02X486602Y379549I283J-282D01*
G03X489327Y379851I1330J447D01*
G01X489334Y379918D01*
X489928Y380727D01*
G02X490467Y380827I323J-236D01*
G03X491654Y383308I845J1120D01*
G01X491574Y383328D01*
X491416Y383519D01*
X491424Y383620D01*
G03Y384174I-3492J277D01*
G01X491416Y384275D01*
X491574Y384466D01*
X491654Y384486D01*
G03X492120Y386994I-342J1361D01*
G01Y388600D01*
G03X492669Y389391I-808J1147D01*
G01X492686Y389456D01*
X493814Y390584D01*
X493981Y390486D01*
G03X495902Y392407I711J1210D01*
G01X495804Y392574D01*
X496240Y393010D01*
G02X496851Y392956I283J-283D01*
G03X499421Y394031I1221J691D01*
G02X499813Y394510I392J79D01*
G01X500565D01*
G03X501042Y394255I888J1087D01*
G03X502821Y395903I410J1342D01*
G01X502797Y396010D01*
X503194Y396407D01*
G02X503917Y396482I397J-304D01*
G03X505375Y398840I914J1064D01*
G02X505214Y399654I193J461D01*
G01X508822Y403262D01*
X509593D01*
X509667Y403422D01*
X511831D01*
X512808Y404398D01*
X513721Y404061D01*
X513653Y403874D01*
G03X515958Y404394I1319J-478D01*
G02X516309Y405250I351J356D01*
G01X516938D01*
X516980Y405052D01*
G03X519724I1372J295D01*
G01X519766Y405250D01*
X520394D01*
G02X520745Y404394I0J-500D01*
G03X522717I986J-998D01*
G02X523068Y405250I351J356D01*
G01X523697D01*
X523739Y405052D01*
G03X526483I1372J295D01*
G01X526525Y405250D01*
X527154D01*
G02X527505Y404394I0J-500D01*
G03X528751Y404775I986J-998D01*
G02X528490Y405620I92J491D01*
G01X529280Y406410D01*
X533430D01*
X534524Y405316D01*
G02X534454Y404551I-354J-353D01*
G03X536406Y402599I797J-1155D01*
G02X537171Y402669I412J-284D01*
G01X537517Y402323D01*
X537420Y402156D01*
G03X539340Y400236I1211J-709D01*
G01X539507Y400333D01*
X540638Y399202D01*
X540651Y399149D01*
G03X541664Y398136I1360J347D01*
G01X541717Y398123D01*
X542018Y397822D01*
G02X541756Y396977I-353J-354D01*
G03X542519Y394289I256J-1380D01*
G02X543200Y393823I181J-466D01*
G01Y393470D01*
G02X542519Y393004I-500J0D01*
G03Y390388I-508J-1308D01*
G02X543200Y389922I181J-466D01*
G01Y389570D01*
G02X542519Y389104I-500J0D01*
G03Y386488I-508J-1308D01*
G02X543200Y386022I181J-466D01*
G01Y385670D01*
G02X542519Y385204I-500J0D01*
G03Y382588I-508J-1308D01*
G02X543200Y382122I181J-466D01*
G01Y381770D01*
G02X542519Y381304I-500J0D01*
G03Y378688I-508J-1308D01*
G02X543200Y378222I181J-466D01*
G01Y377870D01*
G02X542519Y377404I-500J0D01*
G03Y374788I-508J-1308D01*
G02X543200Y374322I181J-466D01*
G01Y370070D01*
G02X542519Y369604I-500J0D01*
G03Y366988I-508J-1308D01*
G02X543200Y366522I181J-466D01*
G01Y362270D01*
G02X542519Y361804I-500J0D01*
G03Y359188I-508J-1308D01*
G02X543200Y358722I181J-466D01*
G01Y358370D01*
G02X542519Y357904I-500J0D01*
G03X543093Y355703I-508J-1308D01*
G02X543832Y355738I385J-319D01*
G01X544185Y355385D01*
X544114Y355227D01*
G03X545971Y353370I1277J-580D01*
G01X546129Y353441D01*
X547532Y352038D01*
G03X548001Y351523I1239J658D01*
G01Y349969D01*
G03X547965Y347647I770J-1173D01*
G01Y346044D01*
G03X549390Y343637I806J-1148D01*
G02X550110Y343188I220J-449D01*
G01Y342704D01*
G02X549390Y342255I-500J0D01*
G03Y339737I-619J-1259D01*
G02X550110Y339288I220J-449D01*
G01Y334904D01*
G02X549390Y334455I-500J0D01*
G03Y331937I-619J-1259D01*
G02X550110Y331488I220J-449D01*
G01Y328670D01*
X548024Y326584D01*
X548002Y326570D01*
G03X547666Y326260I771J-1172D01*
G01X547201D01*
G02X546726Y326914I0J500D01*
G03X544056I-1335J433D01*
G02X543581Y326260I-475J-154D01*
G01X543116D01*
G03X540906I-1105J-864D01*
G01X540441D01*
G02X539966Y326914I0J500D01*
G03X537544Y326460I-1335J433D01*
G02X537510Y325790I-387J-316D01*
G01X535840Y324120D01*
X535300D01*
X532112Y320932D01*
X532017Y320941D01*
G03X531310Y320832I-147J-1394D01*
G01X531271Y320815D01*
X530271D01*
G02X529876Y321277I0J400D01*
G03X527106I-1385J219D01*
G02X526711Y320815I-395J-62D01*
G01X525711D01*
X525672Y320832D01*
G03X524550I-561J-1285D01*
G01X524511Y320815D01*
X518952D01*
X518913Y320832D01*
G03X517791I-561J-1285D01*
G01X517752Y320815D01*
X516752D01*
G02X516357Y321277I0J400D01*
G03X513587I-1385J219D01*
G02X513192Y320815I-395J-62D01*
G01X512192D01*
X512153Y320832D01*
G03X511031I-561J-1285D01*
G01X510992Y320815D01*
X509785D01*
X507946Y318976D01*
X506626D01*
G02X506228Y319414I0J400D01*
G03X503436I-1396J133D01*
G02X503038Y318976I-398J-38D01*
G01X501700D01*
X501684Y318979D01*
G03X501220I-232J-1383D01*
G01X501204Y318976D01*
X499866D01*
G02X499468Y319414I0J400D01*
G03X496676I-1396J133D01*
G02X496278Y318976I-398J-38D01*
G01X494940D01*
X494924Y318979D01*
G03X494460I-232J-1383D01*
G01X494444Y318976D01*
X493106D01*
G02X492708Y319414I0J400D01*
G03X489916I-1396J133D01*
G02X489518Y318976I-398J-38D01*
G01X488180D01*
X488164Y318979D01*
G03X487700I-232J-1383D01*
G01X487684Y318976D01*
X486346D01*
G02X485948Y319414I0J400D01*
G03X483156I-1396J132D01*
G02X482758Y318976I-398J-38D01*
G01X481420D01*
X481404Y318979D01*
G03X480940I-232J-1383D01*
G01X480924Y318976D01*
X479586D01*
G02X479188Y319414I0J400D01*
G03X477202Y320819I-1396J133D01*
G01X477161Y320800D01*
X471690D01*
G02X471296Y321266I0J400D01*
G03X469191Y320294I-1383J230D01*
G02X469268Y319668I-206J-343D01*
G01X466600Y317000D01*
Y307500D01*
X463700D01*
X462600Y306400D01*
Y294570D01*
G03Y294430I1400J-70D01*
G01Y293100D01*
X464116Y291584D01*
G02X463825Y290902I-283J-282D01*
G03X465202Y289525I-25J-1402D01*
G02X465884Y289816I400J8D01*
G01X466592Y289108D01*
G02X466403Y288436I-283J-283D01*
G03X468136Y287080I331J-1362D01*
G01Y287164D01*
X468336Y287364D01*
X468660Y287040D01*
X468611Y286917D01*
G03X469902Y284994I1302J-521D01*
G02X470100Y284794I-2J-200D01*
G01Y284100D01*
X476100Y278100D01*
X477300D01*
X478400Y277000D01*
Y276400D01*
X477026Y275026D01*
X476670D01*
X475420Y273776D01*
X473331D01*
G37*
G36*
G01X630450Y138000D02*
X626000Y142450D01*
Y153200D01*
X596470Y182730D01*
Y187950D01*
X578420Y206000D01*
Y216089D01*
G02X578855Y216488I400J0D01*
G03X580354Y218161I125J1396D01*
G02X580825Y218632I392J79D01*
G03X579728Y219729I277J1374D01*
G02X579257Y219258I-392J-79D01*
G03X578855Y219280I-277J-1374D01*
G02X578420Y219679I-35J399D01*
G01Y228782D01*
G02X579128Y229037I400J0D01*
G03X579664Y231502I1232J1023D01*
G02X579126Y231698I-173J361D01*
G03X578809Y232141I-1277J-579D01*
G02X578805Y232720I274J291D01*
G03X579050Y233034I-972J1011D01*
G02X579589Y233186I347J-199D01*
G03X578828Y235056I771J1404D01*
G02X578536Y234941I-192J58D01*
G03X578420Y235002I-710J-1209D01*
G01Y262880D01*
X568300Y273000D01*
X561000D01*
X560200Y273303D01*
X560165Y273373D01*
G03X558388Y274048I-1254J-626D01*
G01X558315Y274018D01*
X556932Y274543D01*
X556933Y274683D01*
G03X554473Y275616I-1402J13D01*
G01X554381Y275511D01*
X553736Y275755D01*
G02X553494Y276244I141J374D01*
G03X550879Y277236I-1343J402D01*
G02X550375Y277030I-363J168D01*
G01X550073Y277145D01*
G02X549895Y277758I142J374D01*
G03X547497Y279181I-1124J838D01*
G02X546851Y279066I-363J168D01*
G01X546371Y279545D01*
G03X544111Y281120I-980J1002D01*
G01X544058Y281002D01*
X543015D01*
X542752Y281264D01*
X542900Y281412D01*
X542907Y281418D01*
G03X540663Y282111I-896J1078D01*
G02X540278Y281602I-385J-109D01*
G01X539555D01*
G03X537707I-924J-1055D01*
G01X536984D01*
G02X536599Y282111I0J400D01*
G03X533858Y282656I-1348J385D01*
G02X533349Y282318I-397J46D01*
G01X532678Y282513D01*
G02X532586Y283241I112J384D01*
G03X530549Y283981I-715J1206D01*
G02X529996Y283489I-378J-132D01*
G01X526190Y285344D01*
X526163Y285374D01*
G03X525192Y285847I-1052J-927D01*
G01X525152Y285849D01*
X523052Y286872D01*
X523023Y286941D01*
G03X521364Y287749I-1292J-545D01*
G01X521292Y287730D01*
X519751Y288480D01*
X519734Y288581D01*
G03X517685Y289580I-1382J-234D01*
G01X517594Y289531D01*
X516370Y290128D01*
X516373Y290256D01*
G03X514077Y291375I-1401J40D01*
G01X513978Y291293D01*
X512931Y291803D01*
X512964Y291955D01*
G03X510386Y292960I-1372J290D01*
G01X510308Y292828D01*
X509711Y292992D01*
G02X509461Y293560I106J386D01*
G03X506813Y294289I-1249J636D01*
G02X506308Y293930I-399J27D01*
G01X505524Y294146D01*
G02X505453Y294890I106J386D01*
G03X503655Y295385I-621J1257D01*
G02X503213Y294782I-336J-218D01*
G01X502643Y294939D01*
X502602Y294998D01*
G03X500875Y295474I-1150J-802D01*
G01X500809Y295444D01*
X499446Y295819D01*
X499465Y295989D01*
G03X496794Y296725I-1393J159D01*
G01X496724Y296569D01*
X496104Y296740D01*
G02X495873Y297341I106J386D01*
G03X493291Y298052I-1181J755D01*
G02X492785Y297653I-400J-13D01*
G01X489231Y298632D01*
X489191Y298713D01*
G03X487166Y299271I-1259J-617D01*
G01X487091Y299221D01*
X485879Y299555D01*
X485920Y299741D01*
G03X483220Y300485I-1368J306D01*
G01X483161Y300304D01*
X482478Y300491D01*
G02X482271Y301125I107J386D01*
G03X479782Y301811I-1099J871D01*
G02X479280Y301372I-396J-53D01*
G01X477000Y302000D01*
X474800Y304200D01*
X471165D01*
G02X470887Y304888I0J400D01*
G03X469412Y304587I-974J1008D01*
G01X469540Y304538D01*
Y304200D01*
X468900D01*
X468100Y305000D01*
Y314500D01*
X468700Y315100D01*
Y317684D01*
X469716Y318700D01*
X474800D01*
X476695Y316805D01*
G02X476708Y316537I-141J-141D01*
G03X479194Y315610I1084J-889D01*
G02X479593Y316000I400J-10D01*
G01X482751D01*
G02X483150Y315610I-1J-400D01*
G03X485681Y314816I1402J37D01*
G01X485787Y314960D01*
X486718Y314419D01*
X486647Y314256D01*
G03X489054Y312855I1285J-560D01*
G01X489161Y312997D01*
X490090Y312457D01*
X490021Y312294D01*
G03X492426Y310895I1291J-548D01*
G01X492533Y311035D01*
X493463Y310494D01*
X493396Y310333D01*
G03X495798Y308935I1295J-537D01*
G01X495905Y309073D01*
X496836Y308532D01*
X496772Y308371D01*
G03X499170Y306975I1300J-524D01*
G01X499278Y307111D01*
X500210Y306569D01*
X500147Y306409D01*
G03X502543Y305015I1305J-514D01*
G01X502651Y305149D01*
X503583Y304606D01*
X503522Y304447D01*
G03X505914Y303056I1310J-500D01*
G01X506022Y303187D01*
X506957Y302643D01*
X506898Y302485D01*
G03X509287Y301096I1314J-489D01*
G01X509395Y301225D01*
X510330Y300681D01*
X510274Y300524D01*
G03X512706Y299196I1318J-477D01*
G02X512982Y299236I159J-122D01*
G03X513575Y298893I1992J2759D01*
G02X513677Y298634I-82J-182D01*
G03X516334Y297764I1295J-538D01*
G02X516860Y298044I388J-95D01*
G01X517306Y297882D01*
G02X517431Y297204I-137J-376D01*
G03X519737Y296363I921J-1057D01*
G02X520270Y296800I395J61D01*
G01X523873Y295486D01*
X523909Y295425D01*
G03X525565Y294821I1202J722D01*
G01X525632Y294844D01*
X527087Y294313D01*
X527089Y294175D01*
G03X529550Y293277I1402J21D01*
G01X529640Y293381D01*
X530228Y293167D01*
X530241Y293160D01*
G03X530474Y293044I1632J2986D01*
G02X530577Y292784I-82J-183D01*
G03X533160Y291694I1294J-539D01*
G02X533665Y291913I368J-157D01*
G01X533981Y291797D01*
G02X534156Y291172I-137J-375D01*
G03X536653Y290261I1095J-876D01*
G02X537190Y290627I400J-10D01*
G01X537974Y290340D01*
G02X538013Y289606I-137J-375D01*
G03X539914Y288912I618J-1259D01*
G02X540417Y289449I366J161D01*
G01X541169Y289175D01*
X541191Y289159D01*
G03X541906Y288898I820J1137D01*
G01X541934Y288896D01*
X544000Y288142D01*
X544024Y288036D01*
G03X546236Y287229I1367J311D01*
G01X546323Y287294D01*
X547445Y286885D01*
X547405Y286713D01*
G03X550170Y286312I1366J-317D01*
G01X550182Y286500D01*
X556753D01*
X556794Y286353D01*
G03X557651Y285415I1351J374D01*
G02X557887Y284909I-141J-374D01*
G03X560608Y284565I1324J-462D01*
G02X560979Y284997I399J33D01*
G03X562283Y286312I-95J1399D01*
G01X562295Y286500D01*
X586780D01*
X593730Y279550D01*
Y221979D01*
G02X593101Y221650I-400J-1D01*
G03Y219350I-801J-1150D01*
G02X593730Y219021I229J-328D01*
G01Y216940D01*
X593724Y216916D01*
G03Y212612I8638J-2152D01*
G01X593730Y212588D01*
Y210060D01*
X599303Y204487D01*
G02X599301Y203919I-283J-283D01*
G03X601284Y201936I985J-998D01*
G02X601852Y201938I285J-281D01*
G01X602924Y200866D01*
G02X602781Y200209I-283J-282D01*
G03X604586Y198404I492J-1313D01*
G02X605243Y198547I375J-140D01*
G01X605384Y198406D01*
X605376Y198314D01*
G03X606891Y196799I1397J-118D01*
G01X606983Y196807D01*
X610750Y193040D01*
X630532D01*
X643250Y180322D01*
Y175150D01*
X644200Y174200D01*
X649000D01*
X659500Y163700D01*
Y139500D01*
X658000Y138000D01*
X630450D01*
G37*
G36*
G01X443202Y382742D02*
X442455Y382622D01*
X441935Y383320D01*
X442263Y384001D01*
X442403Y384105D01*
X443342Y382847D01*
X443202Y382742D01*
G37*
G36*
G01X441491Y388937D02*
X440821Y389287D01*
Y390157D01*
X441491Y390507D01*
X441666D01*
Y388937D01*
X441491D01*
G37*
G36*
G01X442364Y388601D02*
X443034Y388251D01*
Y387381D01*
X442364Y387031D01*
X442189D01*
Y388601D01*
X442364D01*
G37*
G36*
G01X434992Y400752D02*
X434232Y401102D01*
Y402002D01*
X434992Y402352D01*
X435167D01*
Y400752D01*
X434992D01*
G37*
G36*
G01X437417Y395718D02*
X436584Y395640D01*
X436134Y396420D01*
X436617Y397103D01*
X436768Y397191D01*
X437569Y395805D01*
X437417Y395718D01*
G37*
G36*
G01X436090Y402352D02*
X436850Y402002D01*
Y401102D01*
X436090Y400752D01*
X435915D01*
Y402352D01*
X436090D01*
G37*
G36*
G01X437571Y397655D02*
X438404Y397732D01*
X438855Y396953D01*
X438372Y396270D01*
X438220Y396182D01*
X437420Y397567D01*
X437571Y397655D01*
G37*
G36*
G01X441215Y394236D02*
X441853Y394641D01*
X442606Y394206D01*
X442574Y393451D01*
X442487Y393299D01*
X441127Y394085D01*
X441215Y394236D01*
G37*
G36*
G01X452382Y387031D02*
X451712Y387381D01*
Y388251D01*
X452382Y388601D01*
X452557D01*
Y387031D01*
X452382D01*
G37*
G36*
G01X453902Y402751D02*
X453117Y402461D01*
X452481Y403097D01*
X452771Y403882D01*
X452894Y404006D01*
X454026Y402874D01*
X453902Y402751D01*
G37*
G36*
G01X455206Y399589D02*
X454446Y399939D01*
Y400839D01*
X455206Y401189D01*
X455381D01*
Y399589D01*
X455206D01*
G37*
G36*
G01Y395689D02*
X454446Y396039D01*
Y396939D01*
X455206Y397289D01*
X455381D01*
Y395689D01*
X455206D01*
G37*
G36*
G01X456628Y393946D02*
X457299Y393597D01*
X457301Y392727D01*
X456631Y392376D01*
X456456D01*
X456453Y393945D01*
X456628Y393946D01*
G37*
G36*
G01X456304Y401189D02*
X457064Y400839D01*
Y399939D01*
X456304Y399589D01*
X456129D01*
Y401189D01*
X456304D01*
G37*
G36*
G01Y397289D02*
X457064Y396939D01*
Y396039D01*
X456304Y395689D01*
X456129D01*
Y397289D01*
X456304D01*
G37*
G36*
G01X440085Y385214D02*
X439415Y384866D01*
X438702Y385365D01*
X438800Y386114D01*
X438900Y386257D01*
X440186Y385358D01*
X440085Y385214D01*
G37*
G36*
G01X438140Y387007D02*
X437471Y387356D01*
X437470Y388226D01*
X438140Y388575D01*
X438315D01*
Y387006D01*
X438140Y387007D01*
G37*
G36*
G01X433787Y394608D02*
X432953Y394531D01*
X432503Y395310D01*
X432986Y395993D01*
X433137Y396081D01*
X433938Y394696D01*
X433787Y394608D01*
G37*
G36*
G01X436650Y391133D02*
X436012Y390728D01*
X435259Y391163D01*
X435291Y391918D01*
X435378Y392069D01*
X436738Y391284D01*
X436650Y391133D01*
G37*
G36*
G01X430427Y401402D02*
X429642Y401112D01*
X429006Y401749D01*
X429296Y402534D01*
X429420Y402657D01*
X430551Y401526D01*
X430427Y401402D01*
G37*
G36*
G01X439734Y390497D02*
X440404Y390147D01*
Y389278D01*
X439734Y388928D01*
X439560Y388927D01*
X439559Y390498D01*
X439734Y390497D01*
G37*
G36*
G01X430072Y403310D02*
X430857Y403600D01*
X431494Y402964D01*
X431204Y402179D01*
X431080Y402055D01*
X429949Y403186D01*
X430072Y403310D01*
G37*
G36*
G01X433941Y396545D02*
X434774Y396623D01*
X435224Y395843D01*
X434741Y395160D01*
X434590Y395072D01*
X433789Y396458D01*
X433941Y396545D01*
G37*
G36*
G01X437834Y392288D02*
X438472Y392693D01*
X439225Y392259D01*
X439193Y391503D01*
X439107Y391352D01*
X437746Y392137D01*
X437834Y392288D01*
G37*
G36*
G01X449002Y385042D02*
X448332Y385392D01*
Y386262D01*
X449002Y386612D01*
X449177D01*
Y385042D01*
X449002D01*
G37*
G36*
G01X449875Y388606D02*
X450545Y388256D01*
Y387386D01*
X449875Y387036D01*
X449700D01*
Y388606D01*
X449875D01*
G37*
G36*
G01X451374Y400363D02*
X450590Y400073D01*
X449953Y400710D01*
X450243Y401494D01*
X450367Y401618D01*
X451498Y400487D01*
X451374Y400363D01*
G37*
G36*
G01X452153Y394730D02*
X451393Y395080D01*
Y395980D01*
X452153Y396330D01*
X452328D01*
Y394730D01*
X452153D01*
G37*
G36*
G01X451020Y402271D02*
X451804Y402561D01*
X452441Y401924D01*
X452151Y401140D01*
X452027Y401016D01*
X450896Y402147D01*
X451020Y402271D01*
G37*
G36*
G01X453251Y398730D02*
X454011Y398380D01*
Y397480D01*
X453251Y397130D01*
X453076D01*
Y398730D01*
X453251D01*
G37*
G36*
G01Y394830D02*
X454011Y394480D01*
Y393580D01*
X453251Y393230D01*
X453076D01*
Y394830D01*
X453251D01*
G37*
G36*
G01X461771Y388984D02*
X461101Y389334D01*
Y390204D01*
X461771Y390554D01*
X461946D01*
Y388984D01*
X461771D01*
G37*
G36*
G01Y400660D02*
X461101Y401010D01*
Y401880D01*
X461771Y402230D01*
X461946D01*
Y400660D01*
X461771D01*
G37*
G36*
G01Y392884D02*
X461101Y393234D01*
Y394104D01*
X461771Y394454D01*
X461946D01*
Y392884D01*
X461771D01*
G37*
G36*
G01Y396784D02*
X461101Y397134D01*
Y398004D01*
X461771Y398354D01*
X461946D01*
Y396784D01*
X461771D01*
G37*
G36*
G01X462546Y384909D02*
X461876Y385259D01*
Y386129D01*
X462546Y386479D01*
X462721D01*
Y384909D01*
X462546D01*
G37*
G36*
G01X463395Y396355D02*
X464065Y396005D01*
Y395135D01*
X463395Y394785D01*
X463220D01*
Y396355D01*
X463395D01*
G37*
G36*
G01Y404205D02*
X464065Y403855D01*
Y402985D01*
X463395Y402635D01*
X463220D01*
Y404205D01*
X463395D01*
G37*
G36*
G01Y400280D02*
X464065Y399930D01*
Y399060D01*
X463395Y398710D01*
X463220D01*
Y400280D01*
X463395D01*
G37*
G36*
G01X472989Y388992D02*
X472957Y389747D01*
X473710Y390182D01*
X474349Y389777D01*
X474436Y389625D01*
X473076Y388840D01*
X472989Y388992D01*
G37*
G36*
G01X475290Y400626D02*
X474620Y400976D01*
Y401846D01*
X475290Y402196D01*
X475465D01*
Y400626D01*
X475290D01*
G37*
G36*
G01Y392826D02*
X474620Y393176D01*
Y394046D01*
X475290Y394396D01*
X475465D01*
Y392826D01*
X475290D01*
G37*
G36*
G01Y396726D02*
X474620Y397076D01*
Y397946D01*
X475290Y398296D01*
X475465D01*
Y396726D01*
X475290D01*
G37*
G36*
G01X476915Y404217D02*
X477585Y403867D01*
Y402997D01*
X476915Y402647D01*
X476740D01*
Y404217D01*
X476915D01*
G37*
G36*
G01Y392517D02*
X477585Y392167D01*
Y391297D01*
X476915Y390947D01*
X476740D01*
Y392517D01*
X476915D01*
G37*
G36*
G01Y400317D02*
X477585Y399967D01*
Y399097D01*
X476915Y398747D01*
X476740D01*
Y400317D01*
X476915D01*
G37*
G36*
G01Y396417D02*
X477585Y396067D01*
Y395197D01*
X476915Y394847D01*
X476740D01*
Y396417D01*
X476915D01*
G37*
G36*
G01X458391Y387046D02*
X457721Y387396D01*
Y388266D01*
X458391Y388616D01*
X458566D01*
Y387046D01*
X458391D01*
G37*
G36*
G01Y394846D02*
X457721Y395196D01*
Y396066D01*
X458391Y396416D01*
X458566D01*
Y394846D01*
X458391D01*
G37*
G36*
G01Y398746D02*
X457721Y399096D01*
Y399966D01*
X458391Y400316D01*
X458566D01*
Y398746D01*
X458391D01*
G37*
G36*
G01Y390946D02*
X457721Y391296D01*
Y392166D01*
X458391Y392516D01*
X458566D01*
Y390946D01*
X458391D01*
G37*
G36*
G01X460015Y402196D02*
X460685Y401846D01*
Y400976D01*
X460015Y400626D01*
X459840D01*
Y402196D01*
X460015D01*
G37*
G36*
G01Y398296D02*
X460685Y397946D01*
Y397076D01*
X460015Y396726D01*
X459840D01*
Y398296D01*
X460015D01*
G37*
G36*
G01Y394407D02*
X460685Y394057D01*
Y393187D01*
X460015Y392837D01*
X459840D01*
Y394407D01*
X460015D01*
G37*
G36*
G01X470740Y387459D02*
X470019Y387232D01*
X469404Y387847D01*
X469630Y388569D01*
X469754Y388692D01*
X470864Y387582D01*
X470740Y387459D01*
G37*
G36*
G01X471911Y402636D02*
X471241Y402986D01*
Y403856D01*
X471911Y404206D01*
X472086D01*
Y402636D01*
X471911D01*
G37*
G36*
G01Y394836D02*
X471241Y395186D01*
Y396056D01*
X471911Y396406D01*
X472086D01*
Y394836D01*
X471911D01*
G37*
G36*
G01Y398736D02*
X471241Y399086D01*
Y399956D01*
X471911Y400306D01*
X472086D01*
Y398736D01*
X471911D01*
G37*
G36*
G01X473535Y402207D02*
X474205Y401857D01*
Y400987D01*
X473535Y400637D01*
X473360D01*
Y402207D01*
X473535D01*
G37*
G36*
G01Y398307D02*
X474205Y397957D01*
Y397087D01*
X473535Y396737D01*
X473360D01*
Y398307D01*
X473535D01*
G37*
G36*
G01Y394407D02*
X474205Y394057D01*
Y393187D01*
X473535Y392837D01*
X473360D01*
Y394407D01*
X473535D01*
G37*
G36*
G01X440534Y400736D02*
X441367Y400813D01*
X441817Y400033D01*
X441334Y399350D01*
X441182Y399263D01*
X440383Y400648D01*
X440534Y400736D01*
G37*
G36*
G01X446495Y386607D02*
X447165Y386257D01*
Y385387D01*
X446495Y385037D01*
X446320D01*
Y386607D01*
X446495D01*
G37*
G36*
G01Y390507D02*
X447165Y390157D01*
Y389287D01*
X446495Y388937D01*
X446320D01*
Y390507D01*
X446495D01*
G37*
G36*
G01X445776Y395560D02*
X446531Y395592D01*
X446966Y394839D01*
X446561Y394201D01*
X446410Y394113D01*
X445624Y395473D01*
X445776Y395560D01*
G37*
G36*
G01X466775Y390507D02*
X467445Y390157D01*
Y389287D01*
X466775Y388937D01*
X466600D01*
Y390507D01*
X466775D01*
G37*
G36*
G01X470155Y384656D02*
X470825Y384306D01*
Y383436D01*
X470155Y383086D01*
X469980D01*
Y384656D01*
X470155D01*
G37*
G36*
G01X466775Y402255D02*
X467445Y401905D01*
Y401035D01*
X466775Y400685D01*
X466600D01*
Y402255D01*
X466775D01*
G37*
G36*
G01Y398365D02*
X467445Y398015D01*
Y397145D01*
X466775Y396795D01*
X466600D01*
Y398365D01*
X466775D01*
G37*
G36*
G01Y394455D02*
X467445Y394105D01*
Y393235D01*
X466775Y392885D01*
X466600D01*
Y394455D01*
X466775D01*
G37*
G36*
G01X446623Y399181D02*
X445863Y399531D01*
Y400431D01*
X446623Y400781D01*
X446798D01*
Y399181D01*
X446623D01*
G37*
G36*
G01X447799Y393440D02*
X447283Y394099D01*
X447695Y394899D01*
X448531Y394863D01*
X448686Y394784D01*
X447955Y393360D01*
X447799Y393440D01*
G37*
G36*
G01X448285Y396420D02*
X447500Y396130D01*
X446864Y396767D01*
X447154Y397552D01*
X447277Y397675D01*
X448409Y396544D01*
X448285Y396420D01*
G37*
G36*
G01X468531Y400637D02*
X467861Y400987D01*
Y401857D01*
X468531Y402207D01*
X468706D01*
Y400637D01*
X468531D01*
G37*
G36*
G01X468217Y393821D02*
X467782Y394440D01*
X468182Y395213D01*
X468938Y395216D01*
X469093Y395136D01*
X468372Y393741D01*
X468217Y393821D01*
G37*
G36*
G01X468531Y396737D02*
X467861Y397087D01*
Y397957D01*
X468531Y398307D01*
X468706D01*
Y396737D01*
X468531D01*
G37*
G36*
G01X444871Y387036D02*
X444201Y387386D01*
Y388256D01*
X444871Y388606D01*
X445046D01*
Y387036D01*
X444871D01*
G37*
G36*
G01Y390936D02*
X444201Y391286D01*
Y392156D01*
X444871Y392506D01*
X445046D01*
Y390936D01*
X444871D01*
G37*
G36*
G01X440381Y398800D02*
X439548Y398723D01*
X439098Y399503D01*
X439581Y400186D01*
X439733Y400273D01*
X440532Y398888D01*
X440381Y398800D01*
G37*
G36*
G01X443384Y395008D02*
X442746Y394603D01*
X441993Y395038D01*
X442025Y395793D01*
X442112Y395945D01*
X443472Y395159D01*
X443384Y395008D01*
G37*
G36*
G01X467060Y385249D02*
X466422Y384844D01*
X465669Y385279D01*
X465701Y386034D01*
X465788Y386186D01*
X467148Y385401D01*
X467060Y385249D01*
G37*
G36*
G01X465151Y387036D02*
X464481Y387386D01*
Y388256D01*
X465151Y388606D01*
X465326D01*
Y387036D01*
X465151D01*
G37*
G36*
G01Y402611D02*
X464481Y402961D01*
Y403831D01*
X465151Y404181D01*
X465326D01*
Y402611D01*
X465151D01*
G37*
G36*
G01Y394786D02*
X464481Y395136D01*
Y396006D01*
X465151Y396356D01*
X465326D01*
Y394786D01*
X465151D01*
G37*
G36*
G01Y398675D02*
X464481Y399025D01*
Y399895D01*
X465151Y400245D01*
X465326D01*
Y398675D01*
X465151D01*
G37*
G36*
G01X465152Y390911D02*
X464482Y391261D01*
Y392131D01*
X465152Y392481D01*
X465327D01*
Y390911D01*
X465152D01*
G37*
G36*
G01X445806Y403300D02*
X446591Y403590D01*
X447227Y402954D01*
X446937Y402169D01*
X446813Y402045D01*
X445682Y403176D01*
X445806Y403300D01*
G37*
G36*
G01X447931Y398329D02*
X448716Y398619D01*
X449353Y397983D01*
X449063Y397198D01*
X448939Y397074D01*
X447808Y398206D01*
X447931Y398329D01*
G37*
G36*
G01X449837Y396410D02*
X450508Y396062D01*
X450511Y395192D01*
X449841Y394840D01*
X449666D01*
X449662Y396409D01*
X449837Y396410D01*
G37*
G36*
G01X470155Y404206D02*
X470825Y403856D01*
Y402986D01*
X470155Y402636D01*
X469980D01*
Y404206D01*
X470155D01*
G37*
G36*
G01Y400306D02*
X470825Y399956D01*
Y399086D01*
X470155Y398736D01*
X469980D01*
Y400306D01*
X470155D01*
G37*
G36*
G01Y396406D02*
X470825Y396056D01*
Y395186D01*
X470155Y394836D01*
X469980D01*
Y396406D01*
X470155D01*
G37*
G36*
G01X429177Y411224D02*
X428393Y410934D01*
X427756Y411571D01*
X428046Y412355D01*
X428170Y412479D01*
X429301Y411348D01*
X429177Y411224D01*
G37*
G36*
G01X431935Y408466D02*
X431151Y408176D01*
X430514Y408813D01*
X430804Y409597D01*
X430928Y409721D01*
X432059Y408590D01*
X431935Y408466D01*
G37*
G36*
G01X434693Y405708D02*
X433909Y405418D01*
X433272Y406055D01*
X433562Y406839D01*
X433686Y406963D01*
X434817Y405832D01*
X434693Y405708D01*
G37*
G36*
G01X431581Y410374D02*
X432365Y410664D01*
X433002Y410027D01*
X432712Y409243D01*
X432588Y409119D01*
X431457Y410250D01*
X431581Y410374D01*
G37*
G36*
G01X434339Y407616D02*
X435123Y407906D01*
X435760Y407269D01*
X435470Y406485D01*
X435346Y406361D01*
X434215Y407492D01*
X434339Y407616D01*
G37*
G36*
G01X428823Y413132D02*
X429607Y413422D01*
X430244Y412785D01*
X429954Y412001D01*
X429830Y411877D01*
X428699Y413008D01*
X428823Y413132D01*
G37*
G36*
G01X451886Y406944D02*
X451126Y407294D01*
Y408194D01*
X451886Y408544D01*
X452061D01*
Y406944D01*
X451886D01*
G37*
G36*
G01X451102Y409951D02*
X450317Y409661D01*
X449681Y410297D01*
X449971Y411082D01*
X450094Y411206D01*
X451226Y410074D01*
X451102Y409951D01*
G37*
G36*
G01X448786Y413944D02*
X448026Y414294D01*
Y415194D01*
X448786Y415544D01*
X448961D01*
Y413944D01*
X448786D01*
G37*
G36*
G01X450747Y411859D02*
X451532Y412148D01*
X452168Y411512D01*
X451878Y410727D01*
X451755Y410603D01*
X450623Y411735D01*
X450747Y411859D01*
G37*
G36*
G01X449884Y415544D02*
X450644Y415194D01*
Y414294D01*
X449884Y413944D01*
X449709D01*
Y415544D01*
X449884D01*
G37*
G36*
G01X453547Y404659D02*
X454332Y404948D01*
X454968Y404312D01*
X454678Y403527D01*
X454555Y403403D01*
X453423Y404535D01*
X453547Y404659D01*
G37*
G36*
G01X452984Y408544D02*
X453744Y408194D01*
Y407294D01*
X452984Y406944D01*
X452809D01*
Y408544D01*
X452984D01*
G37*
G36*
G01X427669Y404160D02*
X426885Y403870D01*
X426248Y404507D01*
X426538Y405291D01*
X426662Y405415D01*
X427793Y404284D01*
X427669Y404160D01*
G37*
G36*
G01X424912Y406918D02*
X424127Y406628D01*
X423490Y407264D01*
X423780Y408049D01*
X423904Y408173D01*
X425035Y407042D01*
X424912Y406918D01*
G37*
G36*
G01X422093Y412089D02*
X421333Y412439D01*
Y413339D01*
X422093Y413689D01*
X422268D01*
Y412089D01*
X422093D01*
G37*
G36*
G01X424557Y408826D02*
X425342Y409116D01*
X425978Y408479D01*
X425688Y407694D01*
X425564Y407571D01*
X424433Y408702D01*
X424557Y408826D01*
G37*
G36*
G01X427315Y406068D02*
X428099Y406358D01*
X428736Y405721D01*
X428446Y404937D01*
X428322Y404813D01*
X427191Y405944D01*
X427315Y406068D01*
G37*
G36*
G01X423191Y413689D02*
X423951Y413339D01*
Y412439D01*
X423191Y412089D01*
X423016D01*
Y413689D01*
X423191D01*
G37*
G36*
G01X446369Y410529D02*
X445584Y410239D01*
X444948Y410875D01*
X445238Y411660D01*
X445361Y411784D01*
X446493Y410652D01*
X446369Y410529D01*
G37*
G36*
G01X443521Y414539D02*
X442761Y414889D01*
Y415788D01*
X443521Y416138D01*
X443696Y416139D01*
Y414538D01*
X443521Y414539D01*
G37*
G36*
G01X448825Y404595D02*
X448065Y404945D01*
Y405845D01*
X448825Y406195D01*
X449000D01*
Y404595D01*
X448825D01*
G37*
G36*
G01X444618Y416138D02*
X445378Y415788D01*
Y414889D01*
X444618Y414539D01*
X444444Y414538D01*
Y416139D01*
X444618Y416138D01*
G37*
G36*
G01X446014Y412436D02*
X446799Y412726D01*
X447435Y412090D01*
X447145Y411305D01*
X447022Y411181D01*
X445890Y412313D01*
X446014Y412436D01*
G37*
G36*
G01X449923Y406195D02*
X450683Y405845D01*
Y404945D01*
X449923Y404595D01*
X449748D01*
Y406195D01*
X449923D01*
G37*
G36*
G01X461771Y406815D02*
X461011Y407165D01*
Y408065D01*
X461771Y408415D01*
X461946D01*
Y406815D01*
X461771D01*
G37*
G36*
G01X461249Y412028D02*
X460464Y411738D01*
X459828Y412374D01*
X460118Y413159D01*
X460241Y413283D01*
X461373Y412151D01*
X461249Y412028D01*
G37*
G36*
G01X461250Y413584D02*
X462035Y413874D01*
X462671Y413238D01*
X462381Y412453D01*
X462258Y412329D01*
X461126Y413461D01*
X461250Y413584D01*
G37*
G36*
G01X462872Y408415D02*
X463632Y408065D01*
Y407165D01*
X462872Y406815D01*
X462697D01*
Y408415D01*
X462872D01*
G37*
G36*
G01X475966Y412755D02*
X475206Y413105D01*
Y414005D01*
X475966Y414355D01*
X476141D01*
Y412755D01*
X475966D01*
G37*
G36*
G01X475290Y404526D02*
X474620Y404876D01*
Y405746D01*
X475290Y406096D01*
X475465D01*
Y404526D01*
X475290D01*
G37*
G36*
G01Y408426D02*
X474620Y408776D01*
Y409646D01*
X475290Y409996D01*
X475465D01*
Y408426D01*
X475290D01*
G37*
G36*
G01X476915Y408117D02*
X477585Y407767D01*
Y406897D01*
X476915Y406547D01*
X476740D01*
Y408117D01*
X476915D01*
G37*
G36*
G01X477066Y414355D02*
X477826Y414005D01*
Y413105D01*
X477066Y412755D01*
X476891D01*
Y414355D01*
X477066D01*
G37*
G36*
G01X457207Y408122D02*
X456423Y407832D01*
X455786Y408469D01*
X456076Y409253D01*
X456200Y409377D01*
X457331Y408246D01*
X457207Y408122D01*
G37*
G36*
G01X458390Y404557D02*
X457630Y404907D01*
Y405807D01*
X458390Y406157D01*
X458565D01*
Y404557D01*
X458390D01*
G37*
G36*
G01X454791Y411561D02*
X454031Y411911D01*
Y412811D01*
X454791Y413161D01*
X454966D01*
Y411561D01*
X454791D01*
G37*
G36*
G01X456853Y410030D02*
X457637Y410320D01*
X458274Y409683D01*
X457984Y408899D01*
X457860Y408775D01*
X456729Y409906D01*
X456853Y410030D01*
G37*
G36*
G01X455891Y413161D02*
X456651Y412811D01*
Y411911D01*
X455891Y411561D01*
X455716D01*
Y413161D01*
X455891D01*
G37*
G36*
G01X459491Y406157D02*
X460251Y405807D01*
Y404907D01*
X459491Y404557D01*
X459316D01*
Y406157D01*
X459491D01*
G37*
G36*
G01X472148Y411423D02*
X471388Y411773D01*
Y412673D01*
X472148Y413023D01*
X472323D01*
Y411423D01*
X472148D01*
G37*
G36*
G01X471911Y406536D02*
X471241Y406886D01*
Y407756D01*
X471911Y408106D01*
X472086D01*
Y406536D01*
X471911D01*
G37*
G36*
G01X472148Y415323D02*
X471388Y415673D01*
Y416573D01*
X472148Y416923D01*
X472323D01*
Y415323D01*
X472148D01*
G37*
G36*
G01X473535Y406107D02*
X474205Y405757D01*
Y404887D01*
X473535Y404537D01*
X473360D01*
Y406107D01*
X473535D01*
G37*
G36*
G01X473248Y413023D02*
X474008Y412673D01*
Y411773D01*
X473248Y411423D01*
X473073D01*
Y413023D01*
X473248D01*
G37*
G36*
G01X473535Y410007D02*
X474205Y409657D01*
Y408787D01*
X473535Y408437D01*
X473360D01*
Y410007D01*
X473535D01*
G37*
G36*
G01X473248Y416923D02*
X474008Y416573D01*
Y415673D01*
X473248Y415323D01*
X473073D01*
Y416923D01*
X473248D01*
G37*
G36*
G01X433673Y412823D02*
X434458Y413113D01*
X435094Y412477D01*
X434804Y411692D01*
X434681Y411568D01*
X433549Y412700D01*
X433673Y412823D01*
G37*
G36*
G01X436431Y410065D02*
X437216Y410355D01*
X437852Y409719D01*
X437562Y408934D01*
X437439Y408810D01*
X436307Y409942D01*
X436431Y410065D01*
G37*
G36*
G01X432705Y416129D02*
X433465Y415779D01*
Y414879D01*
X432705Y414529D01*
X432530Y414528D01*
Y416129D01*
X432705D01*
G37*
G36*
G01X439207Y405970D02*
X439967Y405620D01*
Y404720D01*
X439207Y404370D01*
X439033D01*
Y405971D01*
X439207Y405970D01*
G37*
G36*
G01X465970Y410579D02*
X466730Y410229D01*
Y409329D01*
X465970Y408979D01*
X465795D01*
Y410579D01*
X465970D01*
G37*
G36*
G01X466774Y406105D02*
X467444Y405755D01*
Y404885D01*
X466774Y404535D01*
X466599D01*
Y406105D01*
X466774D01*
G37*
G36*
G01X442740Y403055D02*
X441955Y402765D01*
X441319Y403401D01*
X441609Y404186D01*
X441732Y404310D01*
X442864Y403179D01*
X442740Y403055D01*
G37*
G36*
G01X440885Y409720D02*
X440100Y409430D01*
X439464Y410067D01*
X439754Y410852D01*
X439877Y410975D01*
X441009Y409844D01*
X440885Y409720D01*
G37*
G36*
G01X441410Y406585D02*
X440650Y406935D01*
Y407835D01*
X441410Y408185D01*
X441585D01*
Y406585D01*
X441410D01*
G37*
G36*
G01X438823Y414581D02*
X438063Y414931D01*
Y415831D01*
X438823Y416181D01*
X438998D01*
Y414581D01*
X438823D01*
G37*
G36*
G01X468531Y404537D02*
X467861Y404887D01*
Y405757D01*
X468531Y406107D01*
X468706D01*
Y404537D01*
X468531D01*
G37*
G36*
G01Y413918D02*
X467771Y414268D01*
Y415168D01*
X468531Y415518D01*
X468706D01*
Y413918D01*
X468531D01*
G37*
G36*
G01Y410018D02*
X467771Y410368D01*
Y411268D01*
X468531Y411618D01*
X468706D01*
Y410018D01*
X468531D01*
G37*
G36*
G01X434026Y410914D02*
X433242Y410624D01*
X432605Y411261D01*
X432895Y412045D01*
X433019Y412169D01*
X434150Y411038D01*
X434026Y410914D01*
G37*
G36*
G01X436784Y408156D02*
X436000Y407866D01*
X435363Y408503D01*
X435653Y409287D01*
X435777Y409411D01*
X436908Y408280D01*
X436784Y408156D01*
G37*
G36*
G01X431605Y414529D02*
X430845Y414878D01*
Y415779D01*
X431605Y416129D01*
X431780D01*
Y414529D01*
X431605D01*
G37*
G36*
G01X438107Y404370D02*
X437348Y404720D01*
Y405621D01*
X438107Y405970D01*
X438282D01*
Y404370D01*
X438107D01*
G37*
G36*
G01X464870Y408979D02*
X464110Y409329D01*
Y410229D01*
X464870Y410579D01*
X465045D01*
Y408979D01*
X464870D01*
G37*
G36*
G01X440531Y411629D02*
X441316Y411919D01*
X441953Y411283D01*
X441663Y410498D01*
X441539Y410374D01*
X440408Y411506D01*
X440531Y411629D01*
G37*
G36*
G01X442510Y408185D02*
X443270Y407835D01*
Y406935D01*
X442510Y406585D01*
X442335D01*
Y408185D01*
X442510D01*
G37*
G36*
G01X439923Y416181D02*
X440683Y415831D01*
Y414931D01*
X439923Y414581D01*
X439748D01*
Y416181D01*
X439923D01*
G37*
G36*
G01X470155Y408106D02*
X470825Y407756D01*
Y406886D01*
X470155Y406536D01*
X469980D01*
Y408106D01*
X470155D01*
G37*
G36*
G01X469631Y415518D02*
X470391Y415168D01*
Y414268D01*
X469631Y413918D01*
X469456D01*
Y415518D01*
X469631D01*
G37*
G36*
G01Y411618D02*
X470391Y411268D01*
Y410368D01*
X469631Y410018D01*
X469456D01*
Y411618D01*
X469631D01*
G37*
G36*
G01X482589Y200052D02*
X481805Y199762D01*
X481168Y200399D01*
X481458Y201183D01*
X481582Y201307D01*
X482713Y200176D01*
X482589Y200052D01*
G37*
G36*
G01X479789Y202852D02*
X479005Y202562D01*
X478368Y203199D01*
X478658Y203983D01*
X478782Y204107D01*
X479913Y202976D01*
X479789Y202852D01*
G37*
G36*
G01X482238Y201963D02*
X483023Y202253D01*
X483659Y201617D01*
X483369Y200832D01*
X483246Y200708D01*
X482114Y201840D01*
X482238Y201963D01*
G37*
G36*
G01X479438Y204763D02*
X480223Y205053D01*
X480859Y204417D01*
X480569Y203632D01*
X480446Y203508D01*
X479314Y204640D01*
X479438Y204763D01*
G37*
G36*
G01X493889Y209450D02*
X493104Y209160D01*
X492468Y209796D01*
X492758Y210581D01*
X492881Y210705D01*
X494013Y209573D01*
X493889Y209450D01*
G37*
G36*
G01X491283Y213476D02*
X490523Y213826D01*
Y214726D01*
X491283Y215076D01*
X491458D01*
Y213476D01*
X491283D01*
G37*
G36*
G01Y217376D02*
X490523Y217726D01*
Y218626D01*
X491283Y218976D01*
X491458D01*
Y217376D01*
X491283D01*
G37*
G36*
G01X494536Y210359D02*
X495321Y210649D01*
X495957Y210013D01*
X495667Y209228D01*
X495544Y209104D01*
X494412Y210236D01*
X494536Y210359D01*
G37*
G36*
G01X492383Y215076D02*
X493143Y214726D01*
Y213826D01*
X492383Y213476D01*
X492208D01*
Y215076D01*
X492383D01*
G37*
G36*
G01Y218976D02*
X493143Y218626D01*
Y217726D01*
X492383Y217376D01*
X492208D01*
Y218976D01*
X492383D01*
G37*
G36*
G01X488263Y211726D02*
X487503Y212076D01*
Y212976D01*
X488263Y213326D01*
X488438D01*
Y211726D01*
X488263D01*
G37*
G36*
G01X493230Y205840D02*
X492445Y205551D01*
X491809Y206187D01*
X492099Y206972D01*
X492222Y207096D01*
X493354Y205964D01*
X493230Y205840D01*
G37*
G36*
G01X490430Y208640D02*
X489645Y208351D01*
X489009Y208987D01*
X489299Y209772D01*
X489422Y209896D01*
X490554Y208764D01*
X490430Y208640D01*
G37*
G36*
G01X488263Y215626D02*
X487503Y215976D01*
Y216876D01*
X488263Y217226D01*
X488438D01*
Y215626D01*
X488263D01*
G37*
G36*
G01X485359Y218353D02*
X485418Y217599D01*
X484680Y217138D01*
X484028Y217520D01*
X483936Y217669D01*
X485267Y218501D01*
X485359Y218353D01*
G37*
G36*
G01X492871Y207756D02*
X493656Y208046D01*
X494293Y207409D01*
X494003Y206624D01*
X493879Y206500D01*
X492748Y207632D01*
X492871Y207756D01*
G37*
G36*
G01X490071Y210556D02*
X490856Y210846D01*
X491493Y210209D01*
X491203Y209424D01*
X491079Y209300D01*
X489948Y210432D01*
X490071Y210556D01*
G37*
G36*
G01X489363Y213326D02*
X490123Y212976D01*
Y212076D01*
X489363Y211726D01*
X489188D01*
Y213326D01*
X489363D01*
G37*
G36*
G01Y217226D02*
X490123Y216876D01*
Y215976D01*
X489363Y215626D01*
X489188D01*
Y217226D01*
X489363D01*
G37*
G36*
G01X483292Y206232D02*
X484076Y206522D01*
X484713Y205885D01*
X484423Y205101D01*
X484299Y204977D01*
X483168Y206108D01*
X483292Y206232D01*
G37*
G36*
G01X482554Y211131D02*
X483224Y210781D01*
Y209911D01*
X482554Y209561D01*
X482379D01*
Y211131D01*
X482554D01*
G37*
G36*
G01X480645Y212892D02*
X481283Y213297D01*
X482036Y212862D01*
X482004Y212107D01*
X481917Y211955D01*
X480557Y212741D01*
X480645Y212892D01*
G37*
G36*
G01X479173Y216960D02*
X479843Y216610D01*
Y215740D01*
X479173Y215390D01*
X478998D01*
X478997Y216960D01*
X479173D01*
G37*
G36*
G01X486092Y203432D02*
X486876Y203722D01*
X487513Y203085D01*
X487223Y202301D01*
X487099Y202177D01*
X485968Y203308D01*
X486092Y203432D01*
G37*
G36*
G01X482830Y213656D02*
X482192Y213251D01*
X481439Y213686D01*
X481471Y214441D01*
X481558Y214593D01*
X482918Y213807D01*
X482830Y213656D01*
G37*
G36*
G01X484310Y209581D02*
X483640Y209931D01*
Y210801D01*
X484310Y211151D01*
X484485D01*
Y209581D01*
X484310D01*
G37*
G36*
G01X487330Y206422D02*
X486545Y206132D01*
X485909Y206768D01*
X486199Y207553D01*
X486322Y207677D01*
X487454Y206545D01*
X487330Y206422D01*
G37*
G36*
G01X483645Y204323D02*
X482860Y204033D01*
X482224Y204669D01*
X482514Y205454D01*
X482637Y205578D01*
X483769Y204446D01*
X483645Y204323D01*
G37*
G36*
G01X479459Y211701D02*
X478821Y211296D01*
X478068Y211731D01*
X478100Y212486D01*
X478187Y212637D01*
X479547Y211853D01*
X479459Y211701D01*
G37*
G36*
G01X480930Y207611D02*
X480260Y207961D01*
Y208831D01*
X480930Y209181D01*
X481105D01*
Y207611D01*
X480930D01*
G37*
G36*
G01X486445Y201523D02*
X485660Y201233D01*
X485024Y201869D01*
X485314Y202654D01*
X485437Y202778D01*
X486569Y201646D01*
X486445Y201523D01*
G37*
G36*
G01X484040Y214833D02*
X484678Y215238D01*
X485431Y214803D01*
X485399Y214048D01*
X485312Y213896D01*
X483952Y214681D01*
X484040Y214833D01*
G37*
G36*
G01X486977Y208331D02*
X487761Y208621D01*
X488398Y207984D01*
X488108Y207200D01*
X487984Y207076D01*
X486853Y208207D01*
X486977Y208331D01*
G37*
G36*
G01X485934Y213081D02*
X486604Y212731D01*
Y211861D01*
X485934Y211511D01*
X485759D01*
Y213081D01*
X485934D01*
G37*
G36*
G01X486231Y223362D02*
X485579Y222979D01*
X484841Y223441D01*
X484900Y224193D01*
X484992Y224343D01*
X486324Y223510D01*
X486231Y223362D01*
G37*
G36*
G01X490689Y221722D02*
X489905Y221432D01*
X489268Y222069D01*
X489558Y222853D01*
X489682Y222977D01*
X490813Y221846D01*
X490689Y221722D01*
G37*
G36*
G01X490336Y223631D02*
X491121Y223921D01*
X491757Y223285D01*
X491467Y222500D01*
X491344Y222376D01*
X490212Y223508D01*
X490336Y223631D01*
G37*
G36*
G01X485934Y228706D02*
X486604Y228356D01*
Y227486D01*
X485934Y227136D01*
X485759D01*
Y228706D01*
X485934D01*
G37*
G36*
G01X484851Y219902D02*
X484819Y220657D01*
X485572Y221092D01*
X486210Y220687D01*
X486298Y220536D01*
X484938Y219751D01*
X484851Y219902D01*
G37*
G36*
G01X480930Y223236D02*
X480260Y223586D01*
Y224456D01*
X480930Y224806D01*
X481105D01*
Y223236D01*
X480930D01*
G37*
G36*
G01Y219336D02*
X480260Y219686D01*
Y220556D01*
X480930Y220906D01*
X481105D01*
Y219336D01*
X480930D01*
G37*
G36*
G01X482554Y222807D02*
X483224Y222457D01*
Y221587D01*
X482554Y221237D01*
X482379D01*
Y222807D01*
X482554D01*
G37*
G36*
G01Y226707D02*
X483224Y226357D01*
Y225487D01*
X482554Y225137D01*
X482379D01*
Y226707D01*
X482554D01*
G37*
G36*
G01X586205Y182480D02*
X564006Y204679D01*
X564081Y204812D01*
G03X562584Y206877I-1220J691D01*
G02X562113Y207348I-79J392D01*
G03X560048Y208845I-1374J277D01*
G01X559915Y208770D01*
X557690Y210995D01*
X553613Y213170D01*
G02X553435Y213683I188J353D01*
G03X550968Y214999I-1284J564D01*
G02X550442Y214861I-337J215D01*
G01X550177Y215003D01*
G02X550011Y215542I188J353D01*
G03X547537Y216862I-1240J654D01*
G02X546997Y216699I-352J190D01*
G01X546732Y216840D01*
G02X546580Y217405I188J353D01*
G03X544112Y218721I-1189J743D01*
G02X543559Y218532I-365J164D01*
G01X543279Y218682D01*
G02X543144Y219270I188J353D01*
G03X540694Y220577I-1133J826D01*
G02X540130Y220361I-376J137D01*
G01X539817Y220528D01*
G02X539700Y221140I188J353D01*
G03X537244Y222251I-1069J907D01*
G01X537219Y222080D01*
X536846D01*
Y222904D01*
X537142Y223200D01*
Y224504D01*
X535957Y225689D01*
X534283D01*
X532403Y227569D01*
X530862D01*
X529780Y228651D01*
Y231244D01*
X529794Y231280D01*
G03Y232314I-1303J517D01*
G01X529780Y232350D01*
Y235143D01*
X529794Y235179D01*
G03Y236213I-1303J517D01*
G01X529780Y236249D01*
Y239043D01*
X529794Y239079D01*
G03Y240113I-1303J517D01*
G01X529780Y240149D01*
Y242943D01*
X529794Y242979D01*
G03Y244013I-1303J517D01*
G01X529780Y244049D01*
Y246843D01*
X529794Y246879D01*
G03Y247913I-1303J517D01*
G01X529780Y247949D01*
Y250743D01*
X529794Y250779D01*
G03Y251813I-1303J517D01*
G01X529780Y251849D01*
Y254643D01*
X529794Y254679D01*
G03Y255713I-1303J517D01*
G01X529780Y255749D01*
Y258543D01*
X529794Y258579D01*
G03Y259613I-1303J517D01*
G01X529780Y259649D01*
Y262443D01*
X529794Y262479D01*
G03Y263513I-1303J517D01*
G01X529780Y263549D01*
Y266343D01*
X529794Y266379D01*
G03Y267413I-1303J517D01*
G01X529780Y267449D01*
Y269673D01*
X530594Y270487D01*
Y271102D01*
X530224Y271472D01*
X530209D01*
X529920Y271761D01*
Y277775D01*
X530758Y278613D01*
Y278892D01*
G02X531316Y279259I400J0D01*
G03X533267Y280418I555J1288D01*
G01X533284Y280600D01*
X537218D01*
X537235Y280418D01*
G03X540027I1396J129D01*
G01X540044Y280600D01*
X542000D01*
X542406Y280194D01*
X542200Y279988D01*
X542109Y279995D01*
G03X543175Y279377I-99J-1399D01*
G02X543507Y280000I332J223D01*
G01X544094D01*
X544151Y279893D01*
G03X545283Y279149I1240J654D01*
G01X545357Y279143D01*
X548035Y276465D01*
G02X547978Y275852I-283J-283D01*
G03X549927Y273903I793J-1156D01*
G02X550540Y273960I330J-226D01*
G01X550975Y273525D01*
X550908Y273395D01*
G03X553497Y272356I1243J-649D01*
G01X553539Y272500D01*
X554287D01*
G02X554563Y271811I0J-400D01*
G03X556926Y270652I968J-1015D01*
G02X557606Y270894I398J-41D01*
G01X558011Y270489D01*
G02X557991Y269905I-283J-283D01*
G03X559969Y267927I920J-1058D01*
G02X560553Y267947I301J-263D01*
G01X563189Y265311D01*
X563155Y265197D01*
G03X564897Y263455I1345J-397D01*
G01X565011Y263489D01*
X575290Y253210D01*
Y204220D01*
X590660Y188850D01*
Y184780D01*
X588360Y182480D01*
X586205D01*
G37*
G36*
G01X528800Y300200D02*
X526100Y302900D01*
X522803D01*
G03X520659I-1072J-904D01*
G01X520207D01*
X520158Y302931D01*
G03X518454Y303448I-1805J-2884D01*
G01X518282D01*
X518250D01*
G03X516546Y302931I101J-3401D01*
G01X516497Y302900D01*
X516100D01*
X513400Y305600D01*
X510111D01*
G02X509712Y305978I0J400D01*
G03X508900Y307231I-1500J-82D01*
G01Y308575D01*
G03Y311019I-688J1222D01*
G01Y312474D01*
G03Y314918I-688J1222D01*
G01Y316374D01*
G03X509226Y318564I-688J1222D01*
G01X509091Y318705D01*
X509612Y319225D01*
G02X510271Y319077I283J-283D01*
G03X512993Y319506I1321J470D01*
G01X512999Y319700D01*
X516945D01*
X516951Y319506D01*
G03X519753I1401J41D01*
G01X519759Y319700D01*
X523704D01*
X523710Y319506D01*
G03X526512I1401J41D01*
G01X526518Y319700D01*
X530464D01*
X530470Y319506D01*
G03X533268Y319667I1401J41D01*
G01X533260Y319760D01*
X534130Y320630D01*
X534272Y320493D01*
G03X536642Y321324I979J1003D01*
G01X536664Y321500D01*
X540598D01*
X540620Y321324D01*
G03X543402I1391J172D01*
G01X543424Y321500D01*
X547358D01*
X547380Y321324D01*
G03X547938Y322623I1391J172D01*
G02X547300Y322945I-238J322D01*
G01Y324200D01*
X547642Y324542D01*
X547783Y324401D01*
G03X549766Y326384I988J995D01*
G02Y326666I142J141D01*
G01X550159Y327059D01*
G02X550821Y326903I283J-283D01*
G03X551800Y328704I1330J444D01*
G02X551300Y329092I-100J387D01*
G01Y329502D01*
G02X551800Y329890I400J1D01*
G03Y332604I351J1357D01*
G02X551300Y332992I-100J387D01*
G01Y333402D01*
G02X551800Y333790I400J1D01*
G03Y336504I351J1357D01*
G02X551300Y336892I-100J387D01*
G01Y337302D01*
G02X551800Y337690I400J1D01*
G03Y340404I351J1357D01*
G02X551300Y340792I-100J387D01*
G01Y341202D01*
G02X551800Y341590I400J1D01*
G03Y344304I351J1357D01*
G02X551300Y344692I-100J387D01*
G01Y345102D01*
G02X551800Y345490I400J1D01*
G03Y348204I351J1357D01*
G02X551300Y348592I-100J387D01*
G01Y349002D01*
G02X551800Y349390I400J1D01*
G03X551342Y351892I351J1357D01*
G01X551205Y351795D01*
X550168Y352832D01*
X550158Y352898D01*
G03X548973Y354083I-1387J-202D01*
G01X548907Y354093D01*
X548489Y354511D01*
G02X548771Y355194I283J283D01*
G03X547369Y356596I0J1402D01*
G02X546686Y356314I-400J1D01*
G01X546183Y356817D01*
G02X546227Y357421I282J283D01*
G03X545242Y359941I-836J1126D01*
G02X544800Y360339I-42J398D01*
G01Y360655D01*
G02X545242Y361053I400J0D01*
G03Y363841I149J1394D01*
G02X544800Y364239I-42J398D01*
G01Y364555D01*
G02X545242Y364953I400J0D01*
G03Y367741I149J1394D01*
G02X544800Y368139I-42J398D01*
G01Y368455D01*
G02X545242Y368853I400J0D01*
G03Y371641I149J1394D01*
G02X544800Y372039I-42J398D01*
G01Y372354D01*
G02X545242Y372752I400J0D01*
G03Y375540I149J1394D01*
G02X544800Y375938I-42J398D01*
G01Y376255D01*
G02X545242Y376653I400J0D01*
G03Y379441I149J1394D01*
G02X544800Y379839I-42J398D01*
G01Y380155D01*
G02X545242Y380553I400J0D01*
G03Y383341I149J1394D01*
G02X544800Y383739I-42J398D01*
G01Y384055D01*
G02X545242Y384453I400J0D01*
G03Y387241I149J1394D01*
G02X544800Y387639I-42J398D01*
G01Y387955D01*
G02X545242Y388353I400J0D01*
G03Y391141I149J1394D01*
G02X544800Y391539I-42J398D01*
G01Y391855D01*
G02X545242Y392253I400J0D01*
G03Y395041I149J1394D01*
G02X544800Y395439I-42J398D01*
G01Y395754D01*
G02X545242Y396152I400J0D01*
G03Y398940I149J1394D01*
G02X544800Y399338I-42J398D01*
G01Y409500D01*
X566100Y430800D01*
X625000D01*
X631000Y424800D01*
Y402200D01*
X621250Y392450D01*
Y308150D01*
X613300Y300200D01*
X556970D01*
G02X556717Y300910I0J400D01*
G03X554945I-886J1086D01*
G02X554692Y300200I-253J-310D01*
G01X553554D01*
X553519Y300356D01*
G03X550783I-1368J-309D01*
G01X550748Y300200D01*
X549910D01*
G02X549657Y300910I0J400D01*
G03X547885I-886J1086D01*
G02X547632Y300200I-253J-310D01*
G01X546794D01*
X546759Y300356D01*
G03X544023I-1368J-309D01*
G01X543988Y300200D01*
X543150D01*
G02X542897Y300910I0J400D01*
G03X541125I-886J1086D01*
G02X540872Y300200I-253J-310D01*
G01X540034D01*
X539999Y300356D01*
G03X537263I-1368J-309D01*
G01X537228Y300200D01*
X536390D01*
G02X536137Y300910I0J400D01*
G03X534365I-886J1086D01*
G02X534112Y300200I-253J-310D01*
G01X533274D01*
X533239Y300356D01*
G03X530503I-1368J-309D01*
G01X530468Y300200D01*
X528800D01*
G37*
G36*
G01X482572Y401777D02*
X481812Y402127D01*
X481813Y403027D01*
X482573Y403377D01*
X482748D01*
Y401777D01*
X482572D01*
G37*
G36*
G01Y397877D02*
X481812Y398227D01*
X481813Y399127D01*
X482573Y399477D01*
X482748D01*
Y397877D01*
X482572D01*
G37*
G36*
G01X482050Y392837D02*
X481380Y393187D01*
Y394057D01*
X482050Y394407D01*
X482225D01*
Y392837D01*
X482050D01*
G37*
G36*
G01Y388937D02*
X481380Y389287D01*
Y390157D01*
X482050Y390507D01*
X482225D01*
Y388937D01*
X482050D01*
G37*
G36*
G01X483672Y401932D02*
X484433Y401582D01*
X484432Y400682D01*
X483672Y400332D01*
X483497Y400333D01*
Y401932D01*
X483672D01*
G37*
G36*
G01Y398032D02*
X484433Y397682D01*
X484432Y396782D01*
X483672Y396432D01*
X483497Y396433D01*
Y398032D01*
X483672D01*
G37*
G36*
G01X478670Y387036D02*
X478000Y387386D01*
Y388256D01*
X478670Y388606D01*
X478845D01*
Y387036D01*
X478670D01*
G37*
G36*
G01X479721Y399612D02*
X478961Y399962D01*
Y400862D01*
X479722Y401212D01*
X479896D01*
Y399612D01*
X479721D01*
G37*
G36*
G01X478670Y390936D02*
X478000Y391286D01*
Y392156D01*
X478670Y392506D01*
X478845D01*
Y390936D01*
X478670D01*
G37*
G36*
G01Y394836D02*
X478000Y395186D01*
Y396056D01*
X478670Y396406D01*
X478845D01*
Y394836D01*
X478670D01*
G37*
G36*
G01X480294Y390507D02*
X480964Y390157D01*
Y389287D01*
X480294Y388937D01*
X480119D01*
Y390507D01*
X480294D01*
G37*
G36*
G01X480822Y401267D02*
X481583Y400917D01*
X481582Y400017D01*
X480822Y399667D01*
X480647Y399668D01*
Y401267D01*
X480822D01*
G37*
G36*
G01X480294Y394407D02*
X480964Y394057D01*
Y393187D01*
X480294Y392837D01*
X480119D01*
Y394407D01*
X480294D01*
G37*
G36*
G01X492190Y398711D02*
X491520Y399061D01*
Y399931D01*
X492190Y400281D01*
X492365D01*
Y398711D01*
X492190D01*
G37*
G36*
G01X487054Y402207D02*
X487724Y401857D01*
Y400987D01*
X487054Y400637D01*
X486879D01*
Y402207D01*
X487054D01*
G37*
G36*
G01Y398356D02*
X487724Y398006D01*
Y397136D01*
X487054Y396786D01*
X486879D01*
Y398356D01*
X487054D01*
G37*
G36*
G01Y394432D02*
X487724Y394082D01*
Y393212D01*
X487054Y392862D01*
X486879D01*
Y394432D01*
X487054D01*
G37*
G36*
G01X488810Y396786D02*
X488140Y397136D01*
Y398006D01*
X488810Y398356D01*
X488985D01*
Y396786D01*
X488810D01*
G37*
G36*
G01Y392862D02*
X488140Y393212D01*
Y394082D01*
X488810Y394432D01*
X488985D01*
Y392862D01*
X488810D01*
G37*
G36*
G01X485430Y398711D02*
X484760Y399061D01*
Y399931D01*
X485430Y400281D01*
X485605D01*
Y398711D01*
X485430D01*
G37*
G36*
G01Y394787D02*
X484760Y395137D01*
Y396007D01*
X485430Y396357D01*
X485605D01*
Y394787D01*
X485430D01*
G37*
G36*
G01Y390887D02*
X484760Y391237D01*
Y392107D01*
X485430Y392457D01*
X485605D01*
Y390887D01*
X485430D01*
G37*
G36*
G01Y402636D02*
X484760Y402986D01*
Y403856D01*
X485430Y404206D01*
X485605D01*
Y402636D01*
X485430D01*
G37*
G36*
G01X490434Y400281D02*
X491104Y399931D01*
Y399061D01*
X490434Y398711D01*
X490259D01*
Y400281D01*
X490434D01*
G37*
G36*
G01Y396357D02*
X491104Y396007D01*
Y395137D01*
X490434Y394787D01*
X490259D01*
Y396357D01*
X490434D01*
G37*
G36*
G01X490432Y392452D02*
X491102Y392102D01*
Y391232D01*
X490432Y390882D01*
X490257D01*
Y392452D01*
X490432D01*
G37*
G36*
G01X485097Y409702D02*
X484807Y410487D01*
X485444Y411123D01*
X486229Y410833D01*
X486352Y410709D01*
X485221Y409578D01*
X485097Y409702D01*
G37*
G36*
G01X487855Y412460D02*
X487565Y413244D01*
X488202Y413881D01*
X488986Y413591D01*
X489110Y413467D01*
X487979Y412336D01*
X487855Y412460D01*
G37*
G36*
G01X490613Y415217D02*
X490323Y416002D01*
X490959Y416639D01*
X491744Y416349D01*
X491868Y416225D01*
X490737Y415094D01*
X490613Y415217D01*
G37*
G36*
G01X493413Y418017D02*
X493123Y418802D01*
X493759Y419439D01*
X494544Y419149D01*
X494668Y419025D01*
X493537Y417894D01*
X493413Y418017D01*
G37*
G36*
G01X487007Y410055D02*
X487297Y409270D01*
X486660Y408634D01*
X485875Y408924D01*
X485752Y409048D01*
X486883Y410179D01*
X487007Y410055D01*
G37*
G36*
G01X489764Y412813D02*
X490054Y412028D01*
X489418Y411392D01*
X488633Y411682D01*
X488509Y411805D01*
X489641Y412937D01*
X489764Y412813D01*
G37*
G36*
G01X492522Y415571D02*
X492812Y414786D01*
X492176Y414149D01*
X491391Y414439D01*
X491267Y414563D01*
X492398Y415694D01*
X492522Y415571D01*
G37*
G36*
G01X495322Y418371D02*
X495612Y417586D01*
X494976Y416949D01*
X494191Y417239D01*
X494067Y417363D01*
X495198Y418494D01*
X495322Y418371D01*
G37*
G36*
G01X500286Y405523D02*
X500636Y406283D01*
X501536D01*
X501886Y405523D01*
Y405348D01*
X500286D01*
Y405523D01*
G37*
G36*
G01X504186D02*
X504536Y406283D01*
X505436D01*
X505786Y405523D01*
Y405348D01*
X504186D01*
Y405523D01*
G37*
G36*
G01X508086D02*
X508436Y406283D01*
X509336D01*
X509686Y405523D01*
Y405348D01*
X508086D01*
Y405523D01*
G37*
G36*
G01X511775Y406338D02*
X511485Y407123D01*
X512121Y407759D01*
X512906Y407469D01*
X513030Y407346D01*
X511898Y406214D01*
X511775Y406338D01*
G37*
G36*
G01X514575Y409138D02*
X514285Y409923D01*
X514921Y410559D01*
X515706Y410269D01*
X515830Y410146D01*
X514698Y409014D01*
X514575Y409138D01*
G37*
G36*
G01X518388Y411275D02*
X518738Y412035D01*
X519638D01*
X519988Y411275D01*
Y411100D01*
X518388D01*
Y411275D01*
G37*
G36*
G01X501886Y404423D02*
X501536Y403663D01*
X500636D01*
X500286Y404423D01*
Y404598D01*
X501886D01*
Y404423D01*
G37*
G36*
G01X505786D02*
X505436Y403663D01*
X504536D01*
X504186Y404423D01*
Y404598D01*
X505786D01*
Y404423D01*
G37*
G36*
G01X513684Y406691D02*
X513974Y405906D01*
X513338Y405270D01*
X512553Y405560D01*
X512429Y405683D01*
X513561Y406815D01*
X513684Y406691D01*
G37*
G36*
G01X509686Y404423D02*
X509336Y403663D01*
X508436D01*
X508086Y404423D01*
Y404598D01*
X509686D01*
Y404423D01*
G37*
G36*
G01X516484Y409491D02*
X516774Y408706D01*
X516138Y408070D01*
X515353Y408360D01*
X515229Y408483D01*
X516361Y409615D01*
X516484Y409491D01*
G37*
G36*
G01X520169Y410175D02*
X519819Y409415D01*
X518919D01*
X518569Y410175D01*
Y410350D01*
X520169D01*
Y410175D01*
G37*
G36*
G01X479204Y406153D02*
X478444Y406503D01*
Y407403D01*
X479205Y407753D01*
X479379D01*
Y406153D01*
X479204D01*
G37*
G36*
G01X481966Y412833D02*
X481676Y413618D01*
X482313Y414254D01*
X483098Y413964D01*
X483221Y413840D01*
X482090Y412709D01*
X481966Y412833D01*
G37*
G36*
G01X484724Y415591D02*
X484434Y416375D01*
X485071Y417012D01*
X485855Y416722D01*
X485979Y416598D01*
X484848Y415467D01*
X484724Y415591D01*
G37*
G36*
G01X487482Y418348D02*
X487192Y419133D01*
X487828Y419770D01*
X488613Y419480D01*
X488737Y419356D01*
X487606Y418225D01*
X487482Y418348D01*
G37*
G36*
G01X480304Y407811D02*
X481065Y407461D01*
X481064Y406561D01*
X480304Y406211D01*
X480129Y406212D01*
Y407811D01*
X480304D01*
G37*
G36*
G01X483876Y413186D02*
X484166Y412401D01*
X483529Y411765D01*
X482744Y412055D01*
X482621Y412179D01*
X483752Y413310D01*
X483876Y413186D01*
G37*
G36*
G01X489391Y418702D02*
X489681Y417917D01*
X489045Y417280D01*
X488260Y417570D01*
X488136Y417694D01*
X489267Y418825D01*
X489391Y418702D01*
G37*
G36*
G01X486633Y415944D02*
X486923Y415159D01*
X486287Y414523D01*
X485502Y414813D01*
X485378Y414936D01*
X486510Y416068D01*
X486633Y415944D01*
G37*
G36*
G01X494214Y405534D02*
X493924Y406318D01*
X494561Y406955D01*
X495345Y406665D01*
X495469Y406541D01*
X494338Y405410D01*
X494214Y405534D01*
G37*
G36*
G01X505962Y408375D02*
X506312Y409135D01*
X507212D01*
X507562Y408375D01*
Y408200D01*
X505962D01*
Y408375D01*
G37*
G36*
G01X502062D02*
X502412Y409135D01*
X503312D01*
X503662Y408375D01*
Y408200D01*
X502062D01*
Y408375D01*
G37*
G36*
G01X510448Y409215D02*
X510158Y410000D01*
X510794Y410636D01*
X511579Y410346D01*
X511703Y410223D01*
X510571Y409091D01*
X510448Y409215D01*
G37*
G36*
G01X513205Y411973D02*
X512915Y412758D01*
X513552Y413394D01*
X514337Y413104D01*
X514460Y412980D01*
X513329Y411849D01*
X513205Y411973D01*
G37*
G36*
G01X518736Y415575D02*
X519086Y416335D01*
X519986D01*
X520336Y415575D01*
Y415400D01*
X518736D01*
Y415575D01*
G37*
G36*
G01X496124Y405886D02*
X496414Y405102D01*
X495777Y404465D01*
X494993Y404755D01*
X494869Y404879D01*
X496000Y406010D01*
X496124Y405886D01*
G37*
G36*
G01X507562Y407275D02*
X507212Y406515D01*
X506312D01*
X505962Y407275D01*
Y407450D01*
X507562D01*
Y407275D01*
G37*
G36*
G01X503662D02*
X503312Y406515D01*
X502412D01*
X502062Y407275D01*
Y407450D01*
X503662D01*
Y407275D01*
G37*
G36*
G01X515157Y412368D02*
X515447Y411583D01*
X514811Y410947D01*
X514026Y411237D01*
X513902Y411360D01*
X515034Y412492D01*
X515157Y412368D01*
G37*
G36*
G01X512357Y409568D02*
X512647Y408783D01*
X512011Y408147D01*
X511226Y408437D01*
X511102Y408560D01*
X512234Y409692D01*
X512357Y409568D01*
G37*
G36*
G01X520336Y414475D02*
X519986Y413715D01*
X519086D01*
X518736Y414475D01*
Y414650D01*
X520336D01*
Y414475D01*
G37*
G36*
G01X492252Y410400D02*
X492542Y409616D01*
X491905Y408979D01*
X491121Y409269D01*
X490997Y409393D01*
X492128Y410524D01*
X492252Y410400D01*
G37*
G36*
G01X489452Y407600D02*
X489742Y406816D01*
X489105Y406179D01*
X488321Y406469D01*
X488197Y406593D01*
X489328Y407724D01*
X489452Y407600D01*
G37*
G36*
G01X498762Y413075D02*
X498412Y412315D01*
X497512D01*
X497162Y413075D01*
Y413250D01*
X498762D01*
Y413075D01*
G37*
G36*
G01X504511Y415822D02*
X504801Y415037D01*
X504165Y414401D01*
X503380Y414691D01*
X503256Y414814D01*
X504388Y415946D01*
X504511Y415822D01*
G37*
G36*
G01X491164Y406584D02*
X490874Y407368D01*
X491511Y408005D01*
X492295Y407715D01*
X492419Y407591D01*
X491288Y406460D01*
X491164Y406584D01*
G37*
G36*
G01X493964Y409384D02*
X493674Y410168D01*
X494311Y410805D01*
X495095Y410515D01*
X495219Y410391D01*
X494088Y409260D01*
X493964Y409384D01*
G37*
G36*
G01X498662Y411251D02*
X499012Y412011D01*
X499912D01*
X500262Y411251D01*
Y411076D01*
X498662D01*
Y411251D01*
G37*
G36*
G01X503777Y412294D02*
X503487Y413078D01*
X504124Y413715D01*
X504908Y413425D01*
X505032Y413301D01*
X503901Y412170D01*
X503777Y412294D01*
G37*
G36*
G01X490342Y410048D02*
X490052Y410832D01*
X490689Y411469D01*
X491473Y411179D01*
X491597Y411055D01*
X490466Y409924D01*
X490342Y410048D01*
G37*
G36*
G01X487542Y407248D02*
X487252Y408032D01*
X487889Y408669D01*
X488673Y408379D01*
X488797Y408255D01*
X487666Y407124D01*
X487542Y407248D01*
G37*
G36*
G01X497162Y414175D02*
X497512Y414935D01*
X498412D01*
X498762Y414175D01*
Y414000D01*
X497162D01*
Y414175D01*
G37*
G36*
G01X502602Y415469D02*
X502312Y416253D01*
X502949Y416890D01*
X503733Y416600D01*
X503857Y416476D01*
X502726Y415345D01*
X502602Y415469D01*
G37*
G36*
G01X493073Y406937D02*
X493363Y406152D01*
X492727Y405516D01*
X491942Y405806D01*
X491818Y405929D01*
X492950Y407061D01*
X493073Y406937D01*
G37*
G36*
G01X495873Y409737D02*
X496163Y408952D01*
X495527Y408316D01*
X494742Y408606D01*
X494618Y408729D01*
X495750Y409861D01*
X495873Y409737D01*
G37*
G36*
G01X500262Y410151D02*
X499912Y409391D01*
X499012D01*
X498662Y410151D01*
Y410326D01*
X500262D01*
Y410151D01*
G37*
G36*
G01X505686Y412647D02*
X505976Y411862D01*
X505340Y411226D01*
X504555Y411516D01*
X504431Y411639D01*
X505563Y412771D01*
X505686Y412647D01*
G37*
G36*
G01X580960Y234590D02*
G03I-600J0D01*
G37*
G36*
G01Y230060D02*
G03I-600J0D01*
G37*
G36*
G01X661800Y2900D02*
X660500Y4200D01*
Y12400D01*
X667500Y19400D01*
X678235D01*
G02X678612Y18868I0J-400D01*
G03X681260I1324J-462D01*
G02X681637Y19400I377J132D01*
G01X689830D01*
G03X689970I70J1400D01*
G01X692330D01*
G03X692470I70J1400D01*
G01X693445D01*
X694375Y18470D01*
Y13475D01*
X693900Y13000D01*
X682800D01*
X680154Y10354D01*
X676647D01*
X676324Y10030D01*
G02X675654Y10209I-283J282D01*
G03X673327Y10857I-1354J-362D01*
G02X672773I-277J288D01*
G03X670827I-973J-1010D01*
G02X670273I-277J288D01*
G03X669363Y8446I-973J-1010D01*
G02X669664Y7764I18J-399D01*
G01X668300Y6400D01*
Y4600D01*
X666600Y2900D01*
X661800D01*
G37*
G36*
G01X616757Y108339D02*
G03I-642J0D01*
G37*
G36*
G01X622842Y112200D02*
G03I-642J0D01*
G37*
G36*
G01X616809Y118627D02*
G03I-642J0D01*
G37*
G36*
G01X607586Y465997D02*
G03I-574J0D01*
G37*
G36*
G01X624234Y466746D02*
G03I-574J0D01*
G37*
G36*
G01X751175Y228689D02*
Y213039D01*
X736711Y198575D01*
X719125D01*
X717700Y200000D01*
X715800D01*
X714550Y198750D01*
X711250D01*
X709850Y200150D01*
X708350D01*
X707056Y198856D01*
X700056D01*
X699068Y199844D01*
Y211626D01*
X700212Y212770D01*
X708022D01*
X708892Y211900D01*
X715635D01*
X716029Y212294D01*
X716033Y212297D01*
G03X716147Y212411I-933J1047D01*
G01X716150Y212415D01*
X719700Y215965D01*
Y227330D01*
G03Y227470I-1400J70D01*
G01Y228800D01*
X718200Y230300D01*
X697300D01*
X696100Y231500D01*
Y235900D01*
X697400Y237200D01*
X722900D01*
X727237Y232863D01*
X747001D01*
X751175Y228689D01*
G37*
G36*
G01X705500Y523500D02*
X703144Y525856D01*
X684055D01*
X682306Y527605D01*
Y536012D01*
X683794Y537500D01*
X716700D01*
X719200Y540000D01*
X735648D01*
X738000Y537648D01*
Y533900D01*
X737500Y533400D01*
X732000D01*
X730950Y532350D01*
Y529150D01*
X726582Y524782D01*
X726483D01*
X725201Y523500D01*
X705500D01*
G37*
G36*
G01X811100Y206200D02*
X806200D01*
X804187Y204187D01*
X804050Y204283D01*
G03X801633Y203530I-916J-1314D01*
G01X801585Y203400D01*
X798299D01*
X798266Y203412D01*
G03X797168I-549J-1505D01*
G01X797135Y203400D01*
X785493D01*
X784960Y203933D01*
Y365758D01*
X785462Y366260D01*
X817817D01*
X818500Y365577D01*
Y209700D01*
X815700Y206900D01*
X811800D01*
X811100Y206200D01*
G37*
G36*
G01X786422Y402100D02*
X789374D01*
X790900Y400574D01*
X813234D01*
X818500Y395307D01*
Y369025D01*
X817739Y368264D01*
X785780D01*
X785100Y368944D01*
Y400778D01*
X786422Y402100D01*
G37*
G36*
G01X820608Y213900D02*
Y362622D01*
X823455Y365469D01*
X823582Y365410D01*
G03X825100Y365500I676J1453D01*
G01X826016D01*
G03X827700I842J1363D01*
G01X828616D01*
G03X830300I842J1363D01*
G01X831216D01*
G03X832900I842J1363D01*
G01X833816D01*
G03X835500I842J1363D01*
G01X836468D01*
G03X838258I895J1329D01*
G01X860597D01*
X897567Y328530D01*
X911986D01*
G02X912386Y328114I0J-400D01*
G03X915188I1401J-54D01*
G02X915588Y328530I400J16D01*
G01X919046D01*
G02X919446Y328114I0J-400D01*
G03X921285Y326728I1401J-54D01*
G01X921402Y326766D01*
X923960Y324208D01*
G02X923799Y323544I-283J-283D01*
G03X925562Y321781I428J-1335D01*
G02X926226Y321942I381J-122D01*
G01X926766Y321402D01*
X926624Y321260D01*
Y321259D01*
G03X928606Y319277I983J-999D01*
G01X928607D01*
X928749Y319419D01*
X929605Y318563D01*
X929594Y318467D01*
G03X932197Y317600I1393J-158D01*
G01X932773D01*
G02X933127Y317014I0J-400D01*
G03X935607I1240J-654D01*
G02X935961Y317600I354J186D01*
G01X936537D01*
G03X938957I1210J709D01*
G01X939533D01*
G02X939887Y317014I0J-400D01*
G03X942367I1240J-654D01*
G02X942721Y317600I354J186D01*
G01X943297D01*
G03X945717I1210J709D01*
G01X946293D01*
G02X946647Y317014I0J-400D01*
G03X949127I1240J-654D01*
G02X949481Y317600I354J186D01*
G01X950057D01*
G03X952477I1210J709D01*
G01X953053D01*
G02X953407Y317014I0J-400D01*
G03X955887I1240J-654D01*
G02X956241Y317600I354J186D01*
G01X956816D01*
G03X959236I1210J709D01*
G01X959812D01*
G02X960166Y317014I0J-400D01*
G03X962646I1240J-654D01*
G02X963000Y317600I354J186D01*
G01X963576D01*
G03X965996I1210J709D01*
G01X966572D01*
G02X966926Y317014I0J-400D01*
G03X969406I1240J-654D01*
G02X969760Y317600I354J186D01*
G01X970336D01*
G03X972756I1210J709D01*
G01X973332D01*
G02X973686Y317014I0J-400D01*
G03X976166I1240J-654D01*
G02X976520Y317600I354J186D01*
G01X977096D01*
G03X979516I1210J709D01*
G01X980092D01*
G02X980446Y317014I0J-400D01*
G03X982574Y317445I1240J-654D01*
G02X982545Y318037I254J309D01*
G01X982985Y318477D01*
G02X983667Y318220I283J-283D01*
G03X985155Y319708I1399J89D01*
G02X984898Y320390I26J399D01*
G01X985341Y320833D01*
X985396Y320846D01*
G03X986429Y321879I-330J1363D01*
G01X986442Y321934D01*
X987565Y323057D01*
X987700Y322973D01*
G03X989542Y325034I746J1187D01*
G01X989989Y325481D01*
G02X990617Y325401I283J-283D01*
G03X992535Y327319I1209J709D01*
G02X992455Y327947I203J345D01*
G01X995070Y330562D01*
X995157Y330559D01*
G03X996607Y332009I49J1401D01*
G01X996604Y332096D01*
X997370Y332862D01*
G02X997646Y332869I142J-141D01*
G03X999626Y334849I940J1040D01*
G01X999498Y334990D01*
X1000001Y335493D01*
G02X1000657Y335355I283J-283D01*
G03X1003199Y336525I1308J505D01*
G02X1003551Y337114I352J189D01*
G01X1003682D01*
X1003922Y337355D01*
X1004086Y337192D01*
X1004100Y337164D01*
G03X1006335Y338802I1245J645D01*
G01X1006811Y339277D01*
G02X1007456Y339165I283J-282D01*
G03X1009806Y340652I1270J594D01*
G02X1009819Y340921I155J127D01*
G01X1010170Y341272D01*
G02X1010820Y341149I283J-283D01*
G03X1013188Y342599I1285J560D01*
G01X1013073Y342739D01*
X1013552Y343219D01*
G02X1014201Y343097I283J-283D01*
G03X1016834Y344041I1284J563D01*
G02X1017219Y344550I385J109D01*
G01X1017946D01*
G03X1019784I919J1059D01*
G01X1023180D01*
X1023690Y344040D01*
X1027960D01*
X1028816Y344896D01*
X1030362D01*
X1031255Y345790D01*
X1035550D01*
X1038160Y348400D01*
X1051350D01*
X1053900Y345850D01*
Y345790D01*
X1054204D01*
X1054248Y345766D01*
G03X1055580I666J1234D01*
G01X1055624Y345790D01*
X1065350D01*
X1066070Y345070D01*
X1074173D01*
X1074190Y345067D01*
G03X1074714I262J1479D01*
G01X1074731Y345070D01*
X1074989D01*
G02X1075310Y344431I0J-400D01*
G03X1077560I1125J-836D01*
G02X1077881Y345070I321J239D01*
G01X1080933D01*
X1080950Y345067D01*
G03X1081474I262J1479D01*
G01X1081491Y345070D01*
X1084800D01*
X1100108Y329762D01*
Y325185D01*
G03X1099958Y325024I1094J-1170D01*
G02X1099647Y325025I-155J127D01*
G03X1097162Y325031I-1245J-1008D01*
G02X1096562Y325008I-310J253D01*
G03X1096642Y322890I-1160J-1104D01*
G02X1097242Y322913I310J-253D01*
G03X1099644Y323006I1160J1104D01*
G02X1099955Y323005I155J-127D01*
G03X1100108Y322841I1245J1008D01*
G01Y311371D01*
G02X1099497Y311031I-400J0D01*
G03X1097583Y310609I-741J-1190D01*
G02X1096905Y310623I-335J219D01*
G03X1094539Y310687I-1203J-719D01*
G02X1093885Y310673I-332J223D01*
G03X1091583Y310609I-1129J-832D01*
G02X1090905Y310623I-335J219D01*
G03X1090875Y309136I-1203J-720D01*
G02X1091553Y309122I335J-219D01*
G03X1093919Y309058I1203J719D01*
G02X1094573Y309072I332J-223D01*
G03X1096875Y309136I1129J832D01*
G02X1097553Y309122I335J-219D01*
G03X1099382Y308587I1203J719D01*
G02X1099937Y308365I179J-358D01*
G03X1100108Y308036I1319J476D01*
G01Y297486D01*
G02X1099480Y297157I-400J0D01*
G03X1097367Y296902I-913J-1316D01*
G02X1096767I-300J265D01*
G03X1094373Y296909I-1200J-1061D01*
G02X1093774Y296913I-298J267D01*
G03X1091367Y296920I-1207J-1054D01*
G02X1090767I-300J265D01*
G03X1088672Y294530I-1200J-1061D01*
G02X1088727Y293911I-223J-332D01*
G03X1090869Y292127I975J-1007D01*
G02X1091535I333J-222D01*
G03X1093775Y292002I1167J777D01*
G02X1094416Y291963I306J-258D01*
G03X1096956Y291780I1340J878D01*
G02X1097556I300J-265D01*
G03X1099518Y291432I1200J1061D01*
G02X1100108Y291080I190J-352D01*
G01Y281908D01*
X1099878Y281678D01*
X1095719D01*
X1094322Y280281D01*
Y276122D01*
X1086600Y268400D01*
Y266100D01*
X1087000Y265700D01*
Y264228D01*
G02X1086492Y263843I-400J0D01*
G03X1084499Y262656I-431J-1543D01*
G01X1084464Y262500D01*
X1078107D01*
X1077653Y262954D01*
Y267275D01*
X1077353Y267575D01*
X1034543D01*
X1029468Y262500D01*
X1022612D01*
X1022575Y262653D01*
G03X1019655I-1460J-353D01*
G01X1019618Y262500D01*
X1010032D01*
G03X1007418I-1307J-740D01*
G01X1003156D01*
G03X1000774I-1191J-740D01*
G01X1000196D01*
G02X999839Y263080I0J400D01*
G03X997333I-1253J629D01*
G02X996976Y262500I-357J-180D01*
G01X996397D01*
G03X994015I-1191J-740D01*
G01X993436D01*
G02X993079Y263080I0J400D01*
G03X990573I-1253J629D01*
G02X990216Y262500I-357J-180D01*
G01X989637D01*
G03X987255I-1191J-740D01*
G01X986676D01*
G02X986319Y263080I0J400D01*
G03X983813I-1253J629D01*
G02X983456Y262500I-357J-180D01*
G01X982877D01*
G03X980495I-1191J-740D01*
G01X979916D01*
G02X979559Y263080I0J400D01*
G03X977053I-1253J629D01*
G02X976696Y262500I-357J-180D01*
G01X976117D01*
G03X973735I-1191J-740D01*
G01X973156D01*
G02X972799Y263080I0J400D01*
G03X970293I-1253J629D01*
G02X969936Y262500I-357J-180D01*
G01X966396D01*
G02X966039Y263080I0J400D01*
G03X963533I-1253J629D01*
G02X963176Y262500I-357J-180D01*
G01X962597D01*
G03X960215I-1191J-740D01*
G01X959636D01*
G02X959279Y263080I0J400D01*
G03X956773I-1253J629D01*
G02X956416Y262500I-357J-180D01*
G01X955838D01*
G03X953456I-1191J-740D01*
G01X952877D01*
G02X952520Y263080I0J400D01*
G03X950014I-1253J629D01*
G02X949657Y262500I-357J-180D01*
G01X949078D01*
G03X946696I-1191J-740D01*
G01X946117D01*
G02X945760Y263080I0J400D01*
G03X943254I-1253J629D01*
G02X942897Y262500I-357J-180D01*
G01X942318D01*
G03X939936I-1191J-740D01*
G01X939357D01*
G02X939000Y263080I0J400D01*
G03X936494I-1253J629D01*
G02X936137Y262500I-357J-180D01*
G01X935558D01*
G03X933176I-1191J-740D01*
G01X932597D01*
G02X932240Y263080I0J400D01*
G03X929734I-1253J629D01*
G02X929377Y262500I-357J-180D01*
G01X928798D01*
G03X926416I-1191J-740D01*
G01X925837D01*
G02X925480Y263080I0J400D01*
G03X922974I-1253J629D01*
G02X922617Y262500I-357J-180D01*
G01X922038D01*
G03X920084Y262936I-1191J-740D01*
G01X919108D01*
Y264454D01*
G02X919805Y264722I400J0D01*
G03Y266598I1042J938D01*
G02X919108Y266866I-297J268D01*
G01Y268354D01*
G02X919805Y268622I400J0D01*
G03Y270498I1042J938D01*
G02X919108Y270766I-297J268D01*
G01Y271000D01*
X918850Y271258D01*
X918860Y271354D01*
G03X917356Y272907I-1393J155D01*
G01X917298Y272902D01*
X917102Y273006D01*
X914608Y275500D01*
X892200D01*
X832924Y216224D01*
X832806Y216266D01*
G03X830764Y214224I-530J-1512D01*
G01X830806Y214106D01*
X830600Y213900D01*
X822473D01*
G03X822327I-73J-1500D01*
G01X820608D01*
G37*
G36*
G01X909583Y222162D02*
X909292Y222947D01*
X909928Y223584D01*
X910713Y223294D01*
X910837Y223171D01*
X909706Y222038D01*
X909583Y222162D01*
G37*
G36*
G01X907280Y389369D02*
X906496Y389079D01*
X905859Y389716D01*
X906149Y390500D01*
X906273Y390624D01*
X907404Y389493D01*
X907280Y389369D01*
G37*
G36*
G01X910038Y386611D02*
X909253Y386321D01*
X908617Y386958D01*
X908907Y387743D01*
X909031Y387866D01*
X910162Y386735D01*
X910038Y386611D01*
G37*
G36*
G01X909683Y388519D02*
X910468Y388809D01*
X911105Y388173D01*
X910815Y387388D01*
X910691Y387264D01*
X909560Y388395D01*
X909683Y388519D01*
G37*
G36*
G01X906926Y391277D02*
X907710Y391567D01*
X908347Y390930D01*
X908057Y390146D01*
X907933Y390022D01*
X906802Y391153D01*
X906926Y391277D01*
G37*
G36*
G01X910548Y376691D02*
X909763Y376401D01*
X909127Y377038D01*
X909417Y377823D01*
X909541Y377946D01*
X910672Y376815D01*
X910548Y376691D01*
G37*
G36*
G01X908906Y401143D02*
X908122Y400853D01*
X907485Y401490D01*
X907775Y402274D01*
X907899Y402398D01*
X909030Y401267D01*
X908906Y401143D01*
G37*
G36*
G01X908552Y403051D02*
X909336Y403341D01*
X909973Y402704D01*
X909683Y401920D01*
X909559Y401796D01*
X908428Y402927D01*
X908552Y403051D01*
G37*
G36*
G01X907616Y375233D02*
X906831Y374943D01*
X906195Y375579D01*
X906485Y376364D01*
X906608Y376488D01*
X907740Y375356D01*
X907616Y375233D01*
G37*
G36*
G01X910374Y372475D02*
X909589Y372185D01*
X908953Y372821D01*
X909243Y373606D01*
X909366Y373730D01*
X910498Y372598D01*
X910374Y372475D01*
G37*
G36*
G01X907287Y377119D02*
X908071Y377409D01*
X908708Y376772D01*
X908418Y375988D01*
X908294Y375864D01*
X907163Y376995D01*
X907287Y377119D01*
G37*
G36*
G01X925106Y214141D02*
X924436Y214491D01*
Y215360D01*
X925106Y215710D01*
X925281Y215711D01*
X925280Y214140D01*
X925106Y214141D01*
G37*
G36*
G01X922260Y210861D02*
X922228Y211616D01*
X922981Y212051D01*
X923619Y211646D01*
X923707Y211495D01*
X922347Y210709D01*
X922260Y210861D01*
G37*
G36*
G01X918895Y208920D02*
X918863Y209675D01*
X919616Y210110D01*
X920254Y209705D01*
X920342Y209553D01*
X918982Y208768D01*
X918895Y208920D01*
G37*
G36*
G01X925647Y216717D02*
X925615Y217472D01*
X926368Y217906D01*
X927006Y217501D01*
X927094Y217350D01*
X925733Y216565D01*
X925647Y216717D01*
G37*
G36*
G01X926187Y211252D02*
X926219Y210497D01*
X925466Y210063D01*
X924828Y210468D01*
X924740Y210619D01*
X926101Y211404D01*
X926187Y211252D01*
G37*
G36*
G01X922799Y209299D02*
X922831Y208544D01*
X922078Y208109D01*
X921440Y208514D01*
X921352Y208665D01*
X922712Y209451D01*
X922799Y209299D01*
G37*
G36*
G01X926728Y213828D02*
X927398Y213478D01*
Y212609D01*
X926728Y212259D01*
X926553Y212258D01*
X926554Y213829D01*
X926728Y213828D01*
G37*
G36*
G01X929507Y217080D02*
X929539Y216325D01*
X928786Y215890D01*
X928148Y216295D01*
X928060Y216447D01*
X929420Y217231D01*
X929507Y217080D01*
G37*
G36*
G01X917477Y213712D02*
X917187Y214497D01*
X917824Y215133D01*
X918609Y214843D01*
X918732Y214719D01*
X917601Y213588D01*
X917477Y213712D01*
G37*
G36*
G01X920235Y216470D02*
X919945Y217254D01*
X920582Y217891D01*
X921366Y217601D01*
X921490Y217477D01*
X920359Y216346D01*
X920235Y216470D01*
G37*
G36*
G01X922143Y216824D02*
X922433Y216040D01*
X921796Y215403D01*
X921012Y215693D01*
X920888Y215817D01*
X922019Y216948D01*
X922143Y216824D01*
G37*
G36*
G01X919385Y214067D02*
X919675Y213282D01*
X919039Y212645D01*
X918254Y212935D01*
X918130Y213059D01*
X919261Y214190D01*
X919385Y214067D01*
G37*
G36*
G01X925867Y200750D02*
X925769Y201500D01*
X926482Y201999D01*
X927153Y201651D01*
X927253Y201507D01*
X925967Y200607D01*
X925867Y200750D01*
G37*
G36*
G01X929035Y203070D02*
X929003Y203825D01*
X929756Y204260D01*
X930394Y203855D01*
X930482Y203703D01*
X929122Y202918D01*
X929035Y203070D01*
G37*
G36*
G01X935786Y206965D02*
X935754Y207720D01*
X936507Y208155D01*
X937145Y207750D01*
X937233Y207599D01*
X935873Y206813D01*
X935786Y206965D01*
G37*
G36*
G01X932400Y205012D02*
X932368Y205767D01*
X933121Y206202D01*
X933759Y205797D01*
X933847Y205645D01*
X932487Y204861D01*
X932400Y205012D01*
G37*
G36*
G01X939175Y208920D02*
X939143Y209675D01*
X939896Y210110D01*
X940534Y209705D01*
X940622Y209553D01*
X939262Y208768D01*
X939175Y208920D01*
G37*
G36*
G01X942540Y210861D02*
X942508Y211616D01*
X943261Y212051D01*
X943899Y211646D01*
X943987Y211495D01*
X942627Y210709D01*
X942540Y210861D01*
G37*
G36*
G01X932939Y203449D02*
X932971Y202694D01*
X932218Y202259D01*
X931580Y202664D01*
X931492Y202815D01*
X932852Y203601D01*
X932939Y203449D01*
G37*
G36*
G01X936328Y205404D02*
X936360Y204649D01*
X935607Y204214D01*
X934969Y204619D01*
X934881Y204771D01*
X936241Y205556D01*
X936328Y205404D01*
G37*
G36*
G01X939714Y207357D02*
X939746Y206602D01*
X938993Y206167D01*
X938355Y206572D01*
X938267Y206723D01*
X939627Y207509D01*
X939714Y207357D01*
G37*
G36*
G01X946468Y211254D02*
X946500Y210499D01*
X945747Y210064D01*
X945109Y210469D01*
X945021Y210621D01*
X946381Y211406D01*
X946468Y211254D01*
G37*
G36*
G01X943079Y209299D02*
X943111Y208544D01*
X942358Y208109D01*
X941720Y208514D01*
X941632Y208665D01*
X942992Y209451D01*
X943079Y209299D01*
G37*
G36*
G01X948032Y216897D02*
X948670Y217302D01*
X949424Y216867D01*
X949392Y216111D01*
X949304Y215960D01*
X947945Y216745D01*
X948032Y216897D01*
G37*
G36*
G01X946786Y195274D02*
X946496Y196058D01*
X947133Y196695D01*
X947917Y196405D01*
X948041Y196281D01*
X946910Y195150D01*
X946786Y195274D01*
G37*
G36*
G01X945331Y191038D02*
X944571Y191388D01*
Y192288D01*
X945331Y192638D01*
X945506D01*
Y191038D01*
X945331D01*
G37*
G36*
G01X953997Y201635D02*
X953707Y202419D01*
X954344Y203056D01*
X955128Y202766D01*
X955252Y202642D01*
X954121Y201511D01*
X953997Y201635D01*
G37*
G36*
G01X951239Y198877D02*
X950949Y199662D01*
X951586Y200298D01*
X952371Y200008D01*
X952494Y199884D01*
X951363Y198753D01*
X951239Y198877D01*
G37*
G36*
G01X958903Y207179D02*
X958143Y207529D01*
Y208429D01*
X958903Y208779D01*
X959078D01*
Y207179D01*
X958903D01*
G37*
G36*
G01X956755Y204392D02*
X956465Y205177D01*
X957101Y205814D01*
X957886Y205524D01*
X958010Y205400D01*
X956879Y204269D01*
X956755Y204392D01*
G37*
G36*
G01X948695Y195627D02*
X948985Y194842D01*
X948349Y194206D01*
X947564Y194496D01*
X947440Y194619D01*
X948572Y195751D01*
X948695Y195627D01*
G37*
G36*
G01X946431Y192638D02*
X947191Y192288D01*
Y191388D01*
X946431Y191038D01*
X946256D01*
Y192638D01*
X946431D01*
G37*
G36*
G01X955906Y201988D02*
X956196Y201203D01*
X955560Y200567D01*
X954775Y200857D01*
X954651Y200980D01*
X955783Y202112D01*
X955906Y201988D01*
G37*
G36*
G01X953149Y199230D02*
X953439Y198445D01*
X952802Y197809D01*
X952017Y198099D01*
X951894Y198223D01*
X953025Y199354D01*
X953149Y199230D01*
G37*
G36*
G01X960003Y208779D02*
X960763Y208429D01*
Y207529D01*
X960003Y207179D01*
X959828D01*
Y208779D01*
X960003D01*
G37*
G36*
G01X960528Y213818D02*
X961198Y213468D01*
Y212598D01*
X960528Y212248D01*
X960353D01*
Y213818D01*
X960528D01*
G37*
G36*
G01X958664Y204746D02*
X958954Y203961D01*
X958318Y203324D01*
X957533Y203614D01*
X957409Y203738D01*
X958540Y204869D01*
X958664Y204746D01*
G37*
G36*
G01X922275Y203070D02*
X922243Y203825D01*
X922996Y204260D01*
X923634Y203855D01*
X923722Y203703D01*
X922362Y202918D01*
X922275Y203070D01*
G37*
G36*
G01X929026Y206965D02*
X928994Y207720D01*
X929747Y208155D01*
X930385Y207750D01*
X930473Y207599D01*
X929113Y206813D01*
X929026Y206965D01*
G37*
G36*
G01X925640Y205012D02*
X925608Y205767D01*
X926361Y206202D01*
X926999Y205797D01*
X927087Y205645D01*
X925727Y204861D01*
X925640Y205012D01*
G37*
G36*
G01X935780Y210861D02*
X935748Y211616D01*
X936501Y212051D01*
X937139Y211646D01*
X937227Y211495D01*
X935867Y210709D01*
X935780Y210861D01*
G37*
G36*
G01X932415Y208920D02*
X932383Y209675D01*
X933136Y210110D01*
X933774Y209705D01*
X933862Y209553D01*
X932502Y208768D01*
X932415Y208920D01*
G37*
G36*
G01X939166Y212815D02*
X939134Y213570D01*
X939887Y214005D01*
X940525Y213600D01*
X940613Y213449D01*
X939253Y212663D01*
X939166Y212815D01*
G37*
G36*
G01X926179Y203449D02*
X926211Y202694D01*
X925458Y202259D01*
X924820Y202664D01*
X924732Y202815D01*
X926092Y203601D01*
X926179Y203449D01*
G37*
G36*
G01X929568Y205404D02*
X929600Y204649D01*
X928847Y204214D01*
X928209Y204619D01*
X928121Y204771D01*
X929481Y205556D01*
X929568Y205404D01*
G37*
G36*
G01X932954Y207357D02*
X932986Y206602D01*
X932233Y206167D01*
X931595Y206572D01*
X931507Y206723D01*
X932867Y207509D01*
X932954Y207357D01*
G37*
G36*
G01X936319Y209299D02*
X936351Y208544D01*
X935598Y208109D01*
X934960Y208514D01*
X934872Y208665D01*
X936232Y209451D01*
X936319Y209299D01*
G37*
G36*
G01X939708Y211254D02*
X939740Y210499D01*
X938987Y210064D01*
X938349Y210469D01*
X938261Y210621D01*
X939621Y211406D01*
X939708Y211254D01*
G37*
G36*
G01X943094Y213208D02*
X943126Y212453D01*
X942373Y212018D01*
X941735Y212423D01*
X941647Y212575D01*
X943007Y213360D01*
X943094Y213208D01*
G37*
G36*
G01X942540Y199161D02*
X942508Y199916D01*
X943261Y200351D01*
X943899Y199946D01*
X943987Y199795D01*
X942627Y199009D01*
X942540Y199161D01*
G37*
G36*
G01X945926Y201115D02*
X945894Y201870D01*
X946647Y202305D01*
X947285Y201900D01*
X947373Y201749D01*
X946013Y200963D01*
X945926Y201115D01*
G37*
G36*
G01X941481Y194932D02*
X940721Y195282D01*
Y196182D01*
X941481Y196532D01*
X941656D01*
Y194932D01*
X941481D01*
G37*
G36*
G01X951432Y203346D02*
X951142Y204131D01*
X951778Y204767D01*
X952563Y204477D01*
X952687Y204354D01*
X951555Y203222D01*
X951432Y203346D01*
G37*
G36*
G01X956048Y208490D02*
X955288Y208839D01*
X955287Y209739D01*
X956047Y210090D01*
X956222D01*
X956223Y208490D01*
X956048D01*
G37*
G36*
G01X953932Y205846D02*
X953642Y206631D01*
X954278Y207267D01*
X955063Y206977D01*
X955187Y206854D01*
X954055Y205722D01*
X953932Y205846D01*
G37*
G36*
G01X946468Y199554D02*
X946500Y198799D01*
X945747Y198364D01*
X945109Y198769D01*
X945021Y198921D01*
X946381Y199706D01*
X946468Y199554D01*
G37*
G36*
G01X942581Y196532D02*
X943341Y196182D01*
Y195282D01*
X942581Y194932D01*
X942406D01*
Y196532D01*
X942581D01*
G37*
G36*
G01X953341Y203699D02*
X953631Y202915D01*
X952994Y202278D01*
X952210Y202568D01*
X952086Y202692D01*
X953217Y203823D01*
X953341Y203699D01*
G37*
G36*
G01X955841Y206199D02*
X956131Y205415D01*
X955494Y204778D01*
X954710Y205068D01*
X954586Y205192D01*
X955717Y206323D01*
X955841Y206199D01*
G37*
G36*
G01X957148Y210090D02*
X957908Y209740D01*
X957909Y208840D01*
X957149Y208490D01*
X956974D01*
X956973Y210090D01*
X957148D01*
G37*
G36*
G01Y215745D02*
X957818Y215395D01*
Y214525D01*
X957148Y214175D01*
X956973D01*
Y215745D01*
X957148D01*
G37*
G36*
G01X932211Y195793D02*
X932501Y195009D01*
X931864Y194372D01*
X931080Y194662D01*
X930956Y194786D01*
X932087Y195917D01*
X932211Y195793D01*
G37*
G36*
G01X936334Y201508D02*
X936366Y200753D01*
X935613Y200318D01*
X934975Y200723D01*
X934887Y200875D01*
X936247Y201660D01*
X936334Y201508D01*
G37*
G36*
G01X932961Y198250D02*
X933721Y197900D01*
Y197000D01*
X932961Y196650D01*
X932786D01*
Y198250D01*
X932961D01*
G37*
G36*
G01X939699Y203449D02*
X939731Y202694D01*
X938978Y202259D01*
X938340Y202664D01*
X938252Y202815D01*
X939612Y203601D01*
X939699Y203449D01*
G37*
G36*
G01X949839Y209299D02*
X949871Y208544D01*
X949118Y208109D01*
X948480Y208514D01*
X948392Y208665D01*
X949752Y209451D01*
X949839Y209299D01*
G37*
G36*
G01X943088Y205404D02*
X943120Y204649D01*
X942367Y204214D01*
X941729Y204619D01*
X941641Y204771D01*
X943001Y205556D01*
X943088Y205404D01*
G37*
G36*
G01X946474Y207357D02*
X946506Y206602D01*
X945753Y206167D01*
X945115Y206572D01*
X945027Y206723D01*
X946387Y207509D01*
X946474Y207357D01*
G37*
G36*
G01X971815Y200974D02*
X972105Y200189D01*
X971469Y199552D01*
X970684Y199842D01*
X970560Y199966D01*
X971691Y201097D01*
X971815Y200974D01*
G37*
G36*
G01X969057Y198216D02*
X969347Y197431D01*
X968711Y196795D01*
X967926Y197085D01*
X967802Y197208D01*
X968934Y198340D01*
X969057Y198216D01*
G37*
G36*
G01X970481Y213556D02*
X971241Y213206D01*
Y212306D01*
X970481Y211956D01*
X970306D01*
Y213556D01*
X970481D01*
G37*
G36*
G01Y216956D02*
X971241Y216606D01*
Y215706D01*
X970481Y215356D01*
X970306D01*
Y216956D01*
X970481D01*
G37*
G36*
G01X970856Y207910D02*
X971640Y208200D01*
X972277Y207563D01*
X971987Y206779D01*
X971863Y206655D01*
X970732Y207786D01*
X970856Y207910D01*
G37*
G36*
G01X935780Y199161D02*
X935748Y199916D01*
X936501Y200351D01*
X937139Y199946D01*
X937227Y199795D01*
X935867Y199009D01*
X935780Y199161D01*
G37*
G36*
G01X939166Y201115D02*
X939134Y201870D01*
X939887Y202305D01*
X940525Y201900D01*
X940613Y201749D01*
X939253Y200963D01*
X939166Y201115D01*
G37*
G36*
G01X942540Y203061D02*
X942508Y203816D01*
X943261Y204251D01*
X943899Y203846D01*
X943987Y203695D01*
X942627Y202909D01*
X942540Y203061D01*
G37*
G36*
G01X952145Y210250D02*
X951475Y210600D01*
Y211470D01*
X952145Y211820D01*
X952320D01*
Y210250D01*
X952145D01*
G37*
G36*
G01Y214150D02*
X951475Y214500D01*
Y215370D01*
X952145Y215720D01*
X952320D01*
Y214150D01*
X952145D01*
G37*
G36*
G01X945926Y205015D02*
X945894Y205770D01*
X946647Y206205D01*
X947285Y205800D01*
X947373Y205649D01*
X946013Y204863D01*
X945926Y205015D01*
G37*
G36*
G01X949300Y206961D02*
X949268Y207716D01*
X950021Y208151D01*
X950659Y207746D01*
X950747Y207595D01*
X949387Y206809D01*
X949300Y206961D01*
G37*
G36*
G01X931861Y197650D02*
X931101Y198000D01*
Y198900D01*
X931861Y199250D01*
X932036D01*
Y197650D01*
X931861D01*
G37*
G36*
G01X930302Y195440D02*
X930012Y196225D01*
X930648Y196861D01*
X931433Y196571D01*
X931557Y196448D01*
X930425Y195316D01*
X930302Y195440D01*
G37*
G36*
G01X932413Y201119D02*
X932381Y201874D01*
X933134Y202309D01*
X933772Y201904D01*
X933860Y201753D01*
X932500Y200967D01*
X932413Y201119D01*
G37*
G36*
G01X935795Y203070D02*
X935763Y203825D01*
X936516Y204260D01*
X937154Y203855D01*
X937242Y203703D01*
X935882Y202918D01*
X935795Y203070D01*
G37*
G36*
G01X939160Y205012D02*
X939128Y205767D01*
X939881Y206202D01*
X940519Y205797D01*
X940607Y205645D01*
X939247Y204861D01*
X939160Y205012D01*
G37*
G36*
G01X945935Y208920D02*
X945903Y209675D01*
X946656Y210110D01*
X947294Y209705D01*
X947382Y209553D01*
X946022Y208768D01*
X945935Y208920D01*
G37*
G36*
G01X942546Y206965D02*
X942514Y207720D01*
X943267Y208155D01*
X943905Y207750D01*
X943993Y207599D01*
X942633Y206813D01*
X942546Y206965D01*
G37*
G36*
G01X965390Y196105D02*
X965100Y196890D01*
X965737Y197526D01*
X966522Y197236D01*
X966645Y197112D01*
X965514Y195981D01*
X965390Y196105D01*
G37*
G36*
G01X968148Y198863D02*
X967858Y199647D01*
X968495Y200284D01*
X969279Y199994D01*
X969403Y199870D01*
X968272Y198739D01*
X968148Y198863D01*
G37*
G36*
G01X969381Y215856D02*
X968621Y216206D01*
Y217106D01*
X969381Y217456D01*
X969556D01*
Y215856D01*
X969381D01*
G37*
G36*
G01Y211956D02*
X968621Y212306D01*
Y213206D01*
X969381Y213556D01*
X969556D01*
Y211956D01*
X969381D01*
G37*
G36*
G01Y208056D02*
X968621Y208406D01*
Y209306D01*
X969381Y209656D01*
X969556D01*
Y208056D01*
X969381D01*
G37*
G36*
G01X971209Y206001D02*
X970424Y205711D01*
X969788Y206347D01*
X970078Y207132D01*
X970201Y207256D01*
X971333Y206124D01*
X971209Y206001D01*
G37*
G36*
G01X939708Y199554D02*
X939740Y198799D01*
X938987Y198364D01*
X938349Y198769D01*
X938261Y198921D01*
X939621Y199706D01*
X939708Y199554D01*
G37*
G36*
G01X946468Y203454D02*
X946500Y202699D01*
X945747Y202264D01*
X945109Y202669D01*
X945021Y202821D01*
X946381Y203606D01*
X946468Y203454D01*
G37*
G36*
G01X943094Y201508D02*
X943126Y200753D01*
X942373Y200318D01*
X941735Y200723D01*
X941647Y200875D01*
X943007Y201660D01*
X943094Y201508D01*
G37*
G36*
G01X953769Y213819D02*
X954439Y213469D01*
Y212599D01*
X953769Y212249D01*
X953594D01*
Y213819D01*
X953769D01*
G37*
G36*
G01Y209928D02*
X954438Y209578D01*
Y208709D01*
X953768Y208359D01*
X953593Y208358D01*
X953594Y209929D01*
X953769Y209928D01*
G37*
G36*
G01Y217676D02*
X954438Y217326D01*
X954439Y216457D01*
X953769Y216107D01*
X953594Y216106D01*
X953593Y217677D01*
X953769Y217676D01*
G37*
G36*
G01X949854Y205408D02*
X949886Y204653D01*
X949133Y204218D01*
X948495Y204623D01*
X948407Y204775D01*
X949767Y205560D01*
X949854Y205408D01*
G37*
G36*
G01X960919Y197871D02*
X960629Y198656D01*
X961265Y199293D01*
X962050Y199003D01*
X962174Y198879D01*
X961043Y197748D01*
X960919Y197871D01*
G37*
G36*
G01X963677Y200629D02*
X963387Y201414D01*
X964023Y202050D01*
X964808Y201760D01*
X964932Y201637D01*
X963800Y200505D01*
X963677Y200629D01*
G37*
G36*
G01X966306Y210199D02*
X965546Y210549D01*
Y211449D01*
X966306Y211799D01*
X966481D01*
Y210199D01*
X966306D01*
G37*
G36*
G01Y214099D02*
X965546Y214449D01*
Y215349D01*
X966306Y215699D01*
X966481D01*
Y214099D01*
X966306D01*
G37*
G36*
G01X966771Y204756D02*
X966011Y205106D01*
Y206006D01*
X966771Y206356D01*
X966946D01*
Y204756D01*
X966771D01*
G37*
G36*
G01X962827Y198226D02*
X963117Y197441D01*
X962480Y196805D01*
X961695Y197095D01*
X961572Y197219D01*
X962703Y198350D01*
X962827Y198226D01*
G37*
G36*
G01X965584Y200984D02*
X965874Y200199D01*
X965238Y199563D01*
X964453Y199853D01*
X964329Y199976D01*
X965461Y201108D01*
X965584Y200984D01*
G37*
G36*
G01X967406Y211799D02*
X968166Y211449D01*
Y210549D01*
X967406Y210199D01*
X967231D01*
Y211799D01*
X967406D01*
G37*
G36*
G01Y215699D02*
X968166Y215349D01*
Y214449D01*
X967406Y214099D01*
X967231D01*
Y215699D01*
X967406D01*
G37*
G36*
G01X967869Y206356D02*
X968629Y206006D01*
Y205106D01*
X967869Y204756D01*
X967694D01*
Y206356D01*
X967869D01*
G37*
G36*
G01X959745Y201018D02*
X959455Y201803D01*
X960091Y202439D01*
X960876Y202149D01*
X961000Y202026D01*
X959868Y200894D01*
X959745Y201018D01*
G37*
G36*
G01X955787Y197060D02*
X955497Y197845D01*
X956133Y198482D01*
X956918Y198192D01*
X957042Y198068D01*
X955911Y196937D01*
X955787Y197060D01*
G37*
G36*
G01X962284Y212249D02*
X961614Y212599D01*
Y213469D01*
X962284Y213819D01*
X962459D01*
Y212249D01*
X962284D01*
G37*
G36*
G01Y216149D02*
X961614Y216499D01*
Y217369D01*
X962284Y217719D01*
X962459D01*
Y216149D01*
X962284D01*
G37*
G36*
G01X962012Y207404D02*
X961252Y207754D01*
Y208654D01*
X962012Y209004D01*
X962187D01*
Y207404D01*
X962012D01*
G37*
G36*
G01X960741Y204021D02*
X959981Y204371D01*
Y205271D01*
X960741Y205621D01*
X960916D01*
Y204021D01*
X960741D01*
G37*
G36*
G01X957701Y197409D02*
X957991Y196624D01*
X957354Y195988D01*
X956569Y196278D01*
X956446Y196402D01*
X957577Y197533D01*
X957701Y197409D01*
G37*
G36*
G01X960458Y200167D02*
X960748Y199382D01*
X960112Y198746D01*
X959327Y199036D01*
X959203Y199159D01*
X960335Y200291D01*
X960458Y200167D01*
G37*
G36*
G01X963215Y202925D02*
X963505Y202140D01*
X962869Y201504D01*
X962084Y201794D01*
X961960Y201917D01*
X963092Y203049D01*
X963215Y202925D01*
G37*
G36*
G01X963908Y215720D02*
X964578Y215370D01*
Y214500D01*
X963908Y214150D01*
X963733D01*
Y215720D01*
X963908D01*
G37*
G36*
G01Y211820D02*
X964578Y211470D01*
Y210600D01*
X963908Y210250D01*
X963733D01*
Y211820D01*
X963908D01*
G37*
G36*
G01X964281Y205921D02*
X965041Y205571D01*
Y204671D01*
X964281Y204321D01*
X964106D01*
Y205921D01*
X964281D01*
G37*
G36*
G01X914456Y229516D02*
X914806Y230276D01*
X915706D01*
X916056Y229516D01*
Y229341D01*
X914456D01*
Y229516D01*
G37*
G36*
G01X917205Y229696D02*
X916915Y230480D01*
X917552Y231117D01*
X918336Y230827D01*
X918460Y230703D01*
X917329Y229572D01*
X917205Y229696D01*
G37*
G36*
G01X920374Y231109D02*
X920724Y231869D01*
X921624D01*
X921974Y231109D01*
Y230934D01*
X920374D01*
Y231109D01*
G37*
G36*
G01X926822Y232310D02*
X927172Y232980D01*
X928042D01*
X928392Y232310D01*
Y232135D01*
X926822D01*
Y232310D01*
G37*
G36*
G01X916556Y228416D02*
X916206Y227656D01*
X915306D01*
X914956Y228416D01*
Y228591D01*
X916556D01*
Y228416D01*
G37*
G36*
G01X919113Y230050D02*
X919403Y229266D01*
X918766Y228629D01*
X917982Y228919D01*
X917858Y229043D01*
X918989Y230174D01*
X919113Y230050D01*
G37*
G36*
G01X921974Y230009D02*
X921624Y229249D01*
X920724D01*
X920374Y230009D01*
Y230184D01*
X921974D01*
Y230009D01*
G37*
G36*
G01X928215Y229197D02*
X928853Y229602D01*
X929606Y229167D01*
X929574Y228412D01*
X929487Y228261D01*
X928127Y229045D01*
X928215Y229197D01*
G37*
G36*
G01X920381Y235009D02*
X920731Y235769D01*
X921631D01*
X921981Y235009D01*
Y234834D01*
X920381D01*
Y235009D01*
G37*
G36*
G01X916254Y233244D02*
X915964Y234029D01*
X916600Y234665D01*
X917385Y234375D01*
X917509Y234252D01*
X916377Y233120D01*
X916254Y233244D01*
G37*
G36*
G01X912826Y232713D02*
X913176Y233473D01*
X914076D01*
X914426Y232713D01*
Y232538D01*
X912826D01*
Y232713D01*
G37*
G36*
G01X931595Y235046D02*
X932233Y235451D01*
X932986Y235016D01*
X932954Y234261D01*
X932867Y234109D01*
X931507Y234895D01*
X931595Y235046D01*
G37*
G36*
G01X925646Y236215D02*
X925614Y236970D01*
X926367Y237405D01*
X927005Y237000D01*
X927093Y236849D01*
X925733Y236063D01*
X925646Y236215D01*
G37*
G36*
G01X926188Y234654D02*
X926220Y233899D01*
X925467Y233464D01*
X924829Y233869D01*
X924741Y234021D01*
X926101Y234806D01*
X926188Y234654D01*
G37*
G36*
G01X921981Y233909D02*
X921631Y233149D01*
X920731D01*
X920381Y233909D01*
Y234084D01*
X921981D01*
Y233909D01*
G37*
G36*
G01X918161Y233599D02*
X918451Y232814D01*
X917815Y232178D01*
X917030Y232468D01*
X916906Y232591D01*
X918038Y233723D01*
X918161Y233599D01*
G37*
G36*
G01X914426Y231613D02*
X914076Y230853D01*
X913176D01*
X912826Y231613D01*
Y231788D01*
X914426D01*
Y231613D01*
G37*
G36*
G01X930385Y233869D02*
X929747Y233464D01*
X928994Y233899D01*
X929026Y234654D01*
X929113Y234806D01*
X930473Y234021D01*
X930385Y233869D01*
G37*
G36*
G01X925646Y220615D02*
X925614Y221370D01*
X926367Y221805D01*
X927005Y221400D01*
X927093Y221249D01*
X925733Y220463D01*
X925646Y220615D01*
G37*
G36*
G01X926188Y219054D02*
X926220Y218299D01*
X925467Y217864D01*
X924829Y218269D01*
X924741Y218421D01*
X926101Y219206D01*
X926188Y219054D01*
G37*
G36*
G01X923138Y226109D02*
X922788Y225349D01*
X921888D01*
X921538Y226109D01*
Y226284D01*
X923138D01*
Y226109D01*
G37*
G36*
G01X916704Y224160D02*
X916354Y223400D01*
X915454D01*
X915104Y224160D01*
Y224335D01*
X916704D01*
Y224160D01*
G37*
G36*
G01X920114Y225751D02*
X920404Y224967D01*
X919767Y224330D01*
X918983Y224620D01*
X918859Y224744D01*
X919990Y225875D01*
X920114Y225751D01*
G37*
G36*
G01X911492Y222516D02*
X911783Y221732D01*
X911147Y221095D01*
X910362Y221384D01*
X910238Y221508D01*
X911368Y222640D01*
X911492Y222516D01*
G37*
G36*
G01X970667Y223518D02*
X971337Y223168D01*
Y222298D01*
X970667Y221948D01*
X970492D01*
Y223518D01*
X970667D01*
G37*
G36*
G01Y227418D02*
X971337Y227068D01*
Y226198D01*
X970667Y225848D01*
X970492D01*
Y227418D01*
X970667D01*
G37*
G36*
G01X925646Y224515D02*
X925614Y225270D01*
X926367Y225705D01*
X927005Y225300D01*
X927093Y225149D01*
X925733Y224363D01*
X925646Y224515D01*
G37*
G36*
G01X928202Y225304D02*
X928840Y225709D01*
X929593Y225274D01*
X929561Y224519D01*
X929474Y224367D01*
X928114Y225153D01*
X928202Y225304D01*
G37*
G36*
G01X918833Y220026D02*
X918543Y220811D01*
X919179Y221447D01*
X919964Y221157D01*
X920088Y221034D01*
X918956Y219902D01*
X918833Y220026D01*
G37*
G36*
G01X950725Y218239D02*
X950087Y217834D01*
X949334Y218269D01*
X949366Y219024D01*
X949453Y219175D01*
X950813Y218390D01*
X950725Y218239D01*
G37*
G36*
G01X921538Y227209D02*
X921888Y227969D01*
X922788D01*
X923138Y227209D01*
Y227034D01*
X921538D01*
Y227209D01*
G37*
G36*
G01X915104Y225260D02*
X915454Y226020D01*
X916354D01*
X916704Y225260D01*
Y225085D01*
X915104D01*
Y225260D01*
G37*
G36*
G01X930394Y226064D02*
X929756Y225659D01*
X929003Y226094D01*
X929035Y226849D01*
X929122Y227001D01*
X930482Y226215D01*
X930394Y226064D01*
G37*
G36*
G01X918334Y225528D02*
X918044Y226313D01*
X918681Y226949D01*
X919466Y226659D01*
X919589Y226535D01*
X918458Y225404D01*
X918334Y225528D01*
G37*
G36*
G01X969044Y220053D02*
X968374Y220403D01*
Y221273D01*
X969044Y221623D01*
X969219D01*
Y220053D01*
X969044D01*
G37*
G36*
G01Y223949D02*
X968374Y224299D01*
Y225169D01*
X969044Y225519D01*
X969219D01*
Y223949D01*
X969044D01*
G37*
G36*
G01X969586Y230367D02*
X969554Y231122D01*
X970307Y231556D01*
X970945Y231151D01*
X971032Y231000D01*
X969673Y230214D01*
X969586Y230367D01*
G37*
G36*
G01X969045Y227791D02*
X968375Y228141D01*
Y229010D01*
X969045Y229360D01*
X969219D01*
X969220Y227790D01*
X969045Y227791D01*
G37*
G36*
G01X926188Y222954D02*
X926220Y222199D01*
X925467Y221764D01*
X924829Y222169D01*
X924741Y222321D01*
X926101Y223106D01*
X926188Y222954D01*
G37*
G36*
G01X920742Y220379D02*
X921032Y219595D01*
X920395Y218958D01*
X919611Y219248D01*
X919487Y219372D01*
X920618Y220503D01*
X920742Y220379D01*
G37*
G36*
G01X932918Y222936D02*
X932950Y222181D01*
X932197Y221746D01*
X931559Y222151D01*
X931471Y222303D01*
X932831Y223087D01*
X932918Y222936D01*
G37*
G36*
G01X951854Y219459D02*
X952491Y219864D01*
X953245Y219430D01*
X953213Y218675D01*
X953126Y218523D01*
X951765Y219308D01*
X951854Y219459D01*
G37*
G36*
G01X965665Y218075D02*
X964995Y218425D01*
Y219295D01*
X965665Y219645D01*
X965840D01*
Y218075D01*
X965665D01*
G37*
G36*
G01X965664Y221950D02*
X964994Y222300D01*
Y223170D01*
X965664Y223520D01*
X965839D01*
Y221950D01*
X965664D01*
G37*
G36*
G01Y225875D02*
X964994Y226225D01*
Y227095D01*
X965664Y227445D01*
X965839D01*
Y225875D01*
X965664D01*
G37*
G36*
G01Y229774D02*
X964995Y230124D01*
Y230994D01*
X965665Y231343D01*
X965840Y231344D01*
X965839Y229773D01*
X965664Y229774D01*
G37*
G36*
G01X966235Y232333D02*
X966204Y233088D01*
X966957Y233523D01*
X967595Y233117D01*
X967683Y232966D01*
X966322Y232181D01*
X966235Y232333D01*
G37*
G36*
G01X969579Y234261D02*
X969547Y235016D01*
X970300Y235451D01*
X970938Y235046D01*
X971026Y234895D01*
X969666Y234109D01*
X969579Y234261D01*
G37*
G36*
G01X967288Y221619D02*
X967958Y221269D01*
Y220399D01*
X967288Y220049D01*
X967113D01*
Y221619D01*
X967288D01*
G37*
G36*
G01X970118Y232699D02*
X970150Y231944D01*
X969397Y231509D01*
X968759Y231914D01*
X968671Y232065D01*
X970031Y232851D01*
X970118Y232699D01*
G37*
G36*
G01X967288Y229370D02*
X967958Y229020D01*
Y228150D01*
X967288Y227800D01*
X967113D01*
Y229370D01*
X967288D01*
G37*
G36*
G01Y225519D02*
X967958Y225169D01*
Y224299D01*
X967288Y223949D01*
X967113D01*
Y225519D01*
X967288D01*
G37*
G36*
G01X962284Y220049D02*
X961614Y220399D01*
Y221269D01*
X962284Y221619D01*
X962459D01*
Y220049D01*
X962284D01*
G37*
G36*
G01X962285Y231681D02*
X961615Y232031D01*
Y232901D01*
X962285Y233251D01*
X962459D01*
X962460Y231681D01*
X962285D01*
G37*
G36*
G01X962284Y223949D02*
X961614Y224299D01*
Y225169D01*
X962284Y225519D01*
X962459D01*
Y223949D01*
X962284D01*
G37*
G36*
G01Y227800D02*
X961614Y228150D01*
Y229020D01*
X962284Y229370D01*
X962459D01*
Y227800D01*
X962284D01*
G37*
G36*
G01X962819Y234261D02*
X962787Y235016D01*
X963540Y235451D01*
X964178Y235046D01*
X964265Y234895D01*
X962906Y234109D01*
X962819Y234261D01*
G37*
G36*
G01X966205Y236215D02*
X966173Y236970D01*
X966926Y237405D01*
X967564Y237000D01*
X967652Y236849D01*
X966292Y236063D01*
X966205Y236215D01*
G37*
G36*
G01X963908Y223520D02*
X964578Y223170D01*
Y222300D01*
X963908Y221950D01*
X963733D01*
Y223520D01*
X963908D01*
G37*
G36*
G01Y219620D02*
X964578Y219270D01*
Y218400D01*
X963908Y218050D01*
X963733D01*
Y219620D01*
X963908D01*
G37*
G36*
G01Y231369D02*
X964578Y231019D01*
Y230149D01*
X963908Y229799D01*
X963733D01*
Y231369D01*
X963908D01*
G37*
G36*
G01X966747Y234654D02*
X966779Y233899D01*
X966026Y233464D01*
X965388Y233869D01*
X965300Y234021D01*
X966660Y234806D01*
X966747Y234654D01*
G37*
G36*
G01X963908Y227445D02*
X964578Y227095D01*
Y226225D01*
X963908Y225875D01*
X963733D01*
Y227445D01*
X963908D01*
G37*
G36*
G01X970133Y236608D02*
X970165Y235853D01*
X969412Y235418D01*
X968774Y235823D01*
X968686Y235975D01*
X970046Y236760D01*
X970133Y236608D01*
G37*
G36*
G01X932939Y367249D02*
X932971Y366494D01*
X932218Y366059D01*
X931580Y366464D01*
X931492Y366615D01*
X932852Y367401D01*
X932939Y367249D01*
G37*
G36*
G01X929574Y365308D02*
X929606Y364553D01*
X928853Y364118D01*
X928215Y364523D01*
X928127Y364675D01*
X929487Y365460D01*
X929574Y365308D01*
G37*
G36*
G01X936328Y369204D02*
X936360Y368449D01*
X935607Y368014D01*
X934969Y368419D01*
X934881Y368570D01*
X936241Y369355D01*
X936328Y369204D01*
G37*
G36*
G01X916205Y362609D02*
X915855Y361849D01*
X914955D01*
X914605Y362609D01*
Y362784D01*
X916205D01*
Y362609D01*
G37*
G36*
G01X920105D02*
X919755Y361849D01*
X918855D01*
X918505Y362609D01*
Y362784D01*
X920105D01*
Y362609D01*
G37*
G36*
G01X925646Y364915D02*
X925614Y365670D01*
X926367Y366105D01*
X927005Y365700D01*
X927093Y365549D01*
X925733Y364763D01*
X925646Y364915D01*
G37*
G36*
G01X915005Y363709D02*
X915355Y364469D01*
X916255D01*
X916605Y363709D01*
Y363534D01*
X915005D01*
Y363709D01*
G37*
G36*
G01X918905D02*
X919255Y364469D01*
X920155D01*
X920505Y363709D01*
Y363534D01*
X918905D01*
Y363709D01*
G37*
G36*
G01X911456Y381767D02*
X910696Y382117D01*
X910697Y383017D01*
X911457Y383367D01*
X911632Y383366D01*
Y381767D01*
X911456D01*
G37*
G36*
G01X920404Y377766D02*
X920054Y377006D01*
X919154D01*
X918804Y377766D01*
Y377941D01*
X920404D01*
Y377766D01*
G37*
G36*
G01X916504D02*
X916154Y377006D01*
X915254D01*
X914904Y377766D01*
Y377941D01*
X916504D01*
Y377766D01*
G37*
G36*
G01X918804Y378864D02*
X919154Y379624D01*
X920054D01*
X920404Y378864D01*
Y378689D01*
X918804D01*
Y378864D01*
G37*
G36*
G01X914904D02*
X915254Y379624D01*
X916154D01*
X916504Y378864D01*
Y378689D01*
X914904D01*
Y378864D01*
G37*
G36*
G01X912555Y383367D02*
X913315Y383017D01*
Y382117D01*
X912555Y381767D01*
X912380D01*
Y383366D01*
X912555Y383367D01*
G37*
G36*
G01X926188Y359454D02*
X926220Y358699D01*
X925467Y358264D01*
X924829Y358669D01*
X924741Y358820D01*
X926101Y359605D01*
X926188Y359454D01*
G37*
G36*
G01X919911Y358516D02*
X919561Y357756D01*
X918661D01*
X918311Y358516D01*
Y358691D01*
X919911D01*
Y358516D01*
G37*
G36*
G01X929574Y361408D02*
X929606Y360653D01*
X928853Y360218D01*
X928215Y360623D01*
X928127Y360775D01*
X929487Y361560D01*
X929574Y361408D01*
G37*
G36*
G01X932948Y363354D02*
X932980Y362599D01*
X932227Y362164D01*
X931589Y362569D01*
X931501Y362720D01*
X932861Y363505D01*
X932948Y363354D01*
G37*
G36*
G01X936334Y365308D02*
X936366Y364553D01*
X935613Y364118D01*
X934975Y364523D01*
X934887Y364675D01*
X936247Y365460D01*
X936334Y365308D01*
G37*
G36*
G01X929020Y362961D02*
X928988Y363716D01*
X929741Y364151D01*
X930379Y363746D01*
X930467Y363595D01*
X929107Y362809D01*
X929020Y362961D01*
G37*
G36*
G01X918311Y359614D02*
X918661Y360374D01*
X919561D01*
X919911Y359614D01*
Y359439D01*
X918311D01*
Y359614D01*
G37*
G36*
G01X925646Y361015D02*
X925614Y361770D01*
X926367Y362205D01*
X927005Y361800D01*
X927093Y361649D01*
X925733Y360863D01*
X925646Y361015D01*
G37*
G36*
G01X914411Y359614D02*
X914761Y360374D01*
X915661D01*
X916011Y359614D01*
Y359439D01*
X914411D01*
Y359614D01*
G37*
G36*
G01X929020Y374661D02*
X928988Y375416D01*
X929741Y375851D01*
X930379Y375446D01*
X930467Y375295D01*
X929107Y374509D01*
X929020Y374661D01*
G37*
G36*
G01X914517Y374766D02*
X914167Y374006D01*
X913267D01*
X912917Y374766D01*
Y374941D01*
X914517D01*
Y374766D01*
G37*
G36*
G01X918417D02*
X918067Y374006D01*
X917167D01*
X916817Y374766D01*
Y374941D01*
X918417D01*
Y374766D01*
G37*
G36*
G01X922317D02*
X921967Y374006D01*
X921067D01*
X920717Y374766D01*
Y374941D01*
X922317D01*
Y374766D01*
G37*
G36*
G01X912917Y375864D02*
X913267Y376624D01*
X914167D01*
X914517Y375864D01*
Y375689D01*
X912917D01*
Y375864D01*
G37*
G36*
G01X916817D02*
X917167Y376624D01*
X918067D01*
X918417Y375864D01*
Y375689D01*
X916817D01*
Y375864D01*
G37*
G36*
G01X920717D02*
X921067Y376624D01*
X921967D01*
X922317Y375864D01*
Y375689D01*
X920717D01*
Y375864D01*
G37*
G36*
G01X910193Y378599D02*
X910978Y378889D01*
X911614Y378253D01*
X911325Y377468D01*
X911201Y377344D01*
X910069Y378475D01*
X910193Y378599D01*
G37*
G36*
G01X930394Y389864D02*
X929756Y389459D01*
X929003Y389894D01*
X929035Y390649D01*
X929122Y390801D01*
X930482Y390015D01*
X930394Y389864D01*
G37*
G36*
G01X933759Y387923D02*
X933121Y387518D01*
X932368Y387953D01*
X932400Y388708D01*
X932487Y388860D01*
X933847Y388075D01*
X933759Y387923D01*
G37*
G36*
G01X937145Y385969D02*
X936507Y385564D01*
X935754Y385999D01*
X935786Y386754D01*
X935873Y386905D01*
X937233Y386120D01*
X937145Y385969D01*
G37*
G36*
G01X940519Y384023D02*
X939881Y383618D01*
X939128Y384053D01*
X939160Y384808D01*
X939247Y384960D01*
X940607Y384175D01*
X940519Y384023D01*
G37*
G36*
G01X917973Y399156D02*
X917188Y398866D01*
X916552Y399503D01*
X916842Y400288D01*
X916966Y400411D01*
X918097Y399280D01*
X917973Y399156D01*
G37*
G36*
G01X915215Y401914D02*
X914431Y401624D01*
X913794Y402261D01*
X914084Y403045D01*
X914208Y403169D01*
X915339Y402038D01*
X915215Y401914D01*
G37*
G36*
G01X923619Y393772D02*
X922981Y393367D01*
X922228Y393802D01*
X922260Y394557D01*
X922347Y394709D01*
X923707Y393923D01*
X923619Y393772D01*
G37*
G36*
G01X927005Y391819D02*
X926367Y391414D01*
X925614Y391849D01*
X925646Y392604D01*
X925733Y392755D01*
X927093Y391970D01*
X927005Y391819D01*
G37*
G36*
G01X943905Y382069D02*
X943267Y381664D01*
X942514Y382099D01*
X942546Y382854D01*
X942633Y383005D01*
X943993Y382220D01*
X943905Y382069D01*
G37*
G36*
G01X946255Y381489D02*
X946926Y381141D01*
X946929Y380272D01*
X946260Y379920D01*
X946084Y379919D01*
X946080Y381489D01*
X946255D01*
G37*
G36*
G01X947045Y375616D02*
X946297Y375507D01*
X945788Y376212D01*
X946126Y376888D01*
X946268Y376991D01*
X947187Y375718D01*
X947045Y375616D01*
G37*
G36*
G01X934969Y389100D02*
X935607Y389505D01*
X936360Y389070D01*
X936328Y388315D01*
X936241Y388163D01*
X934881Y388949D01*
X934969Y389100D01*
G37*
G36*
G01X938355Y387146D02*
X938993Y387551D01*
X939746Y387116D01*
X939714Y386361D01*
X939627Y386209D01*
X938267Y386995D01*
X938355Y387146D01*
G37*
G36*
G01X928215Y392997D02*
X928853Y393402D01*
X929606Y392967D01*
X929574Y392212D01*
X929487Y392061D01*
X928127Y392845D01*
X928215Y392997D01*
G37*
G36*
G01X931580Y391055D02*
X932218Y391460D01*
X932971Y391025D01*
X932939Y390270D01*
X932852Y390118D01*
X931492Y390903D01*
X931580Y391055D01*
G37*
G36*
G01X921440Y396905D02*
X922078Y397310D01*
X922831Y396875D01*
X922799Y396120D01*
X922712Y395968D01*
X921352Y396753D01*
X921440Y396905D01*
G37*
G36*
G01X917618Y401064D02*
X918403Y401354D01*
X919040Y400718D01*
X918750Y399933D01*
X918626Y399809D01*
X917495Y400940D01*
X917618Y401064D01*
G37*
G36*
G01X924829Y394950D02*
X925467Y395355D01*
X926220Y394920D01*
X926188Y394165D01*
X926101Y394013D01*
X924741Y394799D01*
X924829Y394950D01*
G37*
G36*
G01X914861Y403822D02*
X915645Y404112D01*
X916282Y403475D01*
X915992Y402691D01*
X915868Y402567D01*
X914737Y403698D01*
X914861Y403822D01*
G37*
G36*
G01X941729Y385200D02*
X942367Y385605D01*
X943120Y385170D01*
X943088Y384415D01*
X943001Y384263D01*
X941641Y385049D01*
X941729Y385200D01*
G37*
G36*
G01X941075Y400441D02*
X940291Y400151D01*
X939654Y400788D01*
X939944Y401572D01*
X940068Y401696D01*
X941199Y400565D01*
X941075Y400441D01*
G37*
G36*
G01X936483Y402836D02*
X935698Y402547D01*
X935061Y403183D01*
X935351Y403968D01*
X935475Y404092D01*
X936606Y402960D01*
X936483Y402836D01*
G37*
G36*
G01X955524Y387760D02*
X954854Y388110D01*
Y388980D01*
X955524Y389330D01*
X955699D01*
Y387760D01*
X955524D01*
G37*
G36*
G01X957404Y378161D02*
X956733Y377813D01*
X956020Y378311D01*
X956118Y379061D01*
X956218Y379204D01*
X957504Y378304D01*
X957404Y378161D01*
G37*
G36*
G01X955553Y379923D02*
X954883Y380273D01*
Y381142D01*
X955553Y381492D01*
X955727D01*
X955728Y379922D01*
X955553Y379923D01*
G37*
G36*
G01X943899Y397671D02*
X943261Y397266D01*
X942508Y397701D01*
X942540Y398456D01*
X942627Y398607D01*
X943987Y397822D01*
X943899Y397671D01*
G37*
G36*
G01X947285Y395718D02*
X946647Y395313D01*
X945894Y395748D01*
X945926Y396503D01*
X946013Y396655D01*
X947373Y395869D01*
X947285Y395718D01*
G37*
G36*
G01X950674Y393763D02*
X950036Y393358D01*
X949283Y393793D01*
X949315Y394548D01*
X949402Y394699D01*
X950762Y393914D01*
X950674Y393763D01*
G37*
G36*
G01X954039Y391822D02*
X953401Y391417D01*
X952648Y391852D01*
X952680Y392607D01*
X952767Y392759D01*
X954127Y391973D01*
X954039Y391822D01*
G37*
G36*
G01X940723Y402351D02*
X941507Y402641D01*
X942144Y402004D01*
X941854Y401220D01*
X941730Y401096D01*
X940599Y402227D01*
X940723Y402351D01*
G37*
G36*
G01X957149Y387309D02*
X957819Y386959D01*
Y386089D01*
X957149Y385739D01*
X956974D01*
Y387309D01*
X957149D01*
G37*
G36*
G01Y383409D02*
X957819Y383059D01*
Y382189D01*
X957149Y381839D01*
X956974D01*
Y383409D01*
X957149D01*
G37*
G36*
G01X945109Y398849D02*
X945747Y399254D01*
X946500Y398819D01*
X946468Y398064D01*
X946381Y397912D01*
X945021Y398697D01*
X945109Y398849D01*
G37*
G36*
G01X948495Y396896D02*
X949133Y397301D01*
X949886Y396866D01*
X949854Y396111D01*
X949767Y395959D01*
X948407Y396745D01*
X948495Y396896D01*
G37*
G36*
G01X951860Y394954D02*
X952498Y395359D01*
X953251Y394924D01*
X953219Y394169D01*
X953132Y394017D01*
X951772Y394803D01*
X951860Y394954D01*
G37*
G36*
G01X956438Y392359D02*
X957193Y392391D01*
X957628Y391638D01*
X957223Y391000D01*
X957072Y390912D01*
X956286Y392272D01*
X956438Y392359D01*
G37*
G36*
G01X930385Y385969D02*
X929747Y385564D01*
X928994Y385999D01*
X929026Y386754D01*
X929113Y386905D01*
X930473Y386120D01*
X930385Y385969D01*
G37*
G36*
G01X937145Y382069D02*
X936507Y381664D01*
X935754Y382099D01*
X935786Y382854D01*
X935873Y383005D01*
X937233Y382220D01*
X937145Y382069D01*
G37*
G36*
G01X940519Y380123D02*
X939881Y379718D01*
X939128Y380153D01*
X939160Y380908D01*
X939247Y381060D01*
X940607Y380275D01*
X940519Y380123D01*
G37*
G36*
G01X933759Y384023D02*
X933121Y383618D01*
X932368Y384053D01*
X932400Y384808D01*
X932487Y384960D01*
X933847Y384175D01*
X933759Y384023D01*
G37*
G36*
G01X923619Y389873D02*
X922981Y389468D01*
X922228Y389903D01*
X922260Y390658D01*
X922347Y390810D01*
X923707Y390025D01*
X923619Y389873D01*
G37*
G36*
G01X926999Y387923D02*
X926361Y387518D01*
X925608Y387953D01*
X925640Y388708D01*
X925727Y388860D01*
X927087Y388075D01*
X926999Y387923D01*
G37*
G36*
G01X913940Y397289D02*
X913155Y396999D01*
X912519Y397635D01*
X912809Y398420D01*
X912933Y398544D01*
X914064Y397412D01*
X913940Y397289D01*
G37*
G36*
G01X916698Y394531D02*
X915913Y394241D01*
X915277Y394877D01*
X915567Y395662D01*
X915691Y395786D01*
X916822Y394654D01*
X916698Y394531D01*
G37*
G36*
G01X920245Y391819D02*
X919607Y391414D01*
X918854Y391849D01*
X918886Y392604D01*
X918973Y392755D01*
X920333Y391970D01*
X920245Y391819D01*
G37*
G36*
G01X943897Y378156D02*
X943226Y377808D01*
X942513Y378307D01*
X942611Y379057D01*
X942711Y379200D01*
X943997Y378300D01*
X943897Y378156D01*
G37*
G36*
G01X941729Y381300D02*
X942367Y381705D01*
X943120Y381270D01*
X943088Y380515D01*
X943001Y380363D01*
X941641Y381149D01*
X941729Y381300D01*
G37*
G36*
G01X924835Y391047D02*
X925473Y391452D01*
X926226Y391017D01*
X926194Y390262D01*
X926107Y390111D01*
X924747Y390895D01*
X924835Y391047D01*
G37*
G36*
G01X921455Y392997D02*
X922093Y393402D01*
X922846Y392967D01*
X922814Y392212D01*
X922727Y392061D01*
X921367Y392845D01*
X921455Y392997D01*
G37*
G36*
G01X913586Y399196D02*
X914371Y399486D01*
X915007Y398850D01*
X914717Y398065D01*
X914593Y397941D01*
X913462Y399073D01*
X913586Y399196D01*
G37*
G36*
G01X916344Y396438D02*
X917129Y396728D01*
X917765Y396092D01*
X917475Y395307D01*
X917351Y395183D01*
X916220Y396315D01*
X916344Y396438D01*
G37*
G36*
G01X938355Y383246D02*
X938993Y383651D01*
X939746Y383216D01*
X939714Y382461D01*
X939627Y382309D01*
X938267Y383095D01*
X938355Y383246D01*
G37*
G36*
G01X934969Y385200D02*
X935607Y385605D01*
X936360Y385170D01*
X936328Y384415D01*
X936241Y384263D01*
X934881Y385049D01*
X934969Y385200D01*
G37*
G36*
G01X931595Y387146D02*
X932233Y387551D01*
X932986Y387116D01*
X932954Y386361D01*
X932867Y386209D01*
X931507Y386995D01*
X931595Y387146D01*
G37*
G36*
G01X928209Y389100D02*
X928847Y389505D01*
X929600Y389070D01*
X929568Y388315D01*
X929481Y388163D01*
X928121Y388949D01*
X928209Y389100D01*
G37*
G36*
G01X932083Y402682D02*
X931298Y402392D01*
X930662Y403028D01*
X930952Y403813D01*
X931075Y403937D01*
X932207Y402805D01*
X932083Y402682D01*
G37*
G36*
G01X934841Y399924D02*
X934056Y399634D01*
X933420Y400270D01*
X933710Y401055D01*
X933833Y401179D01*
X934965Y400047D01*
X934841Y399924D01*
G37*
G36*
G01X937147Y397667D02*
X936509Y397262D01*
X935756Y397697D01*
X935788Y398452D01*
X935875Y398603D01*
X937235Y397818D01*
X937147Y397667D01*
G37*
G36*
G01X940534Y395714D02*
X939896Y395309D01*
X939143Y395744D01*
X939175Y396499D01*
X939262Y396651D01*
X940622Y395865D01*
X940534Y395714D01*
G37*
G36*
G01X950691Y389870D02*
X950053Y389465D01*
X949300Y389900D01*
X949332Y390655D01*
X949419Y390806D01*
X950779Y390022D01*
X950691Y389870D01*
G37*
G36*
G01X953769Y381519D02*
X954439Y381169D01*
Y380299D01*
X953769Y379949D01*
X953594D01*
Y381519D01*
X953769D01*
G37*
G36*
G01X952896Y377955D02*
X952226Y378305D01*
Y379175D01*
X952896Y379525D01*
X953071D01*
Y377955D01*
X952896D01*
G37*
G36*
G01X943899Y393772D02*
X943261Y393367D01*
X942508Y393802D01*
X942540Y394557D01*
X942627Y394709D01*
X943987Y393923D01*
X943899Y393772D01*
G37*
G36*
G01X947285Y391819D02*
X946647Y391414D01*
X945894Y391849D01*
X945926Y392604D01*
X946013Y392755D01*
X947373Y391970D01*
X947285Y391819D01*
G37*
G36*
G01X934486Y401831D02*
X935271Y402121D01*
X935907Y401485D01*
X935617Y400700D01*
X935494Y400576D01*
X934362Y401708D01*
X934486Y401831D01*
G37*
G36*
G01X938355Y398846D02*
X938993Y399251D01*
X939746Y398816D01*
X939714Y398061D01*
X939627Y397909D01*
X938267Y398695D01*
X938355Y398846D01*
G37*
G36*
G01X952511Y390803D02*
X953232Y391029D01*
X953847Y390414D01*
X953621Y389693D01*
X953497Y389569D01*
X952387Y390679D01*
X952511Y390803D01*
G37*
G36*
G01X954010Y387045D02*
X954765Y387011D01*
X955133Y386223D01*
X954673Y385623D01*
X954515Y385549D01*
X953851Y386971D01*
X954010Y387045D01*
G37*
G36*
G01X941720Y396905D02*
X942358Y397310D01*
X943111Y396875D01*
X943079Y396120D01*
X942992Y395968D01*
X941632Y396753D01*
X941720Y396905D01*
G37*
G36*
G01X945109Y394950D02*
X945747Y395355D01*
X946500Y394920D01*
X946468Y394165D01*
X946381Y394013D01*
X945021Y394799D01*
X945109Y394950D01*
G37*
G36*
G01X948489Y393000D02*
X949127Y393405D01*
X949880Y392970D01*
X949848Y392215D01*
X949761Y392063D01*
X948401Y392849D01*
X948489Y393000D01*
G37*
G36*
G01X929026Y370765D02*
X928994Y371520D01*
X929747Y371955D01*
X930385Y371550D01*
X930473Y371399D01*
X929113Y370613D01*
X929026Y370765D01*
G37*
G36*
G01X932415Y372720D02*
X932383Y373475D01*
X933136Y373910D01*
X933774Y373505D01*
X933862Y373353D01*
X932502Y372568D01*
X932415Y372720D01*
G37*
G36*
G01X925679Y368839D02*
X925647Y369594D01*
X926400Y370029D01*
X927038Y369624D01*
X927126Y369473D01*
X925766Y368687D01*
X925679Y368839D01*
G37*
G36*
G01X918610Y367200D02*
X918960Y367960D01*
X919860D01*
X920210Y367200D01*
Y367025D01*
X918610D01*
Y367200D01*
G37*
G36*
G01X910901Y369466D02*
X911251Y370226D01*
X912151D01*
X912501Y369466D01*
Y369291D01*
X910901D01*
Y369466D01*
G37*
G36*
G01X928200Y396905D02*
X928838Y397310D01*
X929591Y396875D01*
X929559Y396120D01*
X929472Y395968D01*
X928112Y396753D01*
X928200Y396905D01*
G37*
G36*
G01X931589Y394950D02*
X932227Y395355D01*
X932980Y394920D01*
X932948Y394165D01*
X932861Y394013D01*
X931501Y394799D01*
X931589Y394950D01*
G37*
G36*
G01X934975Y392997D02*
X935613Y393402D01*
X936366Y392967D01*
X936334Y392212D01*
X936247Y392061D01*
X934887Y392845D01*
X934975Y392997D01*
G37*
G36*
G01X938340Y391055D02*
X938978Y391460D01*
X939731Y391025D01*
X939699Y390270D01*
X939612Y390118D01*
X938252Y390903D01*
X938340Y391055D01*
G37*
G36*
G01X924835Y398846D02*
X925473Y399251D01*
X926226Y398816D01*
X926194Y398061D01*
X926107Y397909D01*
X924747Y398695D01*
X924835Y398846D01*
G37*
G36*
G01X921057Y401671D02*
X921778Y401897D01*
X922393Y401282D01*
X922167Y400561D01*
X922043Y400437D01*
X920933Y401548D01*
X921057Y401671D01*
G37*
G36*
G01X941729Y389100D02*
X942367Y389505D01*
X943120Y389070D01*
X943088Y388315D01*
X943001Y388163D01*
X941641Y388949D01*
X941729Y389100D01*
G37*
G36*
G01X945115Y387146D02*
X945753Y387551D01*
X946506Y387116D01*
X946474Y386361D01*
X946387Y386209D01*
X945027Y386995D01*
X945115Y387146D01*
G37*
G36*
G01X948488Y385201D02*
X949126Y385606D01*
X949879Y385172D01*
X949847Y384416D01*
X949761Y384265D01*
X948400Y385050D01*
X948488Y385201D01*
G37*
G36*
G01X950389Y379520D02*
X951059Y379170D01*
Y378300D01*
X950389Y377950D01*
X950214D01*
Y379520D01*
X950389D01*
G37*
G36*
G01X968951Y400823D02*
X969711Y400473D01*
Y399573D01*
X968951Y399223D01*
X968776D01*
Y400823D01*
X968951D01*
G37*
G36*
G01X970204Y396759D02*
X970988Y397049D01*
X971625Y396412D01*
X971335Y395628D01*
X971211Y395504D01*
X970080Y396635D01*
X970204Y396759D01*
G37*
G36*
G01X915356Y371666D02*
X915006Y370906D01*
X914106D01*
X913756Y371666D01*
Y371841D01*
X915356D01*
Y371666D01*
G37*
G36*
G01X919256D02*
X918906Y370906D01*
X918006D01*
X917656Y371666D01*
Y371841D01*
X919256D01*
Y371666D01*
G37*
G36*
G01X923162Y370410D02*
X922812Y369650D01*
X921912D01*
X921562Y370410D01*
Y370585D01*
X923162D01*
Y370410D01*
G37*
G36*
G01X930385Y397668D02*
X929747Y397263D01*
X928994Y397698D01*
X929026Y398453D01*
X929113Y398605D01*
X930473Y397819D01*
X930385Y397668D01*
G37*
G36*
G01X933774Y395714D02*
X933136Y395309D01*
X932383Y395744D01*
X932415Y396499D01*
X932502Y396651D01*
X933862Y395865D01*
X933774Y395714D01*
G37*
G36*
G01X937139Y393772D02*
X936501Y393367D01*
X935748Y393802D01*
X935780Y394557D01*
X935867Y394709D01*
X937227Y393923D01*
X937139Y393772D01*
G37*
G36*
G01X940525Y391819D02*
X939887Y391414D01*
X939134Y391849D01*
X939166Y392604D01*
X939253Y392755D01*
X940613Y391970D01*
X940525Y391819D01*
G37*
G36*
G01X927305Y401251D02*
X926519Y400963D01*
X925884Y401601D01*
X926176Y402385D01*
X926300Y402509D01*
X927429Y401375D01*
X927305Y401251D01*
G37*
G36*
G01X943914Y389864D02*
X943276Y389459D01*
X942523Y389894D01*
X942555Y390649D01*
X942642Y390801D01*
X944002Y390015D01*
X943914Y389864D01*
G37*
G36*
G01X947279Y387923D02*
X946641Y387518D01*
X945888Y387953D01*
X945920Y388708D01*
X946007Y388860D01*
X947367Y388075D01*
X947279Y387923D01*
G37*
G36*
G01X929568Y369204D02*
X929600Y368449D01*
X928847Y368014D01*
X928209Y368419D01*
X928121Y368570D01*
X929481Y369355D01*
X929568Y369204D01*
G37*
G36*
G01X932954Y371157D02*
X932986Y370402D01*
X932233Y369967D01*
X931595Y370372D01*
X931507Y370523D01*
X932867Y371309D01*
X932954Y371157D01*
G37*
G36*
G01X920210Y366100D02*
X919860Y365340D01*
X918960D01*
X918610Y366100D01*
Y366275D01*
X920210D01*
Y366100D01*
G37*
G36*
G01X926179Y367249D02*
X926211Y366494D01*
X925458Y366059D01*
X924820Y366464D01*
X924732Y366615D01*
X926092Y367401D01*
X926179Y367249D01*
G37*
G36*
G01X912501Y368366D02*
X912151Y367606D01*
X911251D01*
X910901Y368366D01*
Y368541D01*
X912501D01*
Y368366D01*
G37*
G36*
G01X937154Y389864D02*
X936516Y389459D01*
X935763Y389894D01*
X935795Y390649D01*
X935882Y390801D01*
X937242Y390015D01*
X937154Y389864D01*
G37*
G36*
G01X940519Y387923D02*
X939881Y387518D01*
X939128Y387953D01*
X939160Y388708D01*
X939247Y388860D01*
X940607Y388075D01*
X940519Y387923D01*
G37*
G36*
G01X930379Y393772D02*
X929741Y393367D01*
X928988Y393802D01*
X929020Y394557D01*
X929107Y394709D01*
X930467Y393923D01*
X930379Y393772D01*
G37*
G36*
G01X933765Y391819D02*
X933127Y391414D01*
X932374Y391849D01*
X932406Y392604D01*
X932493Y392755D01*
X933853Y391970D01*
X933765Y391819D01*
G37*
G36*
G01X923625Y397669D02*
X922987Y397264D01*
X922234Y397699D01*
X922266Y398454D01*
X922353Y398605D01*
X923713Y397820D01*
X923625Y397669D01*
G37*
G36*
G01X927014Y395714D02*
X926376Y395309D01*
X925623Y395744D01*
X925655Y396499D01*
X925742Y396651D01*
X927102Y395865D01*
X927014Y395714D01*
G37*
G36*
G01X943905Y385969D02*
X943267Y385564D01*
X942514Y385999D01*
X942546Y386754D01*
X942633Y386905D01*
X943993Y386120D01*
X943905Y385969D01*
G37*
G36*
G01X947279Y384023D02*
X946641Y383618D01*
X945888Y384053D01*
X945920Y384808D01*
X946007Y384960D01*
X947367Y384175D01*
X947279Y384023D01*
G37*
G36*
G01X948765Y379949D02*
X948095Y380299D01*
Y381169D01*
X948765Y381519D01*
X948940D01*
Y379949D01*
X948765D01*
G37*
G36*
G01X950632Y374256D02*
X949962Y373908D01*
X949249Y374407D01*
X949347Y375156D01*
X949447Y375299D01*
X950733Y374400D01*
X950632Y374256D01*
G37*
G36*
G01X948765Y376049D02*
X948095Y376399D01*
Y377269D01*
X948765Y377619D01*
X948940D01*
Y376049D01*
X948765D01*
G37*
G36*
G01X972029Y387661D02*
X971269Y388011D01*
Y388911D01*
X972029Y389261D01*
X972204D01*
Y387661D01*
X972029D01*
G37*
G36*
G01Y383761D02*
X971269Y384111D01*
Y385011D01*
X972029Y385361D01*
X972204D01*
Y383761D01*
X972029D01*
G37*
G36*
G01X970957Y394450D02*
X970172Y394160D01*
X969536Y394796D01*
X969826Y395581D01*
X969949Y395705D01*
X971081Y394573D01*
X970957Y394450D01*
G37*
G36*
G01X967851Y399223D02*
X967091Y399573D01*
Y400473D01*
X967851Y400823D01*
X968026D01*
Y399223D01*
X967851D01*
G37*
G36*
G01X913756Y372766D02*
X914106Y373526D01*
X915006D01*
X915356Y372766D01*
Y372591D01*
X913756D01*
Y372766D01*
G37*
G36*
G01X917656D02*
X918006Y373526D01*
X918906D01*
X919256Y372766D01*
Y372591D01*
X917656D01*
Y372766D01*
G37*
G36*
G01X921562Y371510D02*
X921912Y372270D01*
X922812D01*
X923162Y371510D01*
Y371335D01*
X921562D01*
Y371510D01*
G37*
G36*
G01X910045Y374361D02*
X910829Y374651D01*
X911466Y374014D01*
X911176Y373230D01*
X911052Y373106D01*
X909921Y374237D01*
X910045Y374361D01*
G37*
G36*
G01X926956Y403163D02*
X927742Y403451D01*
X928377Y402813D01*
X928085Y402029D01*
X927961Y401905D01*
X926832Y403039D01*
X926956Y403163D01*
G37*
G36*
G01X931595Y398846D02*
X932233Y399251D01*
X932986Y398816D01*
X932954Y398061D01*
X932867Y397909D01*
X931507Y398695D01*
X931595Y398846D01*
G37*
G36*
G01X934960Y396905D02*
X935598Y397310D01*
X936351Y396875D01*
X936319Y396120D01*
X936232Y395968D01*
X934872Y396753D01*
X934960Y396905D01*
G37*
G36*
G01X938349Y394950D02*
X938987Y395355D01*
X939740Y394920D01*
X939708Y394165D01*
X939621Y394013D01*
X938261Y394799D01*
X938349Y394950D01*
G37*
G36*
G01X948489Y389100D02*
X949127Y389505D01*
X949880Y389070D01*
X949848Y388315D01*
X949761Y388163D01*
X948401Y388949D01*
X948489Y389100D01*
G37*
G36*
G01X941735Y392997D02*
X942373Y393402D01*
X943126Y392967D01*
X943094Y392212D01*
X943007Y392061D01*
X941647Y392845D01*
X941735Y392997D01*
G37*
G36*
G01X945100Y391055D02*
X945738Y391460D01*
X946491Y391025D01*
X946459Y390270D01*
X946372Y390118D01*
X945012Y390903D01*
X945100Y391055D01*
G37*
G36*
G01X969044Y387749D02*
X968374Y388099D01*
Y388969D01*
X969044Y389319D01*
X969219D01*
Y387749D01*
X969044D01*
G37*
G36*
G01Y372124D02*
X968374Y372474D01*
Y373344D01*
X969044Y373694D01*
X969219D01*
Y372124D01*
X969044D01*
G37*
G36*
G01X969045Y364359D02*
X968375Y364709D01*
Y365578D01*
X969044Y365928D01*
X969220Y365929D01*
X969219Y364359D01*
X969045D01*
G37*
G36*
G01X969044Y368200D02*
X968374Y368550D01*
Y369420D01*
X969044Y369770D01*
X969219D01*
Y368200D01*
X969044D01*
G37*
G36*
G01X970945Y362568D02*
X970307Y362163D01*
X969554Y362597D01*
X969586Y363352D01*
X969673Y363505D01*
X971032Y362719D01*
X970945Y362568D01*
G37*
G36*
G01X969044Y383824D02*
X968374Y384174D01*
Y385044D01*
X969044Y385394D01*
X969219D01*
Y383824D01*
X969044D01*
G37*
G36*
G01Y379949D02*
X968374Y380299D01*
Y381169D01*
X969044Y381519D01*
X969219D01*
Y379949D01*
X969044D01*
G37*
G36*
G01Y376049D02*
X968374Y376399D01*
Y377269D01*
X969044Y377619D01*
X969219D01*
Y376049D01*
X969044D01*
G37*
G36*
G01X963527Y396691D02*
X962767Y397041D01*
Y397941D01*
X963527Y398291D01*
X963702D01*
Y396691D01*
X963527D01*
G37*
G36*
G01X967564Y391819D02*
X966926Y391414D01*
X966173Y391849D01*
X966205Y392604D01*
X966292Y392755D01*
X967652Y391970D01*
X967564Y391819D01*
G37*
G36*
G01X970668Y391220D02*
X971338Y390870D01*
Y390000D01*
X970668Y389650D01*
X970493D01*
Y391220D01*
X970668D01*
G37*
G36*
G01Y371769D02*
X971338Y371419D01*
Y370549D01*
X970668Y370199D01*
X970493D01*
Y371769D01*
X970668D01*
G37*
G36*
G01Y367845D02*
X971338Y367495D01*
Y366625D01*
X970668Y366275D01*
X970493D01*
Y367845D01*
X970668D01*
G37*
G36*
G01Y387320D02*
X971338Y386970D01*
Y386100D01*
X970668Y385750D01*
X970493D01*
Y387320D01*
X970668D01*
G37*
G36*
G01Y383469D02*
X971338Y383119D01*
Y382249D01*
X970668Y381899D01*
X970493D01*
Y383469D01*
X970668D01*
G37*
G36*
G01Y379520D02*
X971338Y379170D01*
Y378300D01*
X970668Y377950D01*
X970493D01*
Y379520D01*
X970668D01*
G37*
G36*
G01Y375620D02*
X971338Y375270D01*
Y374400D01*
X970668Y374050D01*
X970493D01*
Y375620D01*
X970668D01*
G37*
G36*
G01X965321Y395549D02*
X966106Y395839D01*
X966742Y395203D01*
X966452Y394418D01*
X966329Y394294D01*
X965197Y395426D01*
X965321Y395549D01*
G37*
G36*
G01X964625Y398291D02*
X965385Y397941D01*
Y397041D01*
X964625Y396691D01*
X964450D01*
Y398291D01*
X964625D01*
G37*
G36*
G01X958956Y395181D02*
X958197Y395530D01*
Y396431D01*
X958956Y396780D01*
X959132D01*
Y395181D01*
X958956D01*
G37*
G36*
G01X961599Y391450D02*
X960815Y391160D01*
X960178Y391797D01*
X960468Y392581D01*
X960592Y392705D01*
X961723Y391574D01*
X961599Y391450D01*
G37*
G36*
G01X969048Y356482D02*
X968378Y356828D01*
X968374Y357699D01*
X969043Y358050D01*
X969218Y358051D01*
X969224Y356482D01*
X969048D01*
G37*
G36*
G01X970936Y354724D02*
X970266Y354376D01*
X969553Y354875D01*
X969651Y355624D01*
X969751Y355767D01*
X971037Y354868D01*
X970936Y354724D01*
G37*
G36*
G01X965664Y362393D02*
X964995Y362743D01*
X964994Y363612D01*
X965664Y363962D01*
X965840Y363963D01*
X965839Y362392D01*
X965664Y362393D01*
G37*
G36*
G01Y370199D02*
X964994Y370549D01*
Y371419D01*
X965664Y371769D01*
X965839D01*
Y370199D01*
X965664D01*
G37*
G36*
G01Y366275D02*
X964994Y366625D01*
Y367495D01*
X965664Y367845D01*
X965839D01*
Y366275D01*
X965664D01*
G37*
G36*
G01Y385750D02*
X964994Y386100D01*
Y386970D01*
X965664Y387320D01*
X965839D01*
Y385750D01*
X965664D01*
G37*
G36*
G01Y381850D02*
X964994Y382200D01*
Y383070D01*
X965664Y383420D01*
X965839D01*
Y381850D01*
X965664D01*
G37*
G36*
G01Y377950D02*
X964994Y378300D01*
Y379170D01*
X965664Y379520D01*
X965839D01*
Y377950D01*
X965664D01*
G37*
G36*
G01Y374050D02*
X964994Y374400D01*
Y375270D01*
X965664Y375620D01*
X965839D01*
Y374050D01*
X965664D01*
G37*
G36*
G01X967579Y360610D02*
X966942Y360205D01*
X966188Y360639D01*
X966220Y361394D01*
X966308Y361547D01*
X967668Y360761D01*
X967579Y360610D01*
G37*
G36*
G01X960058Y396780D02*
X960818Y396430D01*
Y395531D01*
X960058Y395181D01*
X959883Y395180D01*
Y396781D01*
X960058Y396780D01*
G37*
G36*
G01X961247Y393360D02*
X962032Y393650D01*
X962668Y393014D01*
X962378Y392229D01*
X962255Y392105D01*
X961123Y393237D01*
X961247Y393360D01*
G37*
G36*
G01X970667Y360010D02*
X971337Y359660D01*
Y358791D01*
X970667Y358441D01*
X970492Y358440D01*
X970493Y360010D01*
X970667D01*
G37*
G36*
G01X967288Y389283D02*
X967958Y388933D01*
Y388063D01*
X967288Y387713D01*
X967114Y387712D01*
X967113Y389283D01*
X967288D01*
G37*
G36*
G01Y373694D02*
X967958Y373344D01*
Y372474D01*
X967288Y372124D01*
X967113D01*
Y373694D01*
X967288D01*
G37*
G36*
G01X968767Y361801D02*
X969405Y362206D01*
X970158Y361772D01*
X970126Y361016D01*
X970039Y360864D01*
X968680Y361650D01*
X968767Y361801D01*
G37*
G36*
G01X967288Y369770D02*
X967958Y369420D01*
Y368550D01*
X967288Y368200D01*
X967113D01*
Y369770D01*
X967288D01*
G37*
G36*
G01Y365919D02*
X967958Y365569D01*
Y364699D01*
X967288Y364349D01*
X967113D01*
Y365919D01*
X967288D01*
G37*
G36*
G01Y385419D02*
X967958Y385069D01*
Y384199D01*
X967288Y383849D01*
X967113D01*
Y385419D01*
X967288D01*
G37*
G36*
G01Y381519D02*
X967958Y381169D01*
Y380299D01*
X967288Y379949D01*
X967113D01*
Y381519D01*
X967288D01*
G37*
G36*
G01Y377619D02*
X967958Y377269D01*
Y376399D01*
X967288Y376049D01*
X967113D01*
Y377619D01*
X967288D01*
G37*
G36*
G01X965367Y391063D02*
X966005Y391468D01*
X966758Y391033D01*
X966726Y390278D01*
X966640Y390127D01*
X965279Y390911D01*
X965367Y391063D01*
G37*
G36*
G01X912458Y404672D02*
X911673Y404382D01*
X911036Y405018D01*
X911326Y405803D01*
X911450Y405927D01*
X912581Y404796D01*
X912458Y404672D01*
G37*
G36*
G01X912103Y406580D02*
X912888Y406870D01*
X913524Y406233D01*
X913234Y405448D01*
X913110Y405325D01*
X911979Y406456D01*
X912103Y406580D01*
G37*
G36*
G01X934431Y407569D02*
X933646Y407279D01*
X933010Y407915D01*
X933300Y408700D01*
X933423Y408824D01*
X934555Y407692D01*
X934431Y407569D01*
G37*
G36*
G01X931673Y410327D02*
X930888Y410037D01*
X930252Y410673D01*
X930542Y411458D01*
X930665Y411582D01*
X931797Y410450D01*
X931673Y410327D01*
G37*
G36*
G01X934076Y409476D02*
X934861Y409766D01*
X935497Y409130D01*
X935207Y408345D01*
X935084Y408221D01*
X933952Y409353D01*
X934076Y409476D01*
G37*
G36*
G01X936128Y404744D02*
X936913Y405034D01*
X937549Y404398D01*
X937259Y403613D01*
X937136Y403489D01*
X936004Y404621D01*
X936128Y404744D01*
G37*
G36*
G01X931318Y412234D02*
X932103Y412524D01*
X932739Y411888D01*
X932449Y411103D01*
X932326Y410979D01*
X931194Y412111D01*
X931318Y412234D01*
G37*
G36*
G01X929325Y405440D02*
X928540Y405150D01*
X927904Y405786D01*
X928194Y406571D01*
X928317Y406695D01*
X929449Y405563D01*
X929325Y405440D01*
G37*
G36*
G01X926567Y408198D02*
X925782Y407908D01*
X925146Y408544D01*
X925436Y409329D01*
X925559Y409453D01*
X926691Y408321D01*
X926567Y408198D01*
G37*
G36*
G01X928970Y407347D02*
X929755Y407637D01*
X930391Y407001D01*
X930101Y406216D01*
X929978Y406092D01*
X928846Y407224D01*
X928970Y407347D01*
G37*
G36*
G01X931728Y404589D02*
X932513Y404879D01*
X933149Y404243D01*
X932859Y403458D01*
X932736Y403334D01*
X931604Y404466D01*
X931728Y404589D01*
G37*
G36*
G01X926212Y410105D02*
X926997Y410395D01*
X927633Y409759D01*
X927343Y408974D01*
X927220Y408850D01*
X926088Y409982D01*
X926212Y410105D01*
G37*
G36*
G01X919045Y409538D02*
X918259Y409250D01*
X917624Y409888D01*
X917916Y410672D01*
X918040Y410795D01*
X919169Y409661D01*
X919045Y409538D01*
G37*
G36*
G01X924547Y404009D02*
X923761Y403721D01*
X923126Y404359D01*
X923418Y405143D01*
X923542Y405267D01*
X924671Y404133D01*
X924547Y404009D01*
G37*
G36*
G01X921796Y406774D02*
X921010Y406485D01*
X920375Y407123D01*
X920667Y407908D01*
X920791Y408031D01*
X921920Y406897D01*
X921796Y406774D01*
G37*
G36*
G01X971814Y403228D02*
X971054Y403578D01*
Y404478D01*
X971814Y404828D01*
X971989D01*
Y403228D01*
X971814D01*
G37*
G36*
G01X918696Y411449D02*
X919482Y411737D01*
X920117Y411100D01*
X919825Y410315D01*
X919701Y410192D01*
X918572Y411326D01*
X918696Y411449D01*
G37*
G36*
G01X924198Y405921D02*
X924984Y406209D01*
X925619Y405571D01*
X925327Y404787D01*
X925203Y404663D01*
X924074Y405797D01*
X924198Y405921D01*
G37*
G36*
G01X921447Y408685D02*
X922233Y408973D01*
X922868Y408335D01*
X922576Y407551D01*
X922452Y407428D01*
X921323Y408562D01*
X921447Y408685D01*
G37*
G36*
G01X972903Y204945D02*
X973663Y204595D01*
Y203695D01*
X972903Y203345D01*
X972728D01*
Y204945D01*
X972903D01*
G37*
G36*
G01X972197Y197699D02*
X971907Y198484D01*
X972543Y199120D01*
X973328Y198830D01*
X973452Y198707D01*
X972320Y197575D01*
X972197Y197699D01*
G37*
G36*
G01X972423Y217475D02*
X971663Y217825D01*
Y218725D01*
X972423Y219075D01*
X972598D01*
Y217475D01*
X972423D01*
G37*
G36*
G01Y213575D02*
X971663Y213925D01*
Y214825D01*
X972423Y215175D01*
X972598D01*
Y213575D01*
X972423D01*
G37*
G36*
G01Y209675D02*
X971663Y210025D01*
Y210925D01*
X972423Y211275D01*
X972598D01*
Y209675D01*
X972423D01*
G37*
G36*
G01X975221Y204186D02*
X974461Y204536D01*
Y205436D01*
X975221Y205786D01*
X975396D01*
Y204186D01*
X975221D01*
G37*
G36*
G01X974106Y198052D02*
X974396Y197268D01*
X973759Y196631D01*
X972975Y196921D01*
X972851Y197045D01*
X973982Y198176D01*
X974106Y198052D01*
G37*
G36*
G01X973523Y218075D02*
X974283Y217725D01*
Y216825D01*
X973523Y216475D01*
X973348D01*
Y218075D01*
X973523D01*
G37*
G36*
G01Y214175D02*
X974283Y213825D01*
Y212925D01*
X973523Y212575D01*
X973348D01*
Y214175D01*
X973523D01*
G37*
G36*
G01X974086Y208940D02*
X974870Y209230D01*
X975507Y208593D01*
X975217Y207809D01*
X975093Y207685D01*
X973962Y208816D01*
X974086Y208940D01*
G37*
G36*
G01X976321Y205786D02*
X977081Y205436D01*
Y204536D01*
X976321Y204186D01*
X976146D01*
Y205786D01*
X976321D01*
G37*
G36*
G01X979969Y195720D02*
X979209Y196070D01*
Y196970D01*
X979969Y197320D01*
X980144D01*
Y195720D01*
X979969D01*
G37*
G36*
G01X981059Y212320D02*
X980299Y212670D01*
Y213570D01*
X981059Y213920D01*
X981234D01*
Y212320D01*
X981059D01*
G37*
G36*
G01Y208420D02*
X980299Y208770D01*
Y209670D01*
X981059Y210020D01*
X981234D01*
Y208420D01*
X981059D01*
G37*
G36*
G01Y204520D02*
X980299Y204870D01*
Y205770D01*
X981059Y206120D01*
X981234D01*
Y204520D01*
X981059D01*
G37*
G36*
G01X981069Y197320D02*
X981829Y196970D01*
Y196070D01*
X981069Y195720D01*
X980894D01*
Y197320D01*
X981069D01*
G37*
G36*
G01X982159Y213920D02*
X982919Y213570D01*
Y212670D01*
X982159Y212320D01*
X981984D01*
Y213920D01*
X982159D01*
G37*
G36*
G01Y210020D02*
X982919Y209670D01*
Y208770D01*
X982159Y208420D01*
X981984D01*
Y210020D01*
X982159D01*
G37*
G36*
G01Y206120D02*
X982919Y205770D01*
Y204870D01*
X982159Y204520D01*
X981984D01*
Y206120D01*
X982159D01*
G37*
G36*
G01X978041Y202071D02*
X977281Y202421D01*
Y203321D01*
X978041Y203671D01*
X978216D01*
Y202071D01*
X978041D01*
G37*
G36*
G01X975488Y195950D02*
X975198Y196735D01*
X975834Y197371D01*
X976619Y197081D01*
X976743Y196958D01*
X975611Y195826D01*
X975488Y195950D01*
G37*
G36*
G01X978041Y209871D02*
X977281Y210221D01*
Y211121D01*
X978041Y211471D01*
X978216D01*
Y209871D01*
X978041D01*
G37*
G36*
G01X976881Y215367D02*
X976121Y215717D01*
Y216617D01*
X976881Y216967D01*
X977056D01*
Y215367D01*
X976881D01*
G37*
G36*
G01X978041Y205971D02*
X977281Y206321D01*
Y207221D01*
X978041Y207571D01*
X978216D01*
Y205971D01*
X978041D01*
G37*
G36*
G01X979139Y204071D02*
X979899Y203721D01*
Y202821D01*
X979139Y202471D01*
X978964D01*
Y204071D01*
X979139D01*
G37*
G36*
G01X977397Y196303D02*
X977687Y195519D01*
X977050Y194882D01*
X976266Y195172D01*
X976142Y195296D01*
X977273Y196427D01*
X977397Y196303D01*
G37*
G36*
G01X979139Y211471D02*
X979899Y211121D01*
Y210221D01*
X979139Y209871D01*
X978964D01*
Y211471D01*
X979139D01*
G37*
G36*
G01X977981Y217667D02*
X978741Y217317D01*
Y216417D01*
X977981Y216067D01*
X977806D01*
Y217667D01*
X977981D01*
G37*
G36*
G01X979139Y207571D02*
X979899Y207221D01*
Y206321D01*
X979139Y205971D01*
X978964D01*
Y207571D01*
X979139D01*
G37*
G36*
G01X976887Y232705D02*
X976919Y231950D01*
X976166Y231515D01*
X975528Y231920D01*
X975440Y232071D01*
X976800Y232857D01*
X976887Y232705D01*
G37*
G36*
G01X973514Y230758D02*
X973546Y230003D01*
X972793Y229568D01*
X972155Y229973D01*
X972067Y230125D01*
X973427Y230910D01*
X973514Y230758D01*
G37*
G36*
G01X972424Y221950D02*
X971754Y222300D01*
Y223170D01*
X972424Y223520D01*
X972599D01*
Y221950D01*
X972424D01*
G37*
G36*
G01X972425Y225832D02*
X971755Y226182D01*
Y227052D01*
X972425Y227402D01*
X972600Y227403D01*
Y225832D01*
X972425D01*
G37*
G36*
G01X972959Y228412D02*
X972927Y229167D01*
X973680Y229602D01*
X974318Y229197D01*
X974406Y229046D01*
X973046Y228260D01*
X972959Y228412D01*
G37*
G36*
G01X976345Y230365D02*
X976313Y231120D01*
X977066Y231555D01*
X977704Y231150D01*
X977792Y230999D01*
X976432Y230213D01*
X976345Y230365D01*
G37*
G36*
G01X979184Y233650D02*
X978514Y234000D01*
Y234870D01*
X979184Y235220D01*
X979359D01*
Y233650D01*
X979184D01*
G37*
G36*
G01Y237550D02*
X978514Y237900D01*
Y238770D01*
X979184Y239120D01*
X979359D01*
Y237550D01*
X979184D01*
G37*
G36*
G01X977790Y241644D02*
X977152Y241239D01*
X976399Y241674D01*
X976431Y242429D01*
X976518Y242580D01*
X977878Y241795D01*
X977790Y241644D01*
G37*
G36*
G01X972974Y232320D02*
X972942Y233075D01*
X973695Y233510D01*
X974333Y233105D01*
X974421Y232953D01*
X973061Y232168D01*
X972974Y232320D01*
G37*
G36*
G01X974048Y221619D02*
X974718Y221269D01*
Y220399D01*
X974048Y220049D01*
X973873D01*
Y221619D01*
X974048D01*
G37*
G36*
G01X980807Y233337D02*
X981477Y232987D01*
Y232117D01*
X980807Y231767D01*
X980633D01*
Y233337D01*
X980807D01*
G37*
G36*
G01X976887Y228804D02*
X976919Y228049D01*
X976166Y227614D01*
X975528Y228019D01*
X975440Y228171D01*
X976800Y228956D01*
X976887Y228804D01*
G37*
G36*
G01X974048Y225519D02*
X974718Y225169D01*
Y224299D01*
X974048Y223949D01*
X973873D01*
Y225519D01*
X974048D01*
G37*
G36*
G01X980273Y230757D02*
X980305Y230002D01*
X979552Y229567D01*
X978914Y229972D01*
X978827Y230123D01*
X980187Y230908D01*
X980273Y230757D01*
G37*
G36*
G01X980808Y237219D02*
X981478Y236869D01*
Y235999D01*
X980808Y235649D01*
X980633D01*
Y237219D01*
X980808D01*
G37*
G36*
G01Y241076D02*
X981477Y240726D01*
X981478Y239857D01*
X980808Y239507D01*
X980632Y239506D01*
Y241077D01*
X980808Y241076D01*
G37*
G36*
G01X973507Y234653D02*
X973539Y233898D01*
X972786Y233463D01*
X972148Y233868D01*
X972060Y234019D01*
X973420Y234805D01*
X973507Y234653D01*
G37*
G36*
G01X979185Y218075D02*
X978515Y218425D01*
Y219295D01*
X979185Y219645D01*
X979360D01*
Y218075D01*
X979185D01*
G37*
G36*
G01Y221941D02*
X978515Y222291D01*
Y223160D01*
X979185Y223510D01*
X979359D01*
X979360Y221940D01*
X979185Y221941D01*
G37*
G36*
G01X979726Y224517D02*
X979694Y225272D01*
X980447Y225706D01*
X981085Y225301D01*
X981172Y225150D01*
X979813Y224364D01*
X979726Y224517D01*
G37*
G36*
G01X983114Y226470D02*
X983082Y227225D01*
X983835Y227660D01*
X984473Y227255D01*
X984561Y227103D01*
X983201Y226318D01*
X983114Y226470D01*
G37*
G36*
G01X985944Y229799D02*
X985274Y230149D01*
Y231019D01*
X985944Y231369D01*
X986119D01*
Y229799D01*
X985944D01*
G37*
G36*
G01Y233650D02*
X985274Y234000D01*
Y234870D01*
X985944Y235220D01*
X986119D01*
Y233650D01*
X985944D01*
G37*
G36*
G01X987568Y233294D02*
X988238Y232944D01*
Y232074D01*
X987568Y231724D01*
X987393D01*
Y233294D01*
X987568D01*
G37*
G36*
G01X987570Y229389D02*
X988239Y229037D01*
X988236Y228167D01*
X987565Y227819D01*
X987390D01*
X987394Y229389D01*
X987570D01*
G37*
G36*
G01X983653Y224908D02*
X983685Y224153D01*
X982932Y223718D01*
X982294Y224123D01*
X982206Y224274D01*
X983566Y225060D01*
X983653Y224908D01*
G37*
G36*
G01X980808Y221619D02*
X981478Y221269D01*
Y220399D01*
X980808Y220049D01*
X980633D01*
Y221619D01*
X980808D01*
G37*
G36*
G01X987278Y227202D02*
X987442Y226464D01*
X986776Y225904D01*
X986077Y226192D01*
X985964Y226325D01*
X987165Y227336D01*
X987278Y227202D01*
G37*
G36*
G01X987563Y241120D02*
X988236Y240774D01*
X988240Y239904D01*
X987572Y239550D01*
X987396D01*
X987389Y241119D01*
X987563Y241120D01*
G37*
G36*
G01X987568Y237219D02*
X988238Y236869D01*
Y235999D01*
X987568Y235649D01*
X987393D01*
Y237219D01*
X987568D01*
G37*
G36*
G01X975804Y220049D02*
X975134Y220399D01*
Y221269D01*
X975804Y221619D01*
X975979D01*
Y220049D01*
X975804D01*
G37*
G36*
G01X976374Y226484D02*
X976343Y227239D01*
X977096Y227673D01*
X977734Y227268D01*
X977822Y227117D01*
X976462Y226331D01*
X976374Y226484D01*
G37*
G36*
G01X979719Y228412D02*
X979687Y229167D01*
X980440Y229602D01*
X981078Y229197D01*
X981166Y229045D01*
X979806Y228261D01*
X979719Y228412D01*
G37*
G36*
G01X982564Y231724D02*
X981894Y232074D01*
Y232944D01*
X982564Y233294D01*
X982739D01*
Y231724D01*
X982564D01*
G37*
G36*
G01X975803Y223924D02*
X975134Y224274D01*
Y225143D01*
X975804Y225493D01*
X975979Y225494D01*
Y223923D01*
X975803Y223924D01*
G37*
G36*
G01X977428Y223520D02*
X978098Y223170D01*
Y222300D01*
X977428Y221950D01*
X977253D01*
Y223520D01*
X977428D01*
G37*
G36*
G01X984188Y235220D02*
X984858Y234870D01*
Y234000D01*
X984188Y233650D01*
X984013D01*
Y235220D01*
X984188D01*
G37*
G36*
G01X984187Y231378D02*
X984857Y231028D01*
Y230159D01*
X984187Y229809D01*
X984013D01*
X984012Y231379D01*
X984187Y231378D01*
G37*
G36*
G01X980258Y226849D02*
X980290Y226094D01*
X979537Y225659D01*
X978899Y226064D01*
X978811Y226215D01*
X980171Y227001D01*
X980258Y226849D01*
G37*
G36*
G01X983646Y228802D02*
X983678Y228047D01*
X982925Y227613D01*
X982287Y228018D01*
X982200Y228169D01*
X983559Y228955D01*
X983646Y228802D01*
G37*
G36*
G01X984188Y239120D02*
X984858Y238770D01*
Y237900D01*
X984188Y237550D01*
X984013D01*
Y239120D01*
X984188D01*
G37*
G36*
G01X977428Y360020D02*
X978098Y359670D01*
Y358800D01*
X977428Y358450D01*
X977253D01*
Y360020D01*
X977428D01*
G37*
G36*
G01Y356120D02*
X978098Y355770D01*
Y354900D01*
X977428Y354550D01*
X977253D01*
Y356120D01*
X977428D01*
G37*
G36*
G01X973129Y389261D02*
X973889Y388911D01*
Y388011D01*
X973129Y387661D01*
X972954D01*
Y389261D01*
X973129D01*
G37*
G36*
G01X974048Y373694D02*
X974718Y373344D01*
Y372474D01*
X974048Y372124D01*
X973873D01*
Y373694D01*
X974048D01*
G37*
G36*
G01Y369770D02*
X974718Y369420D01*
Y368550D01*
X974048Y368200D01*
X973873D01*
Y369770D01*
X974048D01*
G37*
G36*
G01X975527Y365701D02*
X976165Y366106D01*
X976918Y365672D01*
X976886Y364916D01*
X976799Y364764D01*
X975440Y365550D01*
X975527Y365701D01*
G37*
G36*
G01X977427Y363910D02*
X978097Y363560D01*
Y362691D01*
X977427Y362341D01*
X977252Y362340D01*
X977253Y363910D01*
X977427D01*
G37*
G36*
G01X974048Y381519D02*
X974718Y381169D01*
Y380299D01*
X974048Y379949D01*
X973873D01*
Y381519D01*
X974048D01*
G37*
G36*
G01X973129Y385361D02*
X973889Y385011D01*
Y384111D01*
X973129Y383761D01*
X972954D01*
Y385361D01*
X973129D01*
G37*
G36*
G01X974048Y377619D02*
X974718Y377269D01*
Y376399D01*
X974048Y376049D01*
X973873D01*
Y377619D01*
X974048D01*
G37*
G36*
G01X976375Y387555D02*
X975615Y387905D01*
Y388805D01*
X976375Y389155D01*
X976550D01*
Y387555D01*
X976375D01*
G37*
G36*
G01X975804Y372124D02*
X975134Y372474D01*
Y373344D01*
X975804Y373694D01*
X975979D01*
Y372124D01*
X975804D01*
G37*
G36*
G01Y368226D02*
X975134Y368576D01*
X975133Y369445D01*
X975803Y369796D01*
X975979D01*
Y368225D01*
X975804Y368226D01*
G37*
G36*
G01X977734Y366451D02*
X977096Y366046D01*
X976343Y366480D01*
X976374Y367235D01*
X976462Y367388D01*
X977822Y366602D01*
X977734Y366451D01*
G37*
G36*
G01X976375Y379755D02*
X975615Y380105D01*
Y381005D01*
X976375Y381355D01*
X976550D01*
Y379755D01*
X976375D01*
G37*
G36*
G01Y383655D02*
X975615Y384005D01*
Y384905D01*
X976375Y385255D01*
X976550D01*
Y383655D01*
X976375D01*
G37*
G36*
G01X975804Y376048D02*
X975134Y376398D01*
Y377268D01*
X975804Y377618D01*
X975979D01*
Y376048D01*
X975804D01*
G37*
G36*
G01X975100Y394927D02*
X974315Y394637D01*
X973678Y395274D01*
X973968Y396059D01*
X974092Y396182D01*
X975224Y395051D01*
X975100Y394927D01*
G37*
G36*
G01X976375Y391455D02*
X975615Y391805D01*
Y392705D01*
X976375Y393055D01*
X976550D01*
Y391455D01*
X976375D01*
G37*
G36*
G01X975804Y356549D02*
X975134Y356899D01*
Y357769D01*
X975804Y358119D01*
X975979D01*
Y356549D01*
X975804D01*
G37*
G36*
G01Y352649D02*
X975134Y352999D01*
Y353869D01*
X975804Y354219D01*
X975979D01*
Y352649D01*
X975804D01*
G37*
G36*
G01X972425Y366318D02*
X971755Y366668D01*
Y367538D01*
X972425Y367887D01*
X972600Y367888D01*
Y366317D01*
X972425Y366318D01*
G37*
G36*
G01X972424Y370199D02*
X971754Y370549D01*
Y371419D01*
X972424Y371769D01*
X972599D01*
Y370199D01*
X972424D01*
G37*
G36*
G01X974318Y364523D02*
X973680Y364118D01*
X972927Y364553D01*
X972959Y365308D01*
X973046Y365460D01*
X974406Y364674D01*
X974318Y364523D01*
G37*
G36*
G01X975804Y360449D02*
X975134Y360799D01*
Y361669D01*
X975804Y362019D01*
X975979D01*
Y360449D01*
X975804D01*
G37*
G36*
G01X972424Y377950D02*
X971754Y378300D01*
Y379170D01*
X972424Y379520D01*
X972599D01*
Y377950D01*
X972424D01*
G37*
G36*
G01Y374050D02*
X971754Y374400D01*
Y375270D01*
X972424Y375620D01*
X972599D01*
Y374050D01*
X972424D01*
G37*
G36*
G01X977475Y389155D02*
X978235Y388805D01*
Y387905D01*
X977475Y387555D01*
X977300D01*
Y389155D01*
X977475D01*
G37*
G36*
G01X978878Y367668D02*
X979516Y368073D01*
X980269Y367639D01*
X980237Y366884D01*
X980150Y366731D01*
X978790Y367517D01*
X978878Y367668D01*
G37*
G36*
G01X980808Y365893D02*
X981478Y365543D01*
Y364674D01*
X980809Y364324D01*
X980633Y364323D01*
Y365894D01*
X980808Y365893D01*
G37*
G36*
G01X977428Y371769D02*
X978098Y371419D01*
Y370549D01*
X977428Y370199D01*
X977253D01*
Y371769D01*
X977428D01*
G37*
G36*
G01X977475Y381355D02*
X978235Y381005D01*
Y380105D01*
X977475Y379755D01*
X977300D01*
Y381355D01*
X977475D01*
G37*
G36*
G01Y385255D02*
X978235Y384905D01*
Y384005D01*
X977475Y383655D01*
X977300D01*
Y385255D01*
X977475D01*
G37*
G36*
G01X977428Y375620D02*
X978098Y375270D01*
Y374400D01*
X977428Y374050D01*
X977253D01*
Y375620D01*
X977428D01*
G37*
G36*
G01X977475Y393055D02*
X978235Y392705D01*
Y391805D01*
X977475Y391455D01*
X977300D01*
Y393055D01*
X977475D01*
G37*
G36*
G01X974746Y396837D02*
X975531Y397127D01*
X976168Y396491D01*
X975878Y395706D01*
X975754Y395582D01*
X974623Y396713D01*
X974746Y396837D01*
G37*
G36*
G01X972424Y358450D02*
X971754Y358800D01*
Y359670D01*
X972424Y360020D01*
X972599D01*
Y358450D01*
X972424D01*
G37*
G36*
G01X973297Y358114D02*
X973967Y357764D01*
Y356894D01*
X973297Y356544D01*
X973122D01*
Y358114D01*
X973297D01*
G37*
G36*
G01X972154Y363746D02*
X972792Y364151D01*
X973545Y363716D01*
X973513Y362961D01*
X973426Y362809D01*
X972066Y363595D01*
X972154Y363746D01*
G37*
G36*
G01X982513Y393494D02*
X981753Y393844D01*
Y394744D01*
X982513Y395094D01*
X982688D01*
Y393494D01*
X982513D01*
G37*
G36*
G01Y397394D02*
X981753Y397744D01*
Y398644D01*
X982513Y398994D01*
X982688D01*
Y397394D01*
X982513D01*
G37*
G36*
G01X982564Y376049D02*
X981894Y376399D01*
Y377269D01*
X982564Y377619D01*
X982739D01*
Y376049D01*
X982564D01*
G37*
G36*
G01X982513Y385694D02*
X981753Y386044D01*
Y386944D01*
X982513Y387294D01*
X982688D01*
Y385694D01*
X982513D01*
G37*
G36*
G01Y381794D02*
X981753Y382144D01*
Y383044D01*
X982513Y383394D01*
X982688D01*
Y381794D01*
X982513D01*
G37*
G36*
G01X985944Y362350D02*
X985274Y362700D01*
Y363570D01*
X985944Y363920D01*
X986119D01*
Y362350D01*
X985944D01*
G37*
G36*
G01Y366275D02*
X985274Y366625D01*
Y367495D01*
X985944Y367845D01*
X986119D01*
Y366275D01*
X985944D01*
G37*
G36*
G01X984458Y370372D02*
X983820Y369967D01*
X983067Y370402D01*
X983099Y371157D01*
X983185Y371308D01*
X984545Y370523D01*
X984458Y370372D01*
G37*
G36*
G01X982565Y372167D02*
X981895Y372517D01*
Y373387D01*
X982565Y373736D01*
X982739Y373737D01*
Y372167D01*
X982565D01*
G37*
G36*
G01X982513Y389594D02*
X981753Y389944D01*
Y390844D01*
X982513Y391194D01*
X982688D01*
Y389594D01*
X982513D01*
G37*
G36*
G01X983485Y358418D02*
X983453Y359173D01*
X984206Y359608D01*
X984844Y359203D01*
X984932Y359051D01*
X983572Y358266D01*
X983485Y358418D01*
G37*
G36*
G01X983611Y395094D02*
X984371Y394744D01*
Y393844D01*
X983611Y393494D01*
X983436D01*
Y395094D01*
X983611D01*
G37*
G36*
G01Y398994D02*
X984371Y398644D01*
Y397744D01*
X983611Y397394D01*
X983436D01*
Y398994D01*
X983611D01*
G37*
G36*
G01X984188Y375620D02*
X984858Y375270D01*
Y374400D01*
X984188Y374050D01*
X984013D01*
Y375620D01*
X984188D01*
G37*
G36*
G01Y379520D02*
X984858Y379170D01*
Y378300D01*
X984188Y377950D01*
X984013D01*
Y379520D01*
X984188D01*
G37*
G36*
G01X983611Y387294D02*
X984371Y386944D01*
Y386044D01*
X983611Y385694D01*
X983436D01*
Y387294D01*
X983611D01*
G37*
G36*
G01Y383394D02*
X984371Y383044D01*
Y382144D01*
X983611Y381794D01*
X983436D01*
Y383394D01*
X983611D01*
G37*
G36*
G01X985667Y371551D02*
X986305Y371956D01*
X987058Y371522D01*
X987026Y370766D01*
X986939Y370614D01*
X985580Y371400D01*
X985667Y371551D01*
G37*
G36*
G01X987568Y362019D02*
X988238Y361669D01*
Y360799D01*
X987568Y360449D01*
X987393D01*
Y362019D01*
X987568D01*
G37*
G36*
G01Y365919D02*
X988238Y365569D01*
Y364699D01*
X987568Y364349D01*
X987393D01*
Y365919D01*
X987568D01*
G37*
G36*
G01X987567Y369760D02*
X988237Y369410D01*
Y368541D01*
X987567Y368191D01*
X987392Y368190D01*
X987393Y369760D01*
X987567D01*
G37*
G36*
G01X983611Y391194D02*
X984371Y390844D01*
Y389944D01*
X983611Y389594D01*
X983436D01*
Y391194D01*
X983611D01*
G37*
G36*
G01X979413Y389304D02*
X978653Y389654D01*
Y390554D01*
X979413Y390904D01*
X979588D01*
Y389304D01*
X979413D01*
G37*
G36*
G01X979185Y370209D02*
X978515Y370559D01*
Y371428D01*
X979184Y371778D01*
X979360Y371779D01*
X979359Y370209D01*
X979185D01*
G37*
G36*
G01X981085Y368418D02*
X980447Y368013D01*
X979694Y368447D01*
X979726Y369202D01*
X979813Y369355D01*
X981172Y368569D01*
X981085Y368418D01*
G37*
G36*
G01X982564Y364349D02*
X981894Y364699D01*
Y365569D01*
X982564Y365919D01*
X982739D01*
Y364349D01*
X982564D01*
G37*
G36*
G01X979413Y381504D02*
X978653Y381854D01*
Y382754D01*
X979413Y383104D01*
X979588D01*
Y381504D01*
X979413D01*
G37*
G36*
G01Y385404D02*
X978653Y385754D01*
Y386654D01*
X979413Y387004D01*
X979588D01*
Y385404D01*
X979413D01*
G37*
G36*
G01X979184Y374050D02*
X978514Y374400D01*
Y375270D01*
X979184Y375620D01*
X979359D01*
Y374050D01*
X979184D01*
G37*
G36*
G01X978639Y396919D02*
X977855Y396629D01*
X977218Y397265D01*
X977508Y398050D01*
X977632Y398174D01*
X978763Y397043D01*
X978639Y396919D01*
G37*
G36*
G01X976463Y401630D02*
X975703Y401980D01*
Y402880D01*
X976463Y403230D01*
X976638D01*
Y401630D01*
X976463D01*
G37*
G36*
G01X979413Y393204D02*
X978653Y393554D01*
Y394454D01*
X979413Y394804D01*
X979588D01*
Y393204D01*
X979413D01*
G37*
G36*
G01X979953Y354630D02*
X979282Y354978D01*
X979280Y355848D01*
X979949Y356200D01*
X980125Y356199D01*
X980128Y354630D01*
X979953D01*
G37*
G36*
G01X980808Y373694D02*
X981478Y373344D01*
Y372474D01*
X980808Y372124D01*
X980633D01*
Y373694D01*
X980808D01*
G37*
G36*
G01X982294Y369597D02*
X982932Y370002D01*
X983685Y369567D01*
X983654Y368812D01*
X983566Y368660D01*
X982206Y369446D01*
X982294Y369597D01*
G37*
G36*
G01X984187Y367802D02*
X984857Y367452D01*
Y366582D01*
X984187Y366232D01*
X984012D01*
Y367803D01*
X984187Y367802D01*
G37*
G36*
G01X984188Y363920D02*
X984858Y363570D01*
Y362700D01*
X984188Y362350D01*
X984013D01*
Y363920D01*
X984188D01*
G37*
G36*
G01X980808Y377619D02*
X981478Y377269D01*
Y376399D01*
X980808Y376049D01*
X980633D01*
Y377619D01*
X980808D01*
G37*
G36*
G01X978284Y398827D02*
X979069Y399117D01*
X979706Y398480D01*
X979416Y397695D01*
X979292Y397572D01*
X978161Y398703D01*
X978284Y398827D01*
G37*
G36*
G01X977561Y403230D02*
X978321Y402880D01*
Y401980D01*
X977561Y401630D01*
X977386D01*
Y403230D01*
X977561D01*
G37*
G36*
G01X980511Y394804D02*
X981271Y394454D01*
Y393554D01*
X980511Y393204D01*
X980336D01*
Y394804D01*
X980511D01*
G37*
G36*
G01Y383104D02*
X981271Y382754D01*
Y381854D01*
X980511Y381504D01*
X980336D01*
Y383104D01*
X980511D01*
G37*
G36*
G01Y387004D02*
X981271Y386654D01*
Y385754D01*
X980511Y385404D01*
X980336D01*
Y387004D01*
X980511D01*
G37*
G36*
G01Y390904D02*
X981271Y390554D01*
Y389654D01*
X980511Y389304D01*
X980336D01*
Y390904D01*
X980511D01*
G37*
G36*
G01X972914Y404828D02*
X973674Y404478D01*
Y403578D01*
X972914Y403228D01*
X972739D01*
Y404828D01*
X972914D01*
G37*
G36*
G01X981481Y402819D02*
X980721Y403169D01*
Y404069D01*
X981481Y404419D01*
X981656D01*
Y402819D01*
X981481D01*
G37*
G36*
G01X982579Y404419D02*
X983339Y404069D01*
Y403169D01*
X982579Y402819D01*
X982404D01*
Y404419D01*
X982579D01*
G37*
G36*
G01X1075909Y191060D02*
X1075149Y191410D01*
Y192310D01*
X1075909Y192660D01*
X1076084D01*
Y191060D01*
X1075909D01*
G37*
G36*
G01X1080302Y203877D02*
X1079542Y204227D01*
Y205127D01*
X1080302Y205477D01*
X1080477D01*
Y203877D01*
X1080302D01*
G37*
G36*
G01X1075909Y194960D02*
X1075149Y195310D01*
Y196210D01*
X1075909Y196560D01*
X1076084D01*
Y194960D01*
X1075909D01*
G37*
G36*
G01X1077810Y200391D02*
X1077520Y201176D01*
X1078156Y201812D01*
X1078941Y201522D01*
X1079065Y201399D01*
X1077933Y200267D01*
X1077810Y200391D01*
G37*
G36*
G01X1083079Y210263D02*
X1082319Y210613D01*
Y211513D01*
X1083079Y211863D01*
X1083254D01*
Y210263D01*
X1083079D01*
G37*
G36*
G01X1083219Y215412D02*
X1082549Y215762D01*
Y216632D01*
X1083219Y216982D01*
X1083394D01*
Y215412D01*
X1083219D01*
G37*
G36*
G01X1081188Y208141D02*
X1080899Y208926D01*
X1081535Y209562D01*
X1082320Y209272D01*
X1082444Y209149D01*
X1081312Y208017D01*
X1081188Y208141D01*
G37*
G36*
G01X1077009Y192660D02*
X1077769Y192310D01*
Y191410D01*
X1077009Y191060D01*
X1076834D01*
Y192660D01*
X1077009D01*
G37*
G36*
G01Y196560D02*
X1077769Y196210D01*
Y195310D01*
X1077009Y194960D01*
X1076834D01*
Y196560D01*
X1077009D01*
G37*
G36*
G01X1081402Y205477D02*
X1082162Y205127D01*
Y204227D01*
X1081402Y203877D01*
X1081227D01*
Y205477D01*
X1081402D01*
G37*
G36*
G01X1079419Y200444D02*
X1079709Y199660D01*
X1079072Y199023D01*
X1078288Y199313D01*
X1078164Y199437D01*
X1079295Y200568D01*
X1079419Y200444D01*
G37*
G36*
G01X1084842Y215032D02*
X1085512Y214682D01*
Y213812D01*
X1084842Y213462D01*
X1084667D01*
Y215032D01*
X1084842D01*
G37*
G36*
G01X1083098Y208494D02*
X1083388Y207709D01*
X1082751Y207073D01*
X1081966Y207363D01*
X1081843Y207487D01*
X1082974Y208618D01*
X1083098Y208494D01*
G37*
G36*
G01X1084179Y211463D02*
X1084939Y211113D01*
Y210213D01*
X1084179Y209863D01*
X1084004D01*
Y211463D01*
X1084179D01*
G37*
G36*
G01X1088451Y189914D02*
X1087691Y190264D01*
Y191164D01*
X1088451Y191514D01*
X1088626D01*
Y189914D01*
X1088451D01*
G37*
G36*
G01X1093390Y197582D02*
X1092630Y197932D01*
Y198832D01*
X1093390Y199182D01*
X1093565D01*
Y197582D01*
X1093390D01*
G37*
G36*
G01X1090500Y194538D02*
X1090210Y195323D01*
X1090846Y195959D01*
X1091631Y195669D01*
X1091755Y195546D01*
X1090623Y194414D01*
X1090500Y194538D01*
G37*
G36*
G01X1094895Y203458D02*
X1094605Y204242D01*
X1095242Y204879D01*
X1096026Y204589D01*
X1096150Y204465D01*
X1095019Y203334D01*
X1094895Y203458D01*
G37*
G36*
G01X1089551Y191514D02*
X1090311Y191164D01*
Y190264D01*
X1089551Y189914D01*
X1089376D01*
Y191514D01*
X1089551D01*
G37*
G36*
G01X1094490Y199682D02*
X1095250Y199332D01*
Y198432D01*
X1094490Y198082D01*
X1094315D01*
Y199682D01*
X1094490D01*
G37*
G36*
G01X1092409Y194891D02*
X1092699Y194107D01*
X1092062Y193470D01*
X1091278Y193760D01*
X1091154Y193884D01*
X1092285Y195015D01*
X1092409Y194891D01*
G37*
G36*
G01X1072959Y189525D02*
X1072199Y189875D01*
Y190775D01*
X1072959Y191125D01*
X1073134D01*
Y189525D01*
X1072959D01*
G37*
G36*
G01Y197325D02*
X1072199Y197675D01*
Y198575D01*
X1072959Y198925D01*
X1073134D01*
Y197325D01*
X1072959D01*
G37*
G36*
G01Y193425D02*
X1072199Y193775D01*
Y194675D01*
X1072959Y195025D01*
X1073134D01*
Y193425D01*
X1072959D01*
G37*
G36*
G01X1074911Y201523D02*
X1074621Y202308D01*
X1075257Y202944D01*
X1076042Y202654D01*
X1076166Y202531D01*
X1075034Y201399D01*
X1074911Y201523D01*
G37*
G36*
G01X1079839Y213419D02*
X1079169Y213769D01*
Y214639D01*
X1079839Y214989D01*
X1080014D01*
Y213419D01*
X1079839D01*
G37*
G36*
G01X1077924Y208907D02*
X1077635Y209692D01*
X1078271Y210328D01*
X1079056Y210038D01*
X1079180Y209915D01*
X1078048Y208783D01*
X1077924Y208907D01*
G37*
G36*
G01X1079839Y217319D02*
X1079169Y217669D01*
Y218539D01*
X1079839Y218889D01*
X1080014D01*
Y217319D01*
X1079839D01*
G37*
G36*
G01X1074059Y191125D02*
X1074819Y190775D01*
Y189875D01*
X1074059Y189525D01*
X1073884D01*
Y191125D01*
X1074059D01*
G37*
G36*
G01X1076520Y201576D02*
X1076810Y200792D01*
X1076173Y200155D01*
X1075389Y200445D01*
X1075265Y200569D01*
X1076396Y201700D01*
X1076520Y201576D01*
G37*
G36*
G01X1074059Y195025D02*
X1074819Y194675D01*
Y193775D01*
X1074059Y193425D01*
X1073884D01*
Y195025D01*
X1074059D01*
G37*
G36*
G01Y198925D02*
X1074819Y198575D01*
Y197675D01*
X1074059Y197325D01*
X1073884D01*
Y198925D01*
X1074059D01*
G37*
G36*
G01X1078552Y206977D02*
X1079312Y206627D01*
Y205727D01*
X1078552Y205377D01*
X1078377D01*
Y206977D01*
X1078552D01*
G37*
G36*
G01X1081464Y217017D02*
X1082134Y216667D01*
Y215797D01*
X1081464Y215447D01*
X1081289D01*
Y217017D01*
X1081464D01*
G37*
G36*
G01X1079834Y209260D02*
X1080124Y208475D01*
X1079487Y207839D01*
X1078702Y208129D01*
X1078579Y208253D01*
X1079710Y209384D01*
X1079834Y209260D01*
G37*
G36*
G01X1085193Y190354D02*
X1084433Y190704D01*
Y191604D01*
X1085193Y191954D01*
X1085368D01*
Y190354D01*
X1085193D01*
G37*
G36*
G01X1088851Y199106D02*
X1088091Y199456D01*
Y200356D01*
X1088851Y200706D01*
X1089026D01*
Y199106D01*
X1088851D01*
G37*
G36*
G01X1086726Y194796D02*
X1086436Y195580D01*
X1087073Y196217D01*
X1087857Y195927D01*
X1087981Y195803D01*
X1086850Y194672D01*
X1086726Y194796D01*
G37*
G36*
G01X1089315Y204120D02*
X1089025Y204904D01*
X1089662Y205541D01*
X1090446Y205251D01*
X1090570Y205127D01*
X1089439Y203996D01*
X1089315Y204120D01*
G37*
G36*
G01X1092073Y206878D02*
X1091783Y207662D01*
X1092420Y208299D01*
X1093204Y208009D01*
X1093328Y207885D01*
X1092197Y206754D01*
X1092073Y206878D01*
G37*
G36*
G01X1093882Y209573D02*
X1093122Y209923D01*
Y210823D01*
X1093882Y211173D01*
X1094057D01*
Y209573D01*
X1093882D01*
G37*
G36*
G01Y213473D02*
X1093122Y213823D01*
Y214723D01*
X1093882Y215073D01*
X1094057D01*
Y213473D01*
X1093882D01*
G37*
G36*
G01X1086293Y191954D02*
X1087053Y191604D01*
Y190704D01*
X1086293Y190354D01*
X1086118D01*
Y191954D01*
X1086293D01*
G37*
G36*
G01X1089951Y202606D02*
X1090711Y202256D01*
Y201356D01*
X1089951Y201006D01*
X1089776D01*
Y202606D01*
X1089951D01*
G37*
G36*
G01X1088635Y195149D02*
X1088925Y194364D01*
X1088289Y193728D01*
X1087504Y194018D01*
X1087380Y194141D01*
X1088512Y195273D01*
X1088635Y195149D01*
G37*
G36*
G01X1094982Y212573D02*
X1095742Y212223D01*
Y211323D01*
X1094982Y210973D01*
X1094807D01*
Y212573D01*
X1094982D01*
G37*
G36*
G01X1092980Y206223D02*
X1093270Y205438D01*
X1092634Y204802D01*
X1091849Y205092D01*
X1091725Y205215D01*
X1092857Y206347D01*
X1092980Y206223D01*
G37*
G36*
G01X1094982Y216473D02*
X1095742Y216123D01*
Y215223D01*
X1094982Y214873D01*
X1094807D01*
Y216473D01*
X1094982D01*
G37*
G36*
G01X1080085Y192256D02*
X1080845Y191906D01*
Y191006D01*
X1080085Y190656D01*
X1079910D01*
Y192256D01*
X1080085D01*
G37*
G36*
G01X1084252Y203977D02*
X1085012Y203627D01*
Y202727D01*
X1084252Y202377D01*
X1084077D01*
Y203977D01*
X1084252D01*
G37*
G36*
G01X1080085Y196156D02*
X1080845Y195806D01*
Y194906D01*
X1080085Y194556D01*
X1079910D01*
Y196156D01*
X1080085D01*
G37*
G36*
G01X1082464Y199459D02*
X1082754Y198674D01*
X1082118Y198038D01*
X1081333Y198328D01*
X1081209Y198451D01*
X1082341Y199583D01*
X1082464Y199459D01*
G37*
G36*
G01X1086222Y207559D02*
X1086512Y206774D01*
X1085876Y206138D01*
X1085091Y206428D01*
X1084967Y206551D01*
X1086099Y207683D01*
X1086222Y207559D01*
G37*
G36*
G01X1088222Y213082D02*
X1088892Y212732D01*
Y211862D01*
X1088222Y211512D01*
X1088047D01*
Y213082D01*
X1088222D01*
G37*
G36*
G01X1086002Y200595D02*
X1085242Y200945D01*
Y201845D01*
X1086002Y202195D01*
X1086177D01*
Y200595D01*
X1086002D01*
G37*
G36*
G01X1082145Y190939D02*
X1081385Y191289D01*
Y192189D01*
X1082145Y192539D01*
X1082320D01*
Y190939D01*
X1082145D01*
G37*
G36*
G01X1083778Y195877D02*
X1083488Y196662D01*
X1084124Y197298D01*
X1084909Y197008D01*
X1085033Y196885D01*
X1083901Y195753D01*
X1083778Y195877D01*
G37*
G36*
G01X1088452Y207285D02*
X1088162Y208069D01*
X1088799Y208706D01*
X1089583Y208416D01*
X1089707Y208292D01*
X1088576Y207161D01*
X1088452Y207285D01*
G37*
G36*
G01X1090531Y211456D02*
X1089771Y211806D01*
Y212706D01*
X1090531Y213056D01*
X1090706D01*
Y211456D01*
X1090531D01*
G37*
G36*
G01X1078987Y190656D02*
X1078227Y191006D01*
Y191906D01*
X1078987Y192256D01*
X1079162D01*
Y190656D01*
X1078987D01*
G37*
G36*
G01X1083152Y202377D02*
X1082392Y202727D01*
Y203627D01*
X1083152Y203977D01*
X1083327D01*
Y202377D01*
X1083152D01*
G37*
G36*
G01X1078987Y194556D02*
X1078227Y194906D01*
Y195806D01*
X1078987Y196156D01*
X1079162D01*
Y194556D01*
X1078987D01*
G37*
G36*
G01X1080555Y199106D02*
X1080265Y199890D01*
X1080902Y200527D01*
X1081686Y200237D01*
X1081810Y200113D01*
X1080679Y198982D01*
X1080555Y199106D01*
G37*
G36*
G01X1086599Y213437D02*
X1085929Y213787D01*
Y214657D01*
X1086599Y215007D01*
X1086774D01*
Y213437D01*
X1086599D01*
G37*
G36*
G01X1084313Y207206D02*
X1084023Y207990D01*
X1084660Y208627D01*
X1085444Y208337D01*
X1085568Y208213D01*
X1084437Y207082D01*
X1084313Y207206D01*
G37*
G36*
G01X1085687Y196230D02*
X1085977Y195446D01*
X1085340Y194809D01*
X1084556Y195099D01*
X1084432Y195223D01*
X1085563Y196354D01*
X1085687Y196230D01*
G37*
G36*
G01X1087102Y202195D02*
X1087862Y201845D01*
Y200945D01*
X1087102Y200595D01*
X1086927D01*
Y202195D01*
X1087102D01*
G37*
G36*
G01X1083243Y192539D02*
X1084003Y192189D01*
Y191289D01*
X1083243Y190939D01*
X1083068D01*
Y192539D01*
X1083243D01*
G37*
G36*
G01X1090361Y207638D02*
X1090651Y206853D01*
X1090015Y206217D01*
X1089230Y206507D01*
X1089106Y206630D01*
X1090238Y207762D01*
X1090361Y207638D01*
G37*
G36*
G01X1091631Y213056D02*
X1092391Y212706D01*
Y211806D01*
X1091631Y211456D01*
X1091456D01*
Y213056D01*
X1091631D01*
G37*
G36*
G01X1091603Y218932D02*
X1092273Y218582D01*
Y217712D01*
X1091603Y217362D01*
X1091428D01*
Y218932D01*
X1091603D01*
G37*
G36*
G01X1085708Y222471D02*
X1086407Y222759D01*
X1087073Y222200D01*
X1086911Y221461D01*
X1086798Y221327D01*
X1085596Y222337D01*
X1085708Y222471D01*
G37*
G36*
G01X1094983Y220882D02*
X1095653Y220532D01*
Y219662D01*
X1094983Y219312D01*
X1094808D01*
Y220882D01*
X1094983D01*
G37*
G36*
G01X1094068Y225075D02*
X1094789Y224847D01*
X1094940Y223990D01*
X1094341Y223529D01*
X1094168Y223499D01*
X1093896Y225045D01*
X1094068Y225075D01*
G37*
G36*
G01X1088532Y223415D02*
X1087894Y223009D01*
X1087141Y223444D01*
X1087172Y224200D01*
X1087260Y224351D01*
X1088620Y223566D01*
X1088532Y223415D01*
G37*
G36*
G01X1089979Y219312D02*
X1089309Y219662D01*
Y220532D01*
X1089979Y220882D01*
X1090154D01*
Y219312D01*
X1089979D01*
G37*
G36*
G01X1089709Y224584D02*
X1090347Y224989D01*
X1091100Y224554D01*
X1091068Y223799D01*
X1090982Y223648D01*
X1089621Y224433D01*
X1089709Y224584D01*
G37*
G36*
G01X1091602Y222789D02*
X1092272Y222439D01*
Y221569D01*
X1091602Y221219D01*
X1091428D01*
X1091427Y222790D01*
X1091602Y222789D01*
G37*
G36*
G01X1191600Y206000D02*
X1189003Y208597D01*
G02X1189054Y209205I283J282D01*
G03X1187098Y211161I-815J1141D01*
G02X1186490Y211110I-326J232D01*
G01X1186053Y211547D01*
X1186116Y211676D01*
G03X1183459Y212221I-1257J620D01*
G02X1183060Y211800I-399J-21D01*
G01X1179898D01*
G02X1179499Y212221I0J400D01*
G03X1176699I-1400J75D01*
G02X1176300Y211800I-399J-21D01*
G01X1173138D01*
G02X1172739Y212221I0J400D01*
G03X1169939I-1400J75D01*
G02X1169540Y211800I-399J-21D01*
G01X1166379D01*
G02X1165980Y212221I0J400D01*
G03X1163180I-1400J75D01*
G02X1162781Y211800I-399J-21D01*
G01X1159619D01*
G02X1159220Y212221I0J400D01*
G03X1156420I-1400J75D01*
G02X1156021Y211800I-399J-21D01*
G01X1153700D01*
X1151309Y214191D01*
G02X1151473Y214856I282J283D01*
G03X1149720Y216609I-413J1340D01*
G02X1149055Y216445I-382J118D01*
G01X1148785Y216715D01*
G02X1148760Y217253I283J283D01*
G03X1146786Y219227I-1080J894D01*
G02X1146248Y219252I-255J308D01*
G01X1145678Y219822D01*
X1145691Y219919D01*
G03X1144123Y221487I-1391J177D01*
G01X1144026Y221474D01*
X1141700Y223800D01*
Y226100D01*
X1137817Y229983D01*
X1137807Y230049D01*
G03X1135494Y230900I-1387J-202D01*
G01X1134844D01*
X1134797Y230927D01*
G03X1134473Y231093I-1757J-3030D01*
G02X1134366Y231341I82J182D01*
G03X1131692Y231410I-1326J456D01*
G02X1131308Y230900I-384J-110D01*
G01X1130586D01*
G03X1128734I-926J-1053D01*
G01X1128012D01*
G02X1127628Y231410I0J400D01*
G03X1124932I-1348J387D01*
G02X1124548Y230900I-384J-110D01*
G01X1123826D01*
G03X1121974I-926J-1053D01*
G01X1121253D01*
G02X1120869Y231410I0J400D01*
G03X1118173I-1348J387D01*
G02X1117789Y230900I-384J-110D01*
G01X1117067D01*
G03X1115215I-926J-1053D01*
G01X1114493D01*
G02X1114109Y231410I0J400D01*
G03X1111413I-1348J387D01*
G02X1111029Y230900I-384J-110D01*
G01X1110307D01*
G03X1108455I-926J-1053D01*
G01X1107733D01*
G02X1107349Y231410I0J400D01*
G03X1104653I-1348J387D01*
G02X1104269Y230900I-384J-110D01*
G01X1103547D01*
G03X1101695I-926J-1053D01*
G01X1100973D01*
G02X1100589Y231410I0J400D01*
G03X1097893I-1348J387D01*
G02X1097509Y230900I-384J-110D01*
G01X1096787D01*
G03X1094935I-926J-1053D01*
G01X1094213D01*
G02X1093829Y231410I0J400D01*
G03X1091133I-1348J387D01*
G02X1090749Y230900I-384J-110D01*
G01X1090027D01*
G03X1088175I-926J-1053D01*
G01X1087453D01*
G02X1087069Y231410I0J400D01*
G03X1084599Y232637I-1348J387D01*
G02X1083996Y232594I-320J240D01*
G01X1083556Y233034D01*
X1083615Y233160D01*
G03X1081755Y235020I-1274J586D01*
G01X1081629Y234961D01*
X1081255Y235335D01*
Y235981D01*
G02X1081807Y236351I400J0D01*
G03Y238943I534J1296D01*
G02X1081255Y239313I-152J370D01*
G01Y239881D01*
G02X1081807Y240251I400J0D01*
G03X1081687Y242787I534J1296D01*
G02X1081100Y243141I-187J354D01*
G01Y243853D01*
G02X1081687Y244207I400J0D01*
G03Y246687I654J1240D01*
G02X1081100Y247041I-187J354D01*
G01Y247753D01*
G02X1081687Y248107I400J0D01*
G03Y250587I654J1240D01*
G02X1081100Y250941I-187J354D01*
G01Y251500D01*
X1083880Y254280D01*
X1084007Y254222D01*
G03X1085866Y256081I584J1275D01*
G01X1085808Y256208D01*
X1086411Y256811D01*
G02X1086978I283J-282D01*
G03X1088828Y258909I993J989D01*
G01X1088818Y258917D01*
X1088668Y259068D01*
X1089000Y259400D01*
X1089955D01*
X1089993Y259250D01*
G03X1092709I1358J350D01*
G01X1092747Y259400D01*
X1095900D01*
X1098577Y262077D01*
X1098616Y262092D01*
G03X1099419Y262895I-505J1308D01*
G01X1099434Y262934D01*
X1100720Y264220D01*
X1100850Y264153D01*
G03X1102738Y266041I641J1247D01*
G01X1102671Y266171D01*
X1103087Y266587D01*
G02X1103703Y266525I283J-283D01*
G03X1106266Y267436I1168J775D01*
G02X1106863Y267822I398J39D01*
G03X1108962Y269090I698J1216D01*
G01X1108959Y269177D01*
X1109162Y269380D01*
X1109519Y269022D01*
X1114481D01*
X1115281Y269822D01*
X1116819D01*
X1118119Y268522D01*
X1118201D01*
G02X1118494Y267850I0J-400D01*
G03X1120159Y268144I1027J-954D01*
G01X1120050Y268200D01*
Y268522D01*
X1120581D01*
X1120848Y268790D01*
G02X1121523Y268582I282J-283D01*
G03X1124229Y269295I1377J265D01*
G02X1124608Y269822I379J127D01*
G01X1125219D01*
X1126117Y268925D01*
G02X1125933Y268254I-283J-283D01*
G03X1127638Y266549I347J-1358D01*
G02X1128309Y266733I388J-99D01*
G01X1128319Y266722D01*
X1128496D01*
G02X1128754Y266017I0J-400D01*
G03X1130566I906J-1070D01*
G02X1130824Y266722I258J305D01*
G01X1131119D01*
X1132830Y265012D01*
G02X1132656Y264345I-283J-282D01*
G03X1134440Y263073I384J-1349D01*
G02X1135122Y263378I399J22D01*
G01X1135684Y262816D01*
G02X1135627Y262203I-283J-283D01*
G03X1137576Y260254I793J-1156D01*
G02X1138189Y260311I330J-226D01*
G01X1141322Y257178D01*
Y254960D01*
X1143371Y252912D01*
G02X1143357Y252333I-283J-283D01*
G03X1145457Y250505I942J-1038D01*
G01X1145517Y250592D01*
X1145822D01*
Y250246D01*
X1146330Y249739D01*
X1146308Y249633D01*
G03X1147600Y250747I1373J-286D01*
G02X1147178Y251146I-22J399D01*
G01Y251448D01*
G02X1147600Y251847I400J0D01*
G03X1146290Y253429I80J1400D01*
G02X1145611Y253199I-396J53D01*
G01X1145132Y253678D01*
X1145010D01*
Y253982D01*
X1145096Y254042D01*
G03X1145299Y256179I-796J1154D01*
G02X1145584Y256860I285J281D01*
G01X1146300D01*
X1146344Y256721D01*
G03X1147515Y255755I1336J426D01*
G01X1147583Y255747D01*
X1147700Y255630D01*
X1149258D01*
G02X1149658Y255222I0J-400D01*
G03X1152174Y254345I1402J-26D01*
G02X1152450Y254386I159J-121D01*
G03X1153043Y254044I1988J2762D01*
G02X1153145Y253785I-83J-182D01*
G03X1155305Y252144I1295J-538D01*
G01X1155445Y252253D01*
X1156416Y251282D01*
X1156421Y251207D01*
G03X1157731Y249897I1399J89D01*
G01X1157806Y249892D01*
X1158128Y249570D01*
X1159798D01*
Y249367D01*
G03X1162314Y248496I1402J-20D01*
G02X1162590Y248536I159J-122D01*
G03X1163183Y248193I1992J2759D01*
G02X1163285Y247934I-82J-182D01*
G03X1165875I1295J-538D01*
G02X1165977Y248193I184J77D01*
G03X1166570Y248536I-1399J3102D01*
G02X1166846Y248496I117J-162D01*
G03X1169362Y249367I1114J851D01*
G01Y249570D01*
X1171480D01*
X1171938Y250028D01*
X1171967Y250042D01*
G03X1172593Y250668I-628J1254D01*
G01X1172607Y250697D01*
X1173966Y252056D01*
X1174095Y251992D01*
G03X1175974Y253871I624J1255D01*
G01X1175910Y254000D01*
X1176346Y254436D01*
G02X1176955Y254385I283J-283D01*
G03X1178910Y256340I1144J811D01*
G02X1178859Y256949I232J326D01*
G01X1179170Y257260D01*
Y258191D01*
G03X1179456Y259449I-1071J905D01*
G02X1179843Y259950I387J101D01*
G01X1180606D01*
G03X1182352I873J1097D01*
G01X1183115D01*
G02X1183502Y259449I0J-400D01*
G03X1186216I1357J-353D01*
G02X1186603Y259950I387J101D01*
G01X1187366D01*
G03X1189112I873J1097D01*
G01X1189875D01*
G02X1190262Y259449I0J-400D01*
G03X1192976I1357J-353D01*
G02X1193363Y259950I387J101D01*
G01X1194126D01*
G03X1195872I873J1097D01*
G01X1196635D01*
G02X1197022Y259449I0J-400D01*
G03X1199736I1357J-353D01*
G02X1200123Y259950I387J101D01*
G01X1200886D01*
G03X1202632I873J1097D01*
G01X1203395D01*
G02X1203782Y259449I0J-400D01*
G03X1206496I1357J-353D01*
G02X1206883Y259950I387J101D01*
G01X1207750D01*
X1208682Y259018D01*
X1208935Y258721D01*
X1208720Y258537D01*
X1208637Y258544D01*
G03X1209884Y256825I-118J-1397D01*
G02X1210556Y257016I389J-92D01*
G01X1211700Y255871D01*
Y252612D01*
X1211587Y252558D01*
G03Y250034I612J-1262D01*
G01X1211700Y249980D01*
Y244812D01*
X1211587Y244758D01*
G03Y242234I612J-1262D01*
G01X1211700Y242180D01*
Y240912D01*
X1211587Y240858D01*
G03Y238334I612J-1262D01*
G01X1211700Y238280D01*
Y233113D01*
X1211587Y233059D01*
G03Y230535I612J-1262D01*
G01X1211700Y230481D01*
Y229212D01*
X1211587Y229158D01*
G03Y226634I612J-1262D01*
G01X1211700Y226580D01*
Y225312D01*
X1211587Y225258D01*
G03Y222734I612J-1262D01*
G01X1211700Y222680D01*
Y215000D01*
X1202700Y206000D01*
X1191600D01*
G37*
G36*
G01X1092810Y382742D02*
X1092063Y382622D01*
X1091543Y383320D01*
X1091871Y384001D01*
X1092011Y384105D01*
X1092950Y382847D01*
X1092810Y382742D01*
G37*
G36*
G01X1091099Y388937D02*
X1090429Y389287D01*
Y390157D01*
X1091099Y390507D01*
X1091274D01*
Y388937D01*
X1091099D01*
G37*
G36*
G01X1091972Y388601D02*
X1092642Y388251D01*
Y387381D01*
X1091972Y387031D01*
X1091797D01*
Y388601D01*
X1091972D01*
G37*
G36*
G01X1087025Y395718D02*
X1086192Y395640D01*
X1085742Y396420D01*
X1086225Y397103D01*
X1086376Y397191D01*
X1087177Y395805D01*
X1087025Y395718D01*
G37*
G36*
G01X1084600Y400752D02*
X1083840Y401102D01*
Y402002D01*
X1084600Y402352D01*
X1084775D01*
Y400752D01*
X1084600D01*
G37*
G36*
G01X1087179Y397655D02*
X1088012Y397732D01*
X1088463Y396953D01*
X1087980Y396270D01*
X1087828Y396182D01*
X1087028Y397567D01*
X1087179Y397655D01*
G37*
G36*
G01X1085698Y402352D02*
X1086458Y402002D01*
Y401102D01*
X1085698Y400752D01*
X1085523D01*
Y402352D01*
X1085698D01*
G37*
G36*
G01X1090823Y394236D02*
X1091461Y394641D01*
X1092214Y394206D01*
X1092182Y393451D01*
X1092095Y393299D01*
X1090735Y394085D01*
X1090823Y394236D01*
G37*
G36*
G01X1089693Y385214D02*
X1089023Y384866D01*
X1088310Y385365D01*
X1088408Y386114D01*
X1088508Y386257D01*
X1089794Y385358D01*
X1089693Y385214D01*
G37*
G36*
G01X1087748Y387007D02*
X1087079Y387356D01*
X1087078Y388226D01*
X1087748Y388575D01*
X1087923D01*
Y387006D01*
X1087748Y387007D01*
G37*
G36*
G01X1080035Y401402D02*
X1079250Y401112D01*
X1078614Y401749D01*
X1078904Y402534D01*
X1079028Y402657D01*
X1080159Y401526D01*
X1080035Y401402D01*
G37*
G36*
G01X1083395Y394608D02*
X1082561Y394531D01*
X1082111Y395310D01*
X1082594Y395993D01*
X1082745Y396081D01*
X1083546Y394696D01*
X1083395Y394608D01*
G37*
G36*
G01X1086258Y391133D02*
X1085620Y390728D01*
X1084867Y391163D01*
X1084899Y391918D01*
X1084986Y392069D01*
X1086346Y391284D01*
X1086258Y391133D01*
G37*
G36*
G01X1089342Y390497D02*
X1090012Y390147D01*
Y389278D01*
X1089342Y388928D01*
X1089168Y388927D01*
X1089167Y390498D01*
X1089342Y390497D01*
G37*
G36*
G01X1087442Y392288D02*
X1088080Y392693D01*
X1088833Y392259D01*
X1088801Y391503D01*
X1088715Y391352D01*
X1087354Y392137D01*
X1087442Y392288D01*
G37*
G36*
G01X1079680Y403310D02*
X1080465Y403600D01*
X1081102Y402964D01*
X1080812Y402179D01*
X1080688Y402055D01*
X1079557Y403186D01*
X1079680Y403310D01*
G37*
G36*
G01X1083549Y396545D02*
X1084382Y396623D01*
X1084832Y395843D01*
X1084349Y395160D01*
X1084198Y395072D01*
X1083397Y396458D01*
X1083549Y396545D01*
G37*
G36*
G01X1090142Y400736D02*
X1090975Y400813D01*
X1091425Y400033D01*
X1090942Y399350D01*
X1090790Y399263D01*
X1089991Y400648D01*
X1090142Y400736D01*
G37*
G36*
G01X1094479Y387036D02*
X1093809Y387386D01*
Y388256D01*
X1094479Y388606D01*
X1094654D01*
Y387036D01*
X1094479D01*
G37*
G36*
G01Y390936D02*
X1093809Y391286D01*
Y392156D01*
X1094479Y392506D01*
X1094654D01*
Y390936D01*
X1094479D01*
G37*
G36*
G01X1089989Y398800D02*
X1089156Y398723D01*
X1088706Y399503D01*
X1089189Y400186D01*
X1089341Y400273D01*
X1090140Y398888D01*
X1089989Y398800D01*
G37*
G36*
G01X1092992Y395008D02*
X1092354Y394603D01*
X1091601Y395038D01*
X1091633Y395793D01*
X1091720Y395945D01*
X1093080Y395159D01*
X1092992Y395008D01*
G37*
G36*
G01X1078785Y411224D02*
X1078001Y410934D01*
X1077364Y411571D01*
X1077654Y412355D01*
X1077778Y412479D01*
X1078909Y411348D01*
X1078785Y411224D01*
G37*
G36*
G01X1081543Y408466D02*
X1080759Y408176D01*
X1080122Y408813D01*
X1080412Y409597D01*
X1080536Y409721D01*
X1081667Y408590D01*
X1081543Y408466D01*
G37*
G36*
G01X1084301Y405708D02*
X1083517Y405418D01*
X1082880Y406055D01*
X1083170Y406839D01*
X1083294Y406963D01*
X1084425Y405832D01*
X1084301Y405708D01*
G37*
G36*
G01X1081189Y410374D02*
X1081973Y410664D01*
X1082610Y410027D01*
X1082320Y409243D01*
X1082196Y409119D01*
X1081065Y410250D01*
X1081189Y410374D01*
G37*
G36*
G01X1083947Y407616D02*
X1084731Y407906D01*
X1085368Y407269D01*
X1085078Y406485D01*
X1084954Y406361D01*
X1083823Y407492D01*
X1083947Y407616D01*
G37*
G36*
G01X1078431Y413132D02*
X1079215Y413422D01*
X1079852Y412785D01*
X1079562Y412001D01*
X1079438Y411877D01*
X1078307Y413008D01*
X1078431Y413132D01*
G37*
G36*
G01X1077277Y404160D02*
X1076493Y403870D01*
X1075856Y404507D01*
X1076146Y405291D01*
X1076270Y405415D01*
X1077401Y404284D01*
X1077277Y404160D01*
G37*
G36*
G01X1074520Y406918D02*
X1073735Y406628D01*
X1073098Y407264D01*
X1073388Y408049D01*
X1073512Y408173D01*
X1074643Y407042D01*
X1074520Y406918D01*
G37*
G36*
G01X1071701Y412089D02*
X1070941Y412439D01*
Y413339D01*
X1071701Y413689D01*
X1071876D01*
Y412089D01*
X1071701D01*
G37*
G36*
G01X1074165Y408826D02*
X1074950Y409116D01*
X1075586Y408479D01*
X1075296Y407694D01*
X1075172Y407571D01*
X1074041Y408702D01*
X1074165Y408826D01*
G37*
G36*
G01X1076923Y406068D02*
X1077707Y406358D01*
X1078344Y405721D01*
X1078054Y404937D01*
X1077930Y404813D01*
X1076799Y405944D01*
X1076923Y406068D01*
G37*
G36*
G01X1072799Y413689D02*
X1073559Y413339D01*
Y412439D01*
X1072799Y412089D01*
X1072624D01*
Y413689D01*
X1072799D01*
G37*
G36*
G01X1095977Y410529D02*
X1095192Y410239D01*
X1094556Y410875D01*
X1094846Y411660D01*
X1094969Y411784D01*
X1096101Y410652D01*
X1095977Y410529D01*
G37*
G36*
G01X1093129Y414539D02*
X1092369Y414889D01*
Y415788D01*
X1093129Y416138D01*
X1093304Y416139D01*
Y414538D01*
X1093129Y414539D01*
G37*
G36*
G01X1094226Y416138D02*
X1094986Y415788D01*
Y414889D01*
X1094226Y414539D01*
X1094052Y414538D01*
Y416139D01*
X1094226Y416138D01*
G37*
G36*
G01X1088815Y405970D02*
X1089575Y405620D01*
Y404720D01*
X1088815Y404370D01*
X1088641D01*
Y405971D01*
X1088815Y405970D01*
G37*
G36*
G01X1083281Y412823D02*
X1084066Y413113D01*
X1084702Y412477D01*
X1084412Y411692D01*
X1084289Y411568D01*
X1083157Y412700D01*
X1083281Y412823D01*
G37*
G36*
G01X1086039Y410065D02*
X1086824Y410355D01*
X1087460Y409719D01*
X1087170Y408934D01*
X1087047Y408810D01*
X1085915Y409942D01*
X1086039Y410065D01*
G37*
G36*
G01X1082313Y416129D02*
X1083073Y415779D01*
Y414879D01*
X1082313Y414529D01*
X1082138Y414528D01*
Y416129D01*
X1082313D01*
G37*
G36*
G01X1092348Y403055D02*
X1091563Y402765D01*
X1090927Y403401D01*
X1091217Y404186D01*
X1091340Y404310D01*
X1092472Y403179D01*
X1092348Y403055D01*
G37*
G36*
G01X1090493Y409720D02*
X1089708Y409430D01*
X1089072Y410067D01*
X1089362Y410852D01*
X1089485Y410975D01*
X1090617Y409844D01*
X1090493Y409720D01*
G37*
G36*
G01X1091018Y406585D02*
X1090258Y406935D01*
Y407835D01*
X1091018Y408185D01*
X1091193D01*
Y406585D01*
X1091018D01*
G37*
G36*
G01X1088431Y414581D02*
X1087671Y414931D01*
Y415831D01*
X1088431Y416181D01*
X1088606D01*
Y414581D01*
X1088431D01*
G37*
G36*
G01X1083634Y410914D02*
X1082850Y410624D01*
X1082213Y411261D01*
X1082503Y412045D01*
X1082627Y412169D01*
X1083758Y411038D01*
X1083634Y410914D01*
G37*
G36*
G01X1086392Y408156D02*
X1085608Y407866D01*
X1084971Y408503D01*
X1085261Y409287D01*
X1085385Y409411D01*
X1086516Y408280D01*
X1086392Y408156D01*
G37*
G36*
G01X1087715Y404370D02*
X1086956Y404720D01*
Y405621D01*
X1087715Y405970D01*
X1087890D01*
Y404370D01*
X1087715D01*
G37*
G36*
G01X1081213Y414529D02*
X1080453Y414878D01*
Y415779D01*
X1081213Y416129D01*
X1081388D01*
Y414529D01*
X1081213D01*
G37*
G36*
G01X1090139Y411629D02*
X1090924Y411919D01*
X1091561Y411283D01*
X1091271Y410498D01*
X1091147Y410374D01*
X1090016Y411506D01*
X1090139Y411629D01*
G37*
G36*
G01X1092118Y408185D02*
X1092878Y407835D01*
Y406935D01*
X1092118Y406585D01*
X1091943D01*
Y408185D01*
X1092118D01*
G37*
G36*
G01X1089531Y416181D02*
X1090291Y415831D01*
Y414931D01*
X1089531Y414581D01*
X1089356D01*
Y416181D01*
X1089531D01*
G37*
G36*
G01X1096741Y213439D02*
X1095981Y213789D01*
Y214689D01*
X1096741Y215039D01*
X1096916D01*
Y213439D01*
X1096741D01*
G37*
G36*
G01Y209539D02*
X1095981Y209889D01*
Y210789D01*
X1096741Y211139D01*
X1096916D01*
Y209539D01*
X1096741D01*
G37*
G36*
G01X1096813Y203817D02*
X1097103Y203033D01*
X1096466Y202396D01*
X1095682Y202686D01*
X1095558Y202810D01*
X1096689Y203941D01*
X1096813Y203817D01*
G37*
G36*
G01X1097841Y211139D02*
X1098601Y210789D01*
Y209889D01*
X1097841Y209539D01*
X1097666D01*
Y211139D01*
X1097841D01*
G37*
G36*
G01Y215039D02*
X1098601Y214689D01*
Y213789D01*
X1097841Y213439D01*
X1097666D01*
Y215039D01*
X1097841D01*
G37*
G36*
G01X1098363Y218907D02*
X1099033Y218557D01*
Y217687D01*
X1098363Y217337D01*
X1098188D01*
Y218907D01*
X1098363D01*
G37*
G36*
G01X1102827Y200688D02*
X1102067Y201038D01*
Y201938D01*
X1102827Y202288D01*
X1103002D01*
Y200688D01*
X1102827D01*
G37*
G36*
G01X1102531Y190409D02*
X1101771Y190759D01*
Y191659D01*
X1102531Y192009D01*
X1102706D01*
Y190409D01*
X1102531D01*
G37*
G36*
G01Y194309D02*
X1101771Y194659D01*
Y195559D01*
X1102531Y195909D01*
X1102706D01*
Y194309D01*
X1102531D01*
G37*
G36*
G01X1103499Y215436D02*
X1102829Y215786D01*
Y216656D01*
X1103499Y217006D01*
X1103674D01*
Y215436D01*
X1103499D01*
G37*
G36*
G01X1103705Y208976D02*
X1102945Y209326D01*
Y210226D01*
X1103705Y210576D01*
X1103880D01*
Y208976D01*
X1103705D01*
G37*
G36*
G01Y205076D02*
X1102945Y205426D01*
Y206326D01*
X1103705Y206676D01*
X1103880D01*
Y205076D01*
X1103705D01*
G37*
G36*
G01X1103927Y202288D02*
X1104687Y201938D01*
Y201038D01*
X1103927Y200688D01*
X1103752D01*
Y202288D01*
X1103927D01*
G37*
G36*
G01X1103631Y192009D02*
X1104391Y191659D01*
Y190759D01*
X1103631Y190409D01*
X1103456D01*
Y192009D01*
X1103631D01*
G37*
G36*
G01Y195909D02*
X1104391Y195559D01*
Y194659D01*
X1103631Y194309D01*
X1103456D01*
Y195909D01*
X1103631D01*
G37*
G36*
G01X1105123Y215007D02*
X1105793Y214657D01*
Y213787D01*
X1105123Y213437D01*
X1104948D01*
Y215007D01*
X1105123D01*
G37*
G36*
G01X1104805Y210576D02*
X1105565Y210226D01*
Y209326D01*
X1104805Y208976D01*
X1104630D01*
Y210576D01*
X1104805D01*
G37*
G36*
G01Y206676D02*
X1105565Y206326D01*
Y205426D01*
X1104805Y205076D01*
X1104630D01*
Y206676D01*
X1104805D01*
G37*
G36*
G01X1120906Y195793D02*
X1120122Y195503D01*
X1119485Y196140D01*
X1119775Y196924D01*
X1119899Y197048D01*
X1121030Y195917D01*
X1120906Y195793D01*
G37*
G36*
G01X1119288Y198797D02*
X1118528Y199147D01*
Y200047D01*
X1119288Y200397D01*
X1119463D01*
Y198797D01*
X1119288D01*
G37*
G36*
G01X1119076Y201849D02*
X1118292Y201559D01*
X1117655Y202196D01*
X1117945Y202980D01*
X1118069Y203104D01*
X1119200Y201973D01*
X1119076Y201849D01*
G37*
G36*
G01X1117631Y203844D02*
X1116871Y204194D01*
Y205094D01*
X1117631Y205444D01*
X1117806D01*
Y203844D01*
X1117631D01*
G37*
G36*
G01X1116977Y213515D02*
X1116217Y213865D01*
Y214765D01*
X1116977Y215115D01*
X1117152D01*
Y213515D01*
X1116977D01*
G37*
G36*
G01X1117631Y208244D02*
X1116871Y208594D01*
Y209494D01*
X1117631Y209844D01*
X1117806D01*
Y208244D01*
X1117631D01*
G37*
G36*
G01X1120388Y201397D02*
X1121148Y201047D01*
Y200147D01*
X1120388Y199797D01*
X1120213D01*
Y201397D01*
X1120388D01*
G37*
G36*
G01X1120678Y197579D02*
X1121462Y197869D01*
X1122099Y197232D01*
X1121809Y196448D01*
X1121685Y196324D01*
X1120554Y197455D01*
X1120678Y197579D01*
G37*
G36*
G01X1118643Y218907D02*
X1119313Y218557D01*
Y217687D01*
X1118643Y217337D01*
X1118468D01*
Y218907D01*
X1118643D01*
G37*
G36*
G01X1118731Y205944D02*
X1119491Y205594D01*
Y204694D01*
X1118731Y204344D01*
X1118556D01*
Y205944D01*
X1118731D01*
G37*
G36*
G01Y209844D02*
X1119491Y209494D01*
Y208594D01*
X1118731Y208244D01*
X1118556D01*
Y209844D01*
X1118731D01*
G37*
G36*
G01X1118077Y215115D02*
X1118837Y214765D01*
Y213865D01*
X1118077Y213515D01*
X1117902D01*
Y215115D01*
X1118077D01*
G37*
G36*
G01X1099979Y202181D02*
X1099219Y202531D01*
Y203431D01*
X1099979Y203781D01*
X1100154D01*
Y202181D01*
X1099979D01*
G37*
G36*
G01X1097863Y195940D02*
X1097573Y196725D01*
X1098209Y197361D01*
X1098994Y197071D01*
X1099118Y196948D01*
X1097986Y195816D01*
X1097863Y195940D01*
G37*
G36*
G01X1099209Y198941D02*
X1098449Y199291D01*
Y200191D01*
X1099209Y200541D01*
X1099384D01*
Y198941D01*
X1099209D01*
G37*
G36*
G01X1100119Y213437D02*
X1099449Y213787D01*
Y214657D01*
X1100119Y215007D01*
X1100294D01*
Y213437D01*
X1100119D01*
G37*
G36*
G01X1100685Y209498D02*
X1099925Y209848D01*
Y210748D01*
X1100685Y211098D01*
X1100860D01*
Y209498D01*
X1100685D01*
G37*
G36*
G01Y205598D02*
X1099925Y205948D01*
Y206848D01*
X1100685Y207198D01*
X1100860D01*
Y205598D01*
X1100685D01*
G37*
G36*
G01X1100119Y217337D02*
X1099449Y217687D01*
Y218557D01*
X1100119Y218907D01*
X1100294D01*
Y217337D01*
X1100119D01*
G37*
G36*
G01X1100309Y199541D02*
X1101069Y199191D01*
Y198291D01*
X1100309Y197941D01*
X1100134D01*
Y199541D01*
X1100309D01*
G37*
G36*
G01X1100013Y196533D02*
X1100303Y195748D01*
X1099667Y195112D01*
X1098882Y195402D01*
X1098758Y195525D01*
X1099890Y196657D01*
X1100013Y196533D01*
G37*
G36*
G01X1101079Y203781D02*
X1101839Y203431D01*
Y202531D01*
X1101079Y202181D01*
X1100904D01*
Y203781D01*
X1101079D01*
G37*
G36*
G01X1101743Y217006D02*
X1102413Y216656D01*
Y215786D01*
X1101743Y215436D01*
X1101568D01*
Y217006D01*
X1101743D01*
G37*
G36*
G01X1101785Y211098D02*
X1102545Y210748D01*
Y209848D01*
X1101785Y209498D01*
X1101610D01*
Y211098D01*
X1101785D01*
G37*
G36*
G01Y207198D02*
X1102545Y206848D01*
Y205948D01*
X1101785Y205598D01*
X1101610D01*
Y207198D01*
X1101785D01*
G37*
G36*
G01X1116268Y193142D02*
X1115508Y193492D01*
Y194392D01*
X1116268Y194742D01*
X1116443D01*
Y193142D01*
X1116268D01*
G37*
G36*
G01Y197042D02*
X1115508Y197392D01*
Y198292D01*
X1116268Y198642D01*
X1116443D01*
Y197042D01*
X1116268D01*
G37*
G36*
G01X1115427Y201196D02*
X1114642Y200906D01*
X1114005Y201542D01*
X1114295Y202327D01*
X1114419Y202451D01*
X1115550Y201320D01*
X1115427Y201196D01*
G37*
G36*
G01X1114162Y212615D02*
X1113402Y212965D01*
Y213865D01*
X1114162Y214215D01*
X1114337D01*
Y212615D01*
X1114162D01*
G37*
G36*
G01X1113640Y203955D02*
X1112880Y204305D01*
Y205205D01*
X1113640Y205555D01*
X1113815D01*
Y203955D01*
X1113640D01*
G37*
G36*
G01Y207455D02*
X1112880Y207805D01*
Y208705D01*
X1113640Y209055D01*
X1113815D01*
Y207455D01*
X1113640D01*
G37*
G36*
G01X1117368Y194742D02*
X1118128Y194392D01*
Y193492D01*
X1117368Y193142D01*
X1117193D01*
Y194742D01*
X1117368D01*
G37*
G36*
G01X1115077Y203134D02*
X1115861Y203424D01*
X1116498Y202787D01*
X1116208Y202003D01*
X1116084Y201879D01*
X1114953Y203010D01*
X1115077Y203134D01*
G37*
G36*
G01X1117368Y198642D02*
X1118128Y198292D01*
Y197392D01*
X1117368Y197042D01*
X1117193D01*
Y198642D01*
X1117368D01*
G37*
G36*
G01X1115263Y213415D02*
X1116023Y213065D01*
Y212165D01*
X1115263Y211815D01*
X1115088D01*
Y213415D01*
X1115263D01*
G37*
G36*
G01X1114741Y209055D02*
X1115501Y208705D01*
Y207805D01*
X1114741Y207455D01*
X1114566D01*
Y209055D01*
X1114741D01*
G37*
G36*
G01X1123778Y215436D02*
X1123108Y215786D01*
Y216656D01*
X1123778Y217006D01*
X1123953D01*
Y215436D01*
X1123778D01*
G37*
G36*
G01X1126276Y208690D02*
X1125492Y208400D01*
X1124855Y209037D01*
X1125145Y209821D01*
X1125269Y209945D01*
X1126400Y208814D01*
X1126276Y208690D01*
G37*
G36*
G01X1127148Y206045D02*
X1126388Y206395D01*
Y207295D01*
X1127148Y207645D01*
X1127323D01*
Y206045D01*
X1127148D01*
G37*
G36*
G01X1129397Y202852D02*
X1128613Y202562D01*
X1127976Y203199D01*
X1128266Y203983D01*
X1128390Y204107D01*
X1129521Y202976D01*
X1129397Y202852D01*
G37*
G36*
G01X1132197Y200052D02*
X1131413Y199762D01*
X1130776Y200399D01*
X1131066Y201183D01*
X1131190Y201307D01*
X1132321Y200176D01*
X1132197Y200052D01*
G37*
G36*
G01X1125402Y215007D02*
X1126072Y214657D01*
Y213787D01*
X1125402Y213437D01*
X1125227D01*
Y215007D01*
X1125402D01*
G37*
G36*
G01X1126220Y210303D02*
X1127004Y210593D01*
X1127641Y209956D01*
X1127351Y209172D01*
X1127227Y209048D01*
X1126096Y210179D01*
X1126220Y210303D01*
G37*
G36*
G01X1129046Y204763D02*
X1129831Y205053D01*
X1130467Y204417D01*
X1130177Y203632D01*
X1130054Y203508D01*
X1128922Y204640D01*
X1129046Y204763D01*
G37*
G36*
G01X1131846Y201963D02*
X1132631Y202253D01*
X1133267Y201617D01*
X1132977Y200832D01*
X1132854Y200708D01*
X1131722Y201840D01*
X1131846Y201963D01*
G37*
G36*
G01X1140891Y217376D02*
X1140131Y217726D01*
Y218626D01*
X1140891Y218976D01*
X1141066D01*
Y217376D01*
X1140891D01*
G37*
G36*
G01Y213476D02*
X1140131Y213826D01*
Y214726D01*
X1140891Y215076D01*
X1141066D01*
Y213476D01*
X1140891D01*
G37*
G36*
G01X1143497Y209450D02*
X1142712Y209160D01*
X1142076Y209796D01*
X1142366Y210581D01*
X1142489Y210705D01*
X1143621Y209573D01*
X1143497Y209450D01*
G37*
G36*
G01X1141991Y218976D02*
X1142751Y218626D01*
Y217726D01*
X1141991Y217376D01*
X1141816D01*
Y218976D01*
X1141991D01*
G37*
G36*
G01Y215076D02*
X1142751Y214726D01*
Y213826D01*
X1141991Y213476D01*
X1141816D01*
Y215076D01*
X1141991D01*
G37*
G36*
G01X1144144Y210359D02*
X1144929Y210649D01*
X1145565Y210013D01*
X1145275Y209228D01*
X1145152Y209104D01*
X1144020Y210236D01*
X1144144Y210359D01*
G37*
G36*
G01X1125948Y201942D02*
X1125163Y201652D01*
X1124527Y202288D01*
X1124817Y203073D01*
X1124940Y203197D01*
X1126072Y202065D01*
X1125948Y201942D01*
G37*
G36*
G01X1124294Y204500D02*
X1123534Y204850D01*
Y205750D01*
X1124294Y206100D01*
X1124469D01*
Y204500D01*
X1124294D01*
G37*
G36*
G01X1123396Y207613D02*
X1122611Y207323D01*
X1121975Y207959D01*
X1122265Y208744D01*
X1122388Y208868D01*
X1123520Y207736D01*
X1123396Y207613D01*
G37*
G36*
G01X1120398Y217337D02*
X1119728Y217687D01*
Y218557D01*
X1120398Y218907D01*
X1120573D01*
Y217337D01*
X1120398D01*
G37*
G36*
G01Y213437D02*
X1119728Y213787D01*
Y214657D01*
X1120398Y215007D01*
X1120573D01*
Y213437D01*
X1120398D01*
G37*
G36*
G01X1125394Y206100D02*
X1126154Y205750D01*
Y204850D01*
X1125394Y204500D01*
X1125219D01*
Y206100D01*
X1125394D01*
G37*
G36*
G01X1123043Y209522D02*
X1123827Y209812D01*
X1124464Y209175D01*
X1124174Y208391D01*
X1124050Y208267D01*
X1122919Y209398D01*
X1123043Y209522D01*
G37*
G36*
G01X1122022Y217006D02*
X1122692Y216656D01*
Y215786D01*
X1122022Y215436D01*
X1121847D01*
Y217006D01*
X1122022D01*
G37*
G36*
G01X1126595Y202851D02*
X1127379Y203141D01*
X1128016Y202504D01*
X1127726Y201720D01*
X1127602Y201596D01*
X1126471Y202727D01*
X1126595Y202851D01*
G37*
G36*
G01X1134967Y218353D02*
X1135026Y217599D01*
X1134288Y217138D01*
X1133636Y217520D01*
X1133544Y217669D01*
X1134875Y218501D01*
X1134967Y218353D01*
G37*
G36*
G01X1137871Y215626D02*
X1137111Y215976D01*
Y216876D01*
X1137871Y217226D01*
X1138046D01*
Y215626D01*
X1137871D01*
G37*
G36*
G01X1140038Y208640D02*
X1139253Y208351D01*
X1138617Y208987D01*
X1138907Y209772D01*
X1139030Y209896D01*
X1140162Y208764D01*
X1140038Y208640D01*
G37*
G36*
G01X1137871Y211726D02*
X1137111Y212076D01*
Y212976D01*
X1137871Y213326D01*
X1138046D01*
Y211726D01*
X1137871D01*
G37*
G36*
G01X1142838Y205840D02*
X1142053Y205551D01*
X1141417Y206187D01*
X1141707Y206972D01*
X1141830Y207096D01*
X1142962Y205964D01*
X1142838Y205840D01*
G37*
G36*
G01X1138971Y217226D02*
X1139731Y216876D01*
Y215976D01*
X1138971Y215626D01*
X1138796D01*
Y217226D01*
X1138971D01*
G37*
G36*
G01X1139679Y210556D02*
X1140464Y210846D01*
X1141101Y210209D01*
X1140811Y209424D01*
X1140687Y209300D01*
X1139556Y210432D01*
X1139679Y210556D01*
G37*
G36*
G01X1138971Y213326D02*
X1139731Y212976D01*
Y212076D01*
X1138971Y211726D01*
X1138796D01*
Y213326D01*
X1138971D01*
G37*
G36*
G01X1142479Y207756D02*
X1143264Y208046D01*
X1143901Y207409D01*
X1143611Y206624D01*
X1143487Y206500D01*
X1142356Y207632D01*
X1142479Y207756D01*
G37*
G36*
G01X1108130Y196711D02*
X1108890Y196361D01*
Y195461D01*
X1108130Y195111D01*
X1107955D01*
Y196711D01*
X1108130D01*
G37*
G36*
G01Y192811D02*
X1108890Y192461D01*
Y191561D01*
X1108130Y191211D01*
X1107955D01*
Y192811D01*
X1108130D01*
G37*
G36*
G01X1108297Y203422D02*
X1108587Y202637D01*
X1107951Y202001D01*
X1107166Y202291D01*
X1107042Y202414D01*
X1108174Y203546D01*
X1108297Y203422D01*
G37*
G36*
G01X1108521Y212482D02*
X1109281Y212132D01*
Y211232D01*
X1108521Y210882D01*
X1108346D01*
Y212482D01*
X1108521D01*
G37*
G36*
G01Y208582D02*
X1109281Y208232D01*
Y207332D01*
X1108521Y206982D01*
X1108346D01*
Y208582D01*
X1108521D01*
G37*
G36*
G01X1130253Y212892D02*
X1130891Y213297D01*
X1131644Y212862D01*
X1131612Y212107D01*
X1131525Y211955D01*
X1130165Y212741D01*
X1130253Y212892D01*
G37*
G36*
G01X1128781Y216960D02*
X1129451Y216610D01*
Y215740D01*
X1128781Y215390D01*
X1128606D01*
X1128605Y216960D01*
X1128781D01*
G37*
G36*
G01X1132162Y211131D02*
X1132832Y210781D01*
Y209911D01*
X1132162Y209561D01*
X1131987D01*
Y211131D01*
X1132162D01*
G37*
G36*
G01X1135700Y203432D02*
X1136484Y203722D01*
X1137121Y203085D01*
X1136831Y202301D01*
X1136707Y202177D01*
X1135576Y203308D01*
X1135700Y203432D01*
G37*
G36*
G01X1132900Y206232D02*
X1133684Y206522D01*
X1134321Y205885D01*
X1134031Y205101D01*
X1133907Y204977D01*
X1132776Y206108D01*
X1132900Y206232D01*
G37*
G36*
G01X1110620Y202735D02*
X1109860Y203085D01*
Y203985D01*
X1110620Y204335D01*
X1110795D01*
Y202735D01*
X1110620D01*
G37*
G36*
G01X1111961Y192353D02*
X1111201Y192703D01*
Y193603D01*
X1111961Y193953D01*
X1112136D01*
Y192353D01*
X1111961D01*
G37*
G36*
G01X1110259Y215412D02*
X1109589Y215762D01*
Y216632D01*
X1110259Y216982D01*
X1110434D01*
Y215412D01*
X1110259D01*
G37*
G36*
G01X1110620Y210535D02*
X1109860Y210885D01*
Y211785D01*
X1110620Y212135D01*
X1110795D01*
Y210535D01*
X1110620D01*
G37*
G36*
G01Y206635D02*
X1109860Y206985D01*
Y207885D01*
X1110620Y208235D01*
X1110795D01*
Y206635D01*
X1110620D01*
G37*
G36*
G01X1133918Y209581D02*
X1133248Y209931D01*
Y210801D01*
X1133918Y211151D01*
X1134093D01*
Y209581D01*
X1133918D01*
G37*
G36*
G01X1132438Y213656D02*
X1131800Y213251D01*
X1131047Y213686D01*
X1131079Y214441D01*
X1131166Y214593D01*
X1132526Y213807D01*
X1132438Y213656D01*
G37*
G36*
G01X1136938Y206422D02*
X1136153Y206132D01*
X1135517Y206768D01*
X1135807Y207553D01*
X1135930Y207677D01*
X1137062Y206545D01*
X1136938Y206422D01*
G37*
G36*
G01X1107030Y195111D02*
X1106270Y195461D01*
Y196361D01*
X1107030Y196711D01*
X1107205D01*
Y195111D01*
X1107030D01*
G37*
G36*
G01Y191211D02*
X1106270Y191561D01*
Y192461D01*
X1107030Y192811D01*
X1107205D01*
Y191211D01*
X1107030D01*
G37*
G36*
G01X1106035Y202715D02*
X1105745Y203500D01*
X1106381Y204136D01*
X1107166Y203846D01*
X1107290Y203723D01*
X1106158Y202591D01*
X1106035Y202715D01*
G37*
G36*
G01X1106879Y213437D02*
X1106209Y213787D01*
Y214657D01*
X1106879Y215007D01*
X1107054D01*
Y213437D01*
X1106879D01*
G37*
G36*
G01X1107421Y208882D02*
X1106661Y209232D01*
Y210132D01*
X1107421Y210482D01*
X1107596D01*
Y208882D01*
X1107421D01*
G37*
G36*
G01Y205482D02*
X1106661Y205832D01*
Y206732D01*
X1107421Y207082D01*
X1107596D01*
Y205482D01*
X1107421D01*
G37*
G36*
G01X1130538Y207611D02*
X1129868Y207961D01*
Y208831D01*
X1130538Y209181D01*
X1130713D01*
Y207611D01*
X1130538D01*
G37*
G36*
G01X1129067Y211701D02*
X1128429Y211296D01*
X1127676Y211731D01*
X1127708Y212486D01*
X1127795Y212637D01*
X1129155Y211853D01*
X1129067Y211701D01*
G37*
G36*
G01X1127158Y213437D02*
X1126488Y213787D01*
Y214657D01*
X1127158Y215007D01*
X1127333D01*
Y213437D01*
X1127158D01*
G37*
G36*
G01X1136053Y201523D02*
X1135268Y201233D01*
X1134632Y201869D01*
X1134922Y202654D01*
X1135045Y202778D01*
X1136177Y201646D01*
X1136053Y201523D01*
G37*
G36*
G01X1133253Y204323D02*
X1132468Y204033D01*
X1131832Y204669D01*
X1132122Y205454D01*
X1132245Y205578D01*
X1133377Y204446D01*
X1133253Y204323D01*
G37*
G36*
G01X1111720Y204335D02*
X1112480Y203985D01*
Y203085D01*
X1111720Y202735D01*
X1111545D01*
Y204335D01*
X1111720D01*
G37*
G36*
G01X1113061Y193953D02*
X1113821Y193603D01*
Y192703D01*
X1113061Y192353D01*
X1112886D01*
Y193953D01*
X1113061D01*
G37*
G36*
G01X1111720Y212135D02*
X1112480Y211785D01*
Y210885D01*
X1111720Y210535D01*
X1111545D01*
Y212135D01*
X1111720D01*
G37*
G36*
G01Y208235D02*
X1112480Y207885D01*
Y206985D01*
X1111720Y206635D01*
X1111545D01*
Y208235D01*
X1111720D01*
G37*
G36*
G01X1111883Y218932D02*
X1112553Y218582D01*
Y217712D01*
X1111883Y217362D01*
X1111708D01*
Y218932D01*
X1111883D01*
G37*
G36*
G01X1133648Y214833D02*
X1134286Y215238D01*
X1135039Y214803D01*
X1135007Y214048D01*
X1134920Y213896D01*
X1133560Y214681D01*
X1133648Y214833D01*
G37*
G36*
G01X1135542Y213081D02*
X1136212Y212731D01*
Y211861D01*
X1135542Y211511D01*
X1135367D01*
Y213081D01*
X1135542D01*
G37*
G36*
G01X1136585Y208331D02*
X1137369Y208621D01*
X1138006Y207984D01*
X1137716Y207200D01*
X1137592Y207076D01*
X1136461Y208207D01*
X1136585Y208331D01*
G37*
G36*
G01X1096739Y219336D02*
X1096069Y219686D01*
Y220556D01*
X1096739Y220906D01*
X1096914D01*
Y219336D01*
X1096739D01*
G37*
G36*
G01X1098363Y222807D02*
X1099033Y222457D01*
Y221587D01*
X1098363Y221237D01*
X1098188D01*
Y222807D01*
X1098363D01*
G37*
G36*
G01X1106222Y222218D02*
X1106921Y222506D01*
X1107587Y221947D01*
X1107424Y221209D01*
X1107312Y221075D01*
X1106109Y222084D01*
X1106222Y222218D01*
G37*
G36*
G01X1118643Y222807D02*
X1119313Y222457D01*
Y221587D01*
X1118643Y221237D01*
X1118468D01*
Y222807D01*
X1118643D01*
G37*
G36*
G01X1115263Y220882D02*
X1115933Y220532D01*
Y219662D01*
X1115263Y219312D01*
X1115088D01*
Y220882D01*
X1115263D01*
G37*
G36*
G01X1114348Y225075D02*
X1115069Y224847D01*
X1115220Y223990D01*
X1114621Y223529D01*
X1114448Y223499D01*
X1114176Y225045D01*
X1114348Y225075D01*
G37*
G36*
G01X1127158Y221237D02*
X1126488Y221587D01*
Y222457D01*
X1127158Y222807D01*
X1127333D01*
Y221237D01*
X1127158D01*
G37*
G36*
G01X1135839Y223362D02*
X1135187Y222979D01*
X1134449Y223441D01*
X1134508Y224193D01*
X1134600Y224343D01*
X1135932Y223510D01*
X1135839Y223362D01*
G37*
G36*
G01X1140297Y221722D02*
X1139513Y221432D01*
X1138876Y222069D01*
X1139166Y222853D01*
X1139290Y222977D01*
X1140421Y221846D01*
X1140297Y221722D01*
G37*
G36*
G01X1135542Y228706D02*
X1136212Y228356D01*
Y227486D01*
X1135542Y227136D01*
X1135367D01*
Y228706D01*
X1135542D01*
G37*
G36*
G01X1139944Y223631D02*
X1140729Y223921D01*
X1141365Y223285D01*
X1141075Y222500D01*
X1140952Y222376D01*
X1139820Y223508D01*
X1139944Y223631D01*
G37*
G36*
G01X1124826Y222220D02*
X1125336Y221662D01*
X1125038Y220844D01*
X1124289Y220744D01*
X1124125Y220804D01*
X1124661Y222280D01*
X1124826Y222220D01*
G37*
G36*
G01X1134459Y219902D02*
X1134427Y220657D01*
X1135180Y221092D01*
X1135818Y220687D01*
X1135906Y220536D01*
X1134546Y219751D01*
X1134459Y219902D01*
G37*
G36*
G01X1110259Y219312D02*
X1109589Y219662D01*
Y220532D01*
X1110259Y220882D01*
X1110434D01*
Y219312D01*
X1110259D01*
G37*
G36*
G01X1130538Y219336D02*
X1129868Y219686D01*
Y220556D01*
X1130538Y220906D01*
X1130713D01*
Y219336D01*
X1130538D01*
G37*
G36*
G01Y223236D02*
X1129868Y223586D01*
Y224456D01*
X1130538Y224806D01*
X1130713D01*
Y223236D01*
X1130538D01*
G37*
G36*
G01X1111882Y222789D02*
X1112552Y222439D01*
Y221569D01*
X1111882Y221219D01*
X1111708D01*
X1111707Y222790D01*
X1111882Y222789D01*
G37*
G36*
G01X1132162Y226707D02*
X1132832Y226357D01*
Y225487D01*
X1132162Y225137D01*
X1131987D01*
Y226707D01*
X1132162D01*
G37*
G36*
G01Y222807D02*
X1132832Y222457D01*
Y221587D01*
X1132162Y221237D01*
X1131987D01*
Y222807D01*
X1132162D01*
G37*
G36*
G01X1182836Y275060D02*
G02X1182535Y275724I0J400D01*
G03X1180775Y275433I-1056J922D01*
G01X1180875Y275376D01*
Y275060D01*
X1180310D01*
X1180273Y275024D01*
X1179469D01*
X1179423Y275158D01*
G03X1176775I-1324J-462D01*
G01X1176729Y275024D01*
X1176043D01*
G02X1175749Y275695I0J400D01*
G03X1174423Y275276I-1030J951D01*
G02X1174621Y274602I-85J-391D01*
G01X1173914Y273895D01*
G03X1173825Y273827I806J-1147D01*
G01X1173718Y273738D01*
X1172698Y274325D01*
X1172721Y274463D01*
G03X1170443Y275774I-1382J233D01*
G01X1170336Y275685D01*
X1169318Y276272D01*
X1169342Y276409D01*
G03X1167061Y277722I-1382J237D01*
G01X1166954Y277633D01*
X1165937Y278218D01*
X1165961Y278356D01*
G03X1163679Y279670I-1381J240D01*
G01X1163572Y279580D01*
X1162556Y280165D01*
X1162581Y280303D01*
G03X1160296Y281618I-1381J244D01*
G01X1160188Y281528D01*
X1159175Y282111D01*
X1159200Y282249D01*
G03X1156429Y282675I-1380J247D01*
G01X1156407Y282500D01*
X1152473D01*
X1152451Y282675D01*
G03X1149925Y283319I-1391J-179D01*
G01X1149820Y283174D01*
X1148885Y283708D01*
X1148959Y283874D01*
G03X1146537Y285258I-1279J573D01*
G01X1146432Y285110D01*
X1145498Y285644D01*
X1145574Y285811D01*
G03X1142923Y286662I-1274J585D01*
G01X1142892Y286500D01*
X1138948D01*
X1138917Y286662D01*
G03X1136163I-1377J-266D01*
G01X1136132Y286500D01*
X1132188D01*
X1132157Y286662D01*
G03X1129580Y287121I-1377J-266D01*
G02X1128955Y287045I-342J207D01*
G01X1128516Y287484D01*
X1128598Y287618D01*
G03X1126543Y289457I-1198J729D01*
G01X1122500Y293500D01*
Y304500D01*
X1120911Y306089D01*
X1120900Y306150D01*
G03X1119775Y307275I-1379J-254D01*
G01X1119714Y307286D01*
X1119500Y307500D01*
X1117000D01*
X1116500Y308000D01*
Y317500D01*
X1118000Y319000D01*
X1120000D01*
X1123154Y315846D01*
Y314654D01*
X1125244Y312564D01*
X1127536D01*
X1128044Y312056D01*
Y310744D01*
X1128000Y310700D01*
Y309637D01*
G02X1127556Y309240I-400J1D01*
G03Y306454I-156J-1393D01*
G02X1128000Y306057I44J-398D01*
G01Y305737D01*
G02X1127556Y305340I-400J1D01*
G03Y302554I-156J-1393D01*
G02X1128000Y302157I44J-398D01*
G01Y301837D01*
G02X1127556Y301440I-400J1D01*
G03X1128553Y299250I-156J-1393D01*
G02X1129084Y299368I329J-228D01*
G01X1129352Y299211D01*
G02X1129512Y298695I-201J-345D01*
G03X1131855Y297196I1268J-599D01*
G02X1132445Y297223I307J-256D01*
G01X1132897Y296770D01*
X1132851Y296649D01*
G03X1135429Y295551I1309J-502D01*
G02X1136074Y295664I362J-170D01*
G01X1136287Y295450D01*
X1136534D01*
Y295175D01*
X1136485Y295119D01*
G03X1138584Y295132I1055J-923D01*
G01X1138458Y295273D01*
X1138959Y295774D01*
G02X1139614Y295636I282J-283D01*
G03X1142189Y295551I1306J511D01*
G02X1142834Y295664I362J-170D01*
G01X1143053Y295444D01*
X1143289D01*
Y295170D01*
X1143240Y295114D01*
G03X1145344Y295132I1060J-918D01*
G01X1145218Y295273D01*
X1145719Y295774D01*
G02X1146374Y295636I282J-283D01*
G03X1148721Y295208I1306J511D01*
G02X1149301Y295223I297J-268D01*
G01X1149768Y294755D01*
X1149730Y294638D01*
G03X1152208Y293391I1330J-442D01*
G02X1152734Y293509I328J-229D01*
G01X1152861Y293437D01*
X1153268Y293030D01*
X1153199Y292900D01*
G03X1155746Y291736I1241J-653D01*
G02X1156401Y291874I373J-145D01*
G01X1156902Y291373D01*
X1156776Y291232D01*
G03X1158864I1044J-936D01*
G01X1158738Y291373D01*
X1159239Y291874D01*
G02X1159894Y291736I282J-283D01*
G03X1162241Y291308I1306J511D01*
G02X1162821Y291323I297J-268D01*
G01X1163288Y290855D01*
X1163250Y290738D01*
G03X1165708Y289464I1330J-441D01*
G01X1165816Y289610D01*
X1166181Y289391D01*
X1166668Y288905D01*
X1166629Y288788D01*
G03X1169052Y287468I1331J-441D01*
G01X1169161Y287603D01*
X1170087Y287048D01*
X1170028Y286892D01*
G03X1172644Y285885I1311J-496D01*
G02X1173300Y286022I373J-146D01*
G01X1173666Y285656D01*
G02X1173673Y285381I-142J-141D01*
G03X1175954Y285110I1046J-934D01*
G02X1176306Y285700I352J190D01*
G01X1176882D01*
G03X1179316I1217J696D01*
G01X1179892D01*
G02X1180244Y285110I0J-400D01*
G03X1182536Y285368I1235J-663D01*
G02X1182686Y285700I151J132D01*
G01X1182863D01*
X1182989Y285825D01*
G02X1183624Y285732I283J-283D01*
G03X1185973Y285545I1235J664D01*
G01X1186132Y285624D01*
X1186249Y285586D01*
G03X1186842Y285244I1988J2762D01*
G01X1186959Y285062D01*
X1186944Y284985D01*
G03X1189353Y283596I1295J-538D01*
G02X1189629Y283636I159J-122D01*
G03X1190222Y283293I1992J2759D01*
G01X1190339Y283111D01*
X1190324Y283034D01*
G03X1192733Y281645I1295J-538D01*
G01X1192892Y281724D01*
X1193009Y281686D01*
G03X1193557Y281365I1987J2763D01*
G01X1193566Y281360D01*
X1193768Y281239D01*
X1193702Y281080D01*
G03X1196080Y279654I1297J-533D01*
G01X1196189Y279786D01*
X1197117Y279230D01*
X1197061Y279075D01*
G03X1199770Y278775I1318J-478D01*
G01X1199768Y278787D01*
Y279000D01*
X1200000D01*
X1200658Y279658D01*
X1200799Y279525D01*
G03X1203054Y281085I960J1022D01*
G01X1203039Y281162D01*
X1203156Y281344D01*
G03X1203416Y281475I-1400J3102D01*
G01X1203462Y281500D01*
X1204152D01*
G03X1206126I987J996D01*
G01X1206865D01*
X1206915Y281468D01*
G03X1207376Y281220I1901J2981D01*
G02X1207484Y280976I-82J-182D01*
G03X1209751Y279500I1335J-429D01*
G01X1217254D01*
X1236500Y260254D01*
Y208000D01*
X1244882Y199618D01*
X1244894Y199598D01*
G03X1245358Y199134I1196J732D01*
G01X1245378Y199122D01*
X1246480Y198020D01*
X1246495Y197981D01*
G03X1247298Y197178I1308J505D01*
G01X1247337Y197163D01*
X1248248Y196252D01*
X1248263Y196213D01*
G03X1249066Y195410I1308J505D01*
G01X1249105Y195395D01*
X1249685Y194815D01*
X1249689Y194738D01*
G03X1250000Y193927I1400J72D01*
G01Y178700D01*
X1249200Y177900D01*
X1245900D01*
X1245400Y177400D01*
Y177021D01*
X1245382Y176982D01*
G03Y175808I1273J-587D01*
G01X1245400Y175769D01*
Y175400D01*
X1246000Y174800D01*
X1247800D01*
X1248400Y174200D01*
Y171800D01*
X1247666Y171066D01*
X1243089D01*
G02X1242710Y171593I0J400D01*
G03X1240154Y171362I-1329J447D01*
G01X1240179Y171317D01*
Y171066D01*
X1239710D01*
X1233248Y177528D01*
X1231762D01*
X1231760Y177530D01*
X1226478D01*
X1225366Y178643D01*
Y198155D01*
G02X1225929Y198520I400J0D01*
G03X1227471Y200811I571J1280D01*
G02Y201389I277J289D01*
G03X1225929Y203680I-971J1011D01*
G02X1225366Y204045I-163J365D01*
G01Y206478D01*
G02X1226010Y206794I400J0D01*
G03X1227844Y208909I857J1110D01*
G02X1227826Y209464I279J287D01*
G03X1227756Y211414I-1041J939D01*
G02Y211992I277J289D01*
G03X1227915Y213833I-971J1011D01*
G02X1228007Y214397I322J237D01*
G03X1226070Y214713I-807J1146D01*
G02X1225978Y214149I-322J-237D01*
G03X1225718Y213912I807J-1146D01*
G01X1225366Y214042D01*
Y221208D01*
X1228040Y223882D01*
Y224640D01*
X1228100Y224700D01*
Y248640D01*
X1228040Y248700D01*
Y249019D01*
X1214208Y262850D01*
G02X1214340Y263503I283J283D01*
G03X1215047Y264144I-532J1297D01*
G02X1215586Y264312I354J-187D01*
G03X1217244Y266528I648J1243D01*
G02Y267082I288J277D01*
G03X1217502Y268654I-1010J973D01*
G02X1217716Y269196I362J171D01*
G03X1215932Y269901I-516J1304D01*
G02X1215718Y269359I-362J-171D01*
G03X1215224Y267082I516J-1304D01*
G02Y266528I-288J-277D01*
G03X1214995Y266211I1011J-972D01*
G02X1214456Y266043I-354J187D01*
G03X1212806Y265780I-648J-1243D01*
G01X1212663Y265637D01*
X1210600Y267700D01*
X1210523D01*
X1210472Y267751D01*
G03X1210145Y267932I-479J-479D01*
G02X1209860Y268437I97J388D01*
G03X1207504Y269815I-1341J411D01*
G02X1206932Y269808I-289J276D01*
G01X1206906Y269834D01*
X1206851D01*
G02X1206471Y270359I0J400D01*
G03X1203933Y271511I-1332J437D01*
G02X1203374Y271378I-344J204D01*
G03X1203146Y271510I-1617J-2530D01*
G02X1202982Y272061I184J355D01*
G03X1200599Y273535I-1223J686D01*
G02X1200053Y273423I-331J225D01*
G01X1199835D01*
X1199791Y273446D01*
G03X1199766Y273460I-1479J-2612D01*
G02X1199602Y274010I185J355D01*
G03X1197156I-1223J686D01*
G02X1196992Y273460I-349J-195D01*
G03X1196764Y273328I1389J-2663D01*
G02X1196205Y273462I-215J337D01*
G03X1193651Y273131I-1206J-715D01*
G01X1193609Y272986D01*
X1192871D01*
X1192663Y273194D01*
G02X1192651Y273747I283J283D01*
G03X1190262Y275049I-1032J949D01*
G01X1190248Y274996D01*
X1190069Y274816D01*
X1189861Y275024D01*
X1189345D01*
X1189289Y275080D01*
X1188875D01*
Y275392D01*
X1188971Y275450D01*
G03X1187170Y275738I-732J1196D01*
G02X1186951Y275089I-305J-259D01*
G01X1186886Y275024D01*
X1186229D01*
X1186183Y275158D01*
G03X1183535I-1324J-462D01*
G01X1183489Y275024D01*
X1183098D01*
X1183061Y275060D01*
X1182836D01*
G37*
G36*
G01X1101990Y387031D02*
X1101320Y387381D01*
Y388251D01*
X1101990Y388601D01*
X1102165D01*
Y387031D01*
X1101990D01*
G37*
G36*
G01X1103510Y402751D02*
X1102725Y402461D01*
X1102089Y403097D01*
X1102379Y403882D01*
X1102502Y404006D01*
X1103634Y402874D01*
X1103510Y402751D01*
G37*
G36*
G01X1104814Y395689D02*
X1104054Y396039D01*
Y396939D01*
X1104814Y397289D01*
X1104989D01*
Y395689D01*
X1104814D01*
G37*
G36*
G01Y399589D02*
X1104054Y399939D01*
Y400839D01*
X1104814Y401189D01*
X1104989D01*
Y399589D01*
X1104814D01*
G37*
G36*
G01X1105912Y397289D02*
X1106672Y396939D01*
Y396039D01*
X1105912Y395689D01*
X1105737D01*
Y397289D01*
X1105912D01*
G37*
G36*
G01Y401189D02*
X1106672Y400839D01*
Y399939D01*
X1105912Y399589D01*
X1105737D01*
Y401189D01*
X1105912D01*
G37*
G36*
G01X1106236Y393946D02*
X1106907Y393597D01*
X1106909Y392727D01*
X1106239Y392376D01*
X1106064D01*
X1106061Y393945D01*
X1106236Y393946D01*
G37*
G36*
G01X1098610Y385042D02*
X1097940Y385392D01*
Y386262D01*
X1098610Y386612D01*
X1098785D01*
Y385042D01*
X1098610D01*
G37*
G36*
G01X1099483Y388606D02*
X1100153Y388256D01*
Y387386D01*
X1099483Y387036D01*
X1099308D01*
Y388606D01*
X1099483D01*
G37*
G36*
G01X1101761Y394730D02*
X1101001Y395080D01*
Y395980D01*
X1101761Y396330D01*
X1101936D01*
Y394730D01*
X1101761D01*
G37*
G36*
G01X1100982Y400363D02*
X1100198Y400073D01*
X1099561Y400710D01*
X1099851Y401494D01*
X1099975Y401618D01*
X1101106Y400487D01*
X1100982Y400363D01*
G37*
G36*
G01X1100628Y402271D02*
X1101412Y402561D01*
X1102049Y401924D01*
X1101759Y401140D01*
X1101635Y401016D01*
X1100504Y402147D01*
X1100628Y402271D01*
G37*
G36*
G01X1102859Y394830D02*
X1103619Y394480D01*
Y393580D01*
X1102859Y393230D01*
X1102684D01*
Y394830D01*
X1102859D01*
G37*
G36*
G01Y398730D02*
X1103619Y398380D01*
Y397480D01*
X1102859Y397130D01*
X1102684D01*
Y398730D01*
X1102859D01*
G37*
G36*
G01X1111379Y388984D02*
X1110709Y389334D01*
Y390204D01*
X1111379Y390554D01*
X1111554D01*
Y388984D01*
X1111379D01*
G37*
G36*
G01Y392884D02*
X1110709Y393234D01*
Y394104D01*
X1111379Y394454D01*
X1111554D01*
Y392884D01*
X1111379D01*
G37*
G36*
G01Y396784D02*
X1110709Y397134D01*
Y398004D01*
X1111379Y398354D01*
X1111554D01*
Y396784D01*
X1111379D01*
G37*
G36*
G01Y400660D02*
X1110709Y401010D01*
Y401880D01*
X1111379Y402230D01*
X1111554D01*
Y400660D01*
X1111379D01*
G37*
G36*
G01X1112154Y384909D02*
X1111484Y385259D01*
Y386129D01*
X1112154Y386479D01*
X1112329D01*
Y384909D01*
X1112154D01*
G37*
G36*
G01X1113003Y404205D02*
X1113673Y403855D01*
Y402985D01*
X1113003Y402635D01*
X1112828D01*
Y404205D01*
X1113003D01*
G37*
G36*
G01Y400280D02*
X1113673Y399930D01*
Y399060D01*
X1113003Y398710D01*
X1112828D01*
Y400280D01*
X1113003D01*
G37*
G36*
G01Y396355D02*
X1113673Y396005D01*
Y395135D01*
X1113003Y394785D01*
X1112828D01*
Y396355D01*
X1113003D01*
G37*
G36*
G01X1122597Y388992D02*
X1122565Y389747D01*
X1123318Y390182D01*
X1123957Y389777D01*
X1124044Y389625D01*
X1122684Y388840D01*
X1122597Y388992D01*
G37*
G36*
G01X1124898Y392826D02*
X1124228Y393176D01*
Y394046D01*
X1124898Y394396D01*
X1125073D01*
Y392826D01*
X1124898D01*
G37*
G36*
G01Y396726D02*
X1124228Y397076D01*
Y397946D01*
X1124898Y398296D01*
X1125073D01*
Y396726D01*
X1124898D01*
G37*
G36*
G01Y400626D02*
X1124228Y400976D01*
Y401846D01*
X1124898Y402196D01*
X1125073D01*
Y400626D01*
X1124898D01*
G37*
G36*
G01X1126523Y404217D02*
X1127193Y403867D01*
Y402997D01*
X1126523Y402647D01*
X1126348D01*
Y404217D01*
X1126523D01*
G37*
G36*
G01Y392517D02*
X1127193Y392167D01*
Y391297D01*
X1126523Y390947D01*
X1126348D01*
Y392517D01*
X1126523D01*
G37*
G36*
G01Y400317D02*
X1127193Y399967D01*
Y399097D01*
X1126523Y398747D01*
X1126348D01*
Y400317D01*
X1126523D01*
G37*
G36*
G01Y396417D02*
X1127193Y396067D01*
Y395197D01*
X1126523Y394847D01*
X1126348D01*
Y396417D01*
X1126523D01*
G37*
G36*
G01X1107999Y387046D02*
X1107329Y387396D01*
Y388266D01*
X1107999Y388616D01*
X1108174D01*
Y387046D01*
X1107999D01*
G37*
G36*
G01Y390946D02*
X1107329Y391296D01*
Y392166D01*
X1107999Y392516D01*
X1108174D01*
Y390946D01*
X1107999D01*
G37*
G36*
G01Y394846D02*
X1107329Y395196D01*
Y396066D01*
X1107999Y396416D01*
X1108174D01*
Y394846D01*
X1107999D01*
G37*
G36*
G01Y398746D02*
X1107329Y399096D01*
Y399966D01*
X1107999Y400316D01*
X1108174D01*
Y398746D01*
X1107999D01*
G37*
G36*
G01X1109623Y402196D02*
X1110293Y401846D01*
Y400976D01*
X1109623Y400626D01*
X1109448D01*
Y402196D01*
X1109623D01*
G37*
G36*
G01Y398296D02*
X1110293Y397946D01*
Y397076D01*
X1109623Y396726D01*
X1109448D01*
Y398296D01*
X1109623D01*
G37*
G36*
G01Y394407D02*
X1110293Y394057D01*
Y393187D01*
X1109623Y392837D01*
X1109448D01*
Y394407D01*
X1109623D01*
G37*
G36*
G01X1120348Y387459D02*
X1119627Y387232D01*
X1119012Y387847D01*
X1119238Y388569D01*
X1119362Y388692D01*
X1120472Y387582D01*
X1120348Y387459D01*
G37*
G36*
G01X1121519Y402636D02*
X1120849Y402986D01*
Y403856D01*
X1121519Y404206D01*
X1121694D01*
Y402636D01*
X1121519D01*
G37*
G36*
G01Y394836D02*
X1120849Y395186D01*
Y396056D01*
X1121519Y396406D01*
X1121694D01*
Y394836D01*
X1121519D01*
G37*
G36*
G01Y398736D02*
X1120849Y399086D01*
Y399956D01*
X1121519Y400306D01*
X1121694D01*
Y398736D01*
X1121519D01*
G37*
G36*
G01X1123143Y402207D02*
X1123813Y401857D01*
Y400987D01*
X1123143Y400637D01*
X1122968D01*
Y402207D01*
X1123143D01*
G37*
G36*
G01Y398307D02*
X1123813Y397957D01*
Y397087D01*
X1123143Y396737D01*
X1122968D01*
Y398307D01*
X1123143D01*
G37*
G36*
G01Y394407D02*
X1123813Y394057D01*
Y393187D01*
X1123143Y392837D01*
X1122968D01*
Y394407D01*
X1123143D01*
G37*
G36*
G01X1131658Y392837D02*
X1130988Y393187D01*
Y394057D01*
X1131658Y394407D01*
X1131833D01*
Y392837D01*
X1131658D01*
G37*
G36*
G01X1132180Y401777D02*
X1131420Y402127D01*
X1131421Y403027D01*
X1132181Y403377D01*
X1132356D01*
Y401777D01*
X1132180D01*
G37*
G36*
G01Y397877D02*
X1131420Y398227D01*
X1131421Y399127D01*
X1132181Y399477D01*
X1132356D01*
Y397877D01*
X1132180D01*
G37*
G36*
G01X1131658Y388937D02*
X1130988Y389287D01*
Y390157D01*
X1131658Y390507D01*
X1131833D01*
Y388937D01*
X1131658D01*
G37*
G36*
G01X1133280Y401932D02*
X1134041Y401582D01*
X1134040Y400682D01*
X1133280Y400332D01*
X1133105Y400333D01*
Y401932D01*
X1133280D01*
G37*
G36*
G01Y398032D02*
X1134041Y397682D01*
X1134040Y396782D01*
X1133280Y396432D01*
X1133105Y396433D01*
Y398032D01*
X1133280D01*
G37*
G36*
G01X1128278Y387036D02*
X1127608Y387386D01*
Y388256D01*
X1128278Y388606D01*
X1128453D01*
Y387036D01*
X1128278D01*
G37*
G36*
G01Y390936D02*
X1127608Y391286D01*
Y392156D01*
X1128278Y392506D01*
X1128453D01*
Y390936D01*
X1128278D01*
G37*
G36*
G01Y394836D02*
X1127608Y395186D01*
Y396056D01*
X1128278Y396406D01*
X1128453D01*
Y394836D01*
X1128278D01*
G37*
G36*
G01X1129329Y399612D02*
X1128569Y399962D01*
Y400862D01*
X1129330Y401212D01*
X1129504D01*
Y399612D01*
X1129329D01*
G37*
G36*
G01X1129902Y390507D02*
X1130572Y390157D01*
Y389287D01*
X1129902Y388937D01*
X1129727D01*
Y390507D01*
X1129902D01*
G37*
G36*
G01X1130430Y401267D02*
X1131191Y400917D01*
X1131190Y400017D01*
X1130430Y399667D01*
X1130255Y399668D01*
Y401267D01*
X1130430D01*
G37*
G36*
G01X1129902Y394407D02*
X1130572Y394057D01*
Y393187D01*
X1129902Y392837D01*
X1129727D01*
Y394407D01*
X1129902D01*
G37*
G36*
G01X1141798Y398711D02*
X1141128Y399061D01*
Y399931D01*
X1141798Y400281D01*
X1141973D01*
Y398711D01*
X1141798D01*
G37*
G36*
G01X1095384Y395560D02*
X1096139Y395592D01*
X1096574Y394839D01*
X1096169Y394201D01*
X1096018Y394113D01*
X1095232Y395473D01*
X1095384Y395560D01*
G37*
G36*
G01X1096103Y386607D02*
X1096773Y386257D01*
Y385387D01*
X1096103Y385037D01*
X1095928D01*
Y386607D01*
X1096103D01*
G37*
G36*
G01Y390507D02*
X1096773Y390157D01*
Y389287D01*
X1096103Y388937D01*
X1095928D01*
Y390507D01*
X1096103D01*
G37*
G36*
G01X1119763Y384656D02*
X1120433Y384306D01*
Y383436D01*
X1119763Y383086D01*
X1119588D01*
Y384656D01*
X1119763D01*
G37*
G36*
G01X1116383Y390507D02*
X1117053Y390157D01*
Y389287D01*
X1116383Y388937D01*
X1116208D01*
Y390507D01*
X1116383D01*
G37*
G36*
G01Y402255D02*
X1117053Y401905D01*
Y401035D01*
X1116383Y400685D01*
X1116208D01*
Y402255D01*
X1116383D01*
G37*
G36*
G01Y398365D02*
X1117053Y398015D01*
Y397145D01*
X1116383Y396795D01*
X1116208D01*
Y398365D01*
X1116383D01*
G37*
G36*
G01Y394455D02*
X1117053Y394105D01*
Y393235D01*
X1116383Y392885D01*
X1116208D01*
Y394455D01*
X1116383D01*
G37*
G36*
G01X1136662Y402207D02*
X1137332Y401857D01*
Y400987D01*
X1136662Y400637D01*
X1136487D01*
Y402207D01*
X1136662D01*
G37*
G36*
G01Y398356D02*
X1137332Y398006D01*
Y397136D01*
X1136662Y396786D01*
X1136487D01*
Y398356D01*
X1136662D01*
G37*
G36*
G01Y394432D02*
X1137332Y394082D01*
Y393212D01*
X1136662Y392862D01*
X1136487D01*
Y394432D01*
X1136662D01*
G37*
G36*
G01X1097407Y393440D02*
X1096891Y394099D01*
X1097303Y394899D01*
X1098139Y394863D01*
X1098294Y394784D01*
X1097563Y393360D01*
X1097407Y393440D01*
G37*
G36*
G01X1097893Y396420D02*
X1097108Y396130D01*
X1096472Y396767D01*
X1096762Y397552D01*
X1096885Y397675D01*
X1098017Y396544D01*
X1097893Y396420D01*
G37*
G36*
G01X1096231Y399181D02*
X1095471Y399531D01*
Y400431D01*
X1096231Y400781D01*
X1096406D01*
Y399181D01*
X1096231D01*
G37*
G36*
G01X1117825Y393821D02*
X1117390Y394440D01*
X1117790Y395213D01*
X1118546Y395216D01*
X1118701Y395136D01*
X1117980Y393741D01*
X1117825Y393821D01*
G37*
G36*
G01X1118139Y396737D02*
X1117469Y397087D01*
Y397957D01*
X1118139Y398307D01*
X1118314D01*
Y396737D01*
X1118139D01*
G37*
G36*
G01Y400637D02*
X1117469Y400987D01*
Y401857D01*
X1118139Y402207D01*
X1118314D01*
Y400637D01*
X1118139D01*
G37*
G36*
G01X1138418Y392862D02*
X1137748Y393212D01*
Y394082D01*
X1138418Y394432D01*
X1138593D01*
Y392862D01*
X1138418D01*
G37*
G36*
G01Y396786D02*
X1137748Y397136D01*
Y398006D01*
X1138418Y398356D01*
X1138593D01*
Y396786D01*
X1138418D01*
G37*
G36*
G01X1116668Y385249D02*
X1116030Y384844D01*
X1115277Y385279D01*
X1115309Y386034D01*
X1115396Y386186D01*
X1116756Y385401D01*
X1116668Y385249D01*
G37*
G36*
G01X1114759Y387036D02*
X1114089Y387386D01*
Y388256D01*
X1114759Y388606D01*
X1114934D01*
Y387036D01*
X1114759D01*
G37*
G36*
G01Y402611D02*
X1114089Y402961D01*
Y403831D01*
X1114759Y404181D01*
X1114934D01*
Y402611D01*
X1114759D01*
G37*
G36*
G01Y394786D02*
X1114089Y395136D01*
Y396006D01*
X1114759Y396356D01*
X1114934D01*
Y394786D01*
X1114759D01*
G37*
G36*
G01Y398675D02*
X1114089Y399025D01*
Y399895D01*
X1114759Y400245D01*
X1114934D01*
Y398675D01*
X1114759D01*
G37*
G36*
G01X1114760Y390911D02*
X1114090Y391261D01*
Y392131D01*
X1114760Y392481D01*
X1114935D01*
Y390911D01*
X1114760D01*
G37*
G36*
G01X1135038Y402636D02*
X1134368Y402986D01*
Y403856D01*
X1135038Y404206D01*
X1135213D01*
Y402636D01*
X1135038D01*
G37*
G36*
G01Y390887D02*
X1134368Y391237D01*
Y392107D01*
X1135038Y392457D01*
X1135213D01*
Y390887D01*
X1135038D01*
G37*
G36*
G01Y398711D02*
X1134368Y399061D01*
Y399931D01*
X1135038Y400281D01*
X1135213D01*
Y398711D01*
X1135038D01*
G37*
G36*
G01Y394787D02*
X1134368Y395137D01*
Y396007D01*
X1135038Y396357D01*
X1135213D01*
Y394787D01*
X1135038D01*
G37*
G36*
G01X1095414Y403300D02*
X1096199Y403590D01*
X1096835Y402954D01*
X1096545Y402169D01*
X1096421Y402045D01*
X1095290Y403176D01*
X1095414Y403300D01*
G37*
G36*
G01X1097539Y398329D02*
X1098324Y398619D01*
X1098961Y397983D01*
X1098671Y397198D01*
X1098547Y397074D01*
X1097416Y398206D01*
X1097539Y398329D01*
G37*
G36*
G01X1099445Y396410D02*
X1100116Y396062D01*
X1100119Y395192D01*
X1099449Y394840D01*
X1099274D01*
X1099270Y396409D01*
X1099445Y396410D01*
G37*
G36*
G01X1119763Y404206D02*
X1120433Y403856D01*
Y402986D01*
X1119763Y402636D01*
X1119588D01*
Y404206D01*
X1119763D01*
G37*
G36*
G01Y400306D02*
X1120433Y399956D01*
Y399086D01*
X1119763Y398736D01*
X1119588D01*
Y400306D01*
X1119763D01*
G37*
G36*
G01Y396406D02*
X1120433Y396056D01*
Y395186D01*
X1119763Y394836D01*
X1119588D01*
Y396406D01*
X1119763D01*
G37*
G36*
G01X1140040Y392452D02*
X1140710Y392102D01*
Y391232D01*
X1140040Y390882D01*
X1139865D01*
Y392452D01*
X1140040D01*
G37*
G36*
G01X1140042Y400281D02*
X1140712Y399931D01*
Y399061D01*
X1140042Y398711D01*
X1139867D01*
Y400281D01*
X1140042D01*
G37*
G36*
G01Y396357D02*
X1140712Y396007D01*
Y395137D01*
X1140042Y394787D01*
X1139867D01*
Y396357D01*
X1140042D01*
G37*
G36*
G01X1101494Y406944D02*
X1100734Y407294D01*
Y408194D01*
X1101494Y408544D01*
X1101669D01*
Y406944D01*
X1101494D01*
G37*
G36*
G01X1100710Y409951D02*
X1099925Y409661D01*
X1099289Y410297D01*
X1099579Y411082D01*
X1099702Y411206D01*
X1100834Y410074D01*
X1100710Y409951D01*
G37*
G36*
G01X1098394Y413944D02*
X1097634Y414294D01*
Y415194D01*
X1098394Y415544D01*
X1098569D01*
Y413944D01*
X1098394D01*
G37*
G36*
G01X1103155Y404659D02*
X1103940Y404948D01*
X1104576Y404312D01*
X1104286Y403527D01*
X1104163Y403403D01*
X1103031Y404535D01*
X1103155Y404659D01*
G37*
G36*
G01X1102592Y408544D02*
X1103352Y408194D01*
Y407294D01*
X1102592Y406944D01*
X1102417D01*
Y408544D01*
X1102592D01*
G37*
G36*
G01X1100355Y411859D02*
X1101140Y412148D01*
X1101776Y411512D01*
X1101486Y410727D01*
X1101363Y410603D01*
X1100231Y411735D01*
X1100355Y411859D01*
G37*
G36*
G01X1099492Y415544D02*
X1100252Y415194D01*
Y414294D01*
X1099492Y413944D01*
X1099317D01*
Y415544D01*
X1099492D01*
G37*
G36*
G01X1098433Y404595D02*
X1097673Y404945D01*
Y405845D01*
X1098433Y406195D01*
X1098608D01*
Y404595D01*
X1098433D01*
G37*
G36*
G01X1099531Y406195D02*
X1100291Y405845D01*
Y404945D01*
X1099531Y404595D01*
X1099356D01*
Y406195D01*
X1099531D01*
G37*
G36*
G01X1095622Y412436D02*
X1096407Y412726D01*
X1097043Y412090D01*
X1096753Y411305D01*
X1096630Y411181D01*
X1095498Y412313D01*
X1095622Y412436D01*
G37*
G36*
G01X1111379Y406815D02*
X1110619Y407165D01*
Y408065D01*
X1111379Y408415D01*
X1111554D01*
Y406815D01*
X1111379D01*
G37*
G36*
G01X1110857Y412028D02*
X1110072Y411738D01*
X1109436Y412374D01*
X1109726Y413159D01*
X1109849Y413283D01*
X1110981Y412151D01*
X1110857Y412028D01*
G37*
G36*
G01X1112480Y408415D02*
X1113240Y408065D01*
Y407165D01*
X1112480Y406815D01*
X1112305D01*
Y408415D01*
X1112480D01*
G37*
G36*
G01X1110858Y413584D02*
X1111643Y413874D01*
X1112279Y413238D01*
X1111989Y412453D01*
X1111866Y412329D01*
X1110734Y413461D01*
X1110858Y413584D01*
G37*
G36*
G01X1124898Y404526D02*
X1124228Y404876D01*
Y405746D01*
X1124898Y406096D01*
X1125073D01*
Y404526D01*
X1124898D01*
G37*
G36*
G01Y408426D02*
X1124228Y408776D01*
Y409646D01*
X1124898Y409996D01*
X1125073D01*
Y408426D01*
X1124898D01*
G37*
G36*
G01X1125574Y412755D02*
X1124814Y413105D01*
Y414005D01*
X1125574Y414355D01*
X1125749D01*
Y412755D01*
X1125574D01*
G37*
G36*
G01X1126523Y408117D02*
X1127193Y407767D01*
Y406897D01*
X1126523Y406547D01*
X1126348D01*
Y408117D01*
X1126523D01*
G37*
G36*
G01X1126674Y414355D02*
X1127434Y414005D01*
Y413105D01*
X1126674Y412755D01*
X1126499D01*
Y414355D01*
X1126674D01*
G37*
G36*
G01X1107998Y404557D02*
X1107238Y404907D01*
Y405807D01*
X1107998Y406157D01*
X1108173D01*
Y404557D01*
X1107998D01*
G37*
G36*
G01X1104399Y411561D02*
X1103639Y411911D01*
Y412811D01*
X1104399Y413161D01*
X1104574D01*
Y411561D01*
X1104399D01*
G37*
G36*
G01X1106815Y408122D02*
X1106031Y407832D01*
X1105394Y408469D01*
X1105684Y409253D01*
X1105808Y409377D01*
X1106939Y408246D01*
X1106815Y408122D01*
G37*
G36*
G01X1109099Y406157D02*
X1109859Y405807D01*
Y404907D01*
X1109099Y404557D01*
X1108924D01*
Y406157D01*
X1109099D01*
G37*
G36*
G01X1105499Y413161D02*
X1106259Y412811D01*
Y411911D01*
X1105499Y411561D01*
X1105324D01*
Y413161D01*
X1105499D01*
G37*
G36*
G01X1106461Y410030D02*
X1107245Y410320D01*
X1107882Y409683D01*
X1107592Y408899D01*
X1107468Y408775D01*
X1106337Y409906D01*
X1106461Y410030D01*
G37*
G36*
G01X1121756Y411423D02*
X1120996Y411773D01*
Y412673D01*
X1121756Y413023D01*
X1121931D01*
Y411423D01*
X1121756D01*
G37*
G36*
G01X1121519Y406536D02*
X1120849Y406886D01*
Y407756D01*
X1121519Y408106D01*
X1121694D01*
Y406536D01*
X1121519D01*
G37*
G36*
G01X1121756Y415323D02*
X1120996Y415673D01*
Y416573D01*
X1121756Y416923D01*
X1121931D01*
Y415323D01*
X1121756D01*
G37*
G36*
G01X1123143Y406107D02*
X1123813Y405757D01*
Y404887D01*
X1123143Y404537D01*
X1122968D01*
Y406107D01*
X1123143D01*
G37*
G36*
G01X1122856Y413023D02*
X1123616Y412673D01*
Y411773D01*
X1122856Y411423D01*
X1122681D01*
Y413023D01*
X1122856D01*
G37*
G36*
G01X1123143Y410007D02*
X1123813Y409657D01*
Y408787D01*
X1123143Y408437D01*
X1122968D01*
Y410007D01*
X1123143D01*
G37*
G36*
G01X1122856Y416923D02*
X1123616Y416573D01*
Y415673D01*
X1122856Y415323D01*
X1122681D01*
Y416923D01*
X1122856D01*
G37*
G36*
G01X1143021Y418017D02*
X1142731Y418802D01*
X1143367Y419439D01*
X1144152Y419149D01*
X1144276Y419025D01*
X1143145Y417894D01*
X1143021Y418017D01*
G37*
G36*
G01X1140221Y415217D02*
X1139931Y416002D01*
X1140567Y416639D01*
X1141352Y416349D01*
X1141476Y416225D01*
X1140345Y415094D01*
X1140221Y415217D01*
G37*
G36*
G01X1137463Y412460D02*
X1137173Y413244D01*
X1137810Y413881D01*
X1138594Y413591D01*
X1138718Y413467D01*
X1137587Y412336D01*
X1137463Y412460D01*
G37*
G36*
G01X1134705Y409702D02*
X1134415Y410487D01*
X1135052Y411123D01*
X1135837Y410833D01*
X1135960Y410709D01*
X1134829Y409578D01*
X1134705Y409702D01*
G37*
G36*
G01X1144930Y418371D02*
X1145220Y417586D01*
X1144584Y416949D01*
X1143799Y417239D01*
X1143675Y417363D01*
X1144806Y418494D01*
X1144930Y418371D01*
G37*
G36*
G01X1136615Y410055D02*
X1136905Y409270D01*
X1136268Y408634D01*
X1135483Y408924D01*
X1135360Y409048D01*
X1136491Y410179D01*
X1136615Y410055D01*
G37*
G36*
G01X1139372Y412813D02*
X1139662Y412028D01*
X1139026Y411392D01*
X1138241Y411682D01*
X1138117Y411805D01*
X1139249Y412937D01*
X1139372Y412813D01*
G37*
G36*
G01X1142130Y415571D02*
X1142420Y414786D01*
X1141784Y414149D01*
X1140999Y414439D01*
X1140875Y414563D01*
X1142006Y415694D01*
X1142130Y415571D01*
G37*
G36*
G01X1153794Y405523D02*
X1154144Y406283D01*
X1155044D01*
X1155394Y405523D01*
Y405348D01*
X1153794D01*
Y405523D01*
G37*
G36*
G01X1149894D02*
X1150244Y406283D01*
X1151144D01*
X1151494Y405523D01*
Y405348D01*
X1149894D01*
Y405523D01*
G37*
G36*
G01X1151494Y404423D02*
X1151144Y403663D01*
X1150244D01*
X1149894Y404423D01*
Y404598D01*
X1151494D01*
Y404423D01*
G37*
G36*
G01X1155394D02*
X1155044Y403663D01*
X1154144D01*
X1153794Y404423D01*
Y404598D01*
X1155394D01*
Y404423D01*
G37*
G36*
G01X1128812Y406153D02*
X1128052Y406503D01*
Y407403D01*
X1128813Y407753D01*
X1128987D01*
Y406153D01*
X1128812D01*
G37*
G36*
G01X1131574Y412833D02*
X1131284Y413618D01*
X1131921Y414254D01*
X1132706Y413964D01*
X1132829Y413840D01*
X1131698Y412709D01*
X1131574Y412833D01*
G37*
G36*
G01X1137090Y418348D02*
X1136800Y419133D01*
X1137436Y419770D01*
X1138221Y419480D01*
X1138345Y419356D01*
X1137214Y418225D01*
X1137090Y418348D01*
G37*
G36*
G01X1134332Y415591D02*
X1134042Y416375D01*
X1134679Y417012D01*
X1135463Y416722D01*
X1135587Y416598D01*
X1134456Y415467D01*
X1134332Y415591D01*
G37*
G36*
G01X1129912Y407811D02*
X1130673Y407461D01*
X1130672Y406561D01*
X1129912Y406211D01*
X1129737Y406212D01*
Y407811D01*
X1129912D01*
G37*
G36*
G01X1138999Y418702D02*
X1139289Y417917D01*
X1138653Y417280D01*
X1137868Y417570D01*
X1137744Y417694D01*
X1138875Y418825D01*
X1138999Y418702D01*
G37*
G36*
G01X1136241Y415944D02*
X1136531Y415159D01*
X1135895Y414523D01*
X1135110Y414813D01*
X1134986Y414936D01*
X1136118Y416068D01*
X1136241Y415944D01*
G37*
G36*
G01X1133484Y413186D02*
X1133774Y412401D01*
X1133137Y411765D01*
X1132352Y412055D01*
X1132229Y412179D01*
X1133360Y413310D01*
X1133484Y413186D01*
G37*
G36*
G01X1143822Y405534D02*
X1143532Y406318D01*
X1144169Y406955D01*
X1144953Y406665D01*
X1145077Y406541D01*
X1143946Y405410D01*
X1143822Y405534D01*
G37*
G36*
G01X1155570Y408375D02*
X1155920Y409135D01*
X1156820D01*
X1157170Y408375D01*
Y408200D01*
X1155570D01*
Y408375D01*
G37*
G36*
G01X1151670D02*
X1152020Y409135D01*
X1152920D01*
X1153270Y408375D01*
Y408200D01*
X1151670D01*
Y408375D01*
G37*
G36*
G01X1145732Y405886D02*
X1146022Y405102D01*
X1145385Y404465D01*
X1144601Y404755D01*
X1144477Y404879D01*
X1145608Y406010D01*
X1145732Y405886D01*
G37*
G36*
G01X1157170Y407275D02*
X1156820Y406515D01*
X1155920D01*
X1155570Y407275D01*
Y407450D01*
X1157170D01*
Y407275D01*
G37*
G36*
G01X1153270D02*
X1152920Y406515D01*
X1152020D01*
X1151670Y407275D01*
Y407450D01*
X1153270D01*
Y407275D01*
G37*
G36*
G01X1115578Y410579D02*
X1116338Y410229D01*
Y409329D01*
X1115578Y408979D01*
X1115403D01*
Y410579D01*
X1115578D01*
G37*
G36*
G01X1116382Y406105D02*
X1117052Y405755D01*
Y404885D01*
X1116382Y404535D01*
X1116207D01*
Y406105D01*
X1116382D01*
G37*
G36*
G01X1141860Y410400D02*
X1142150Y409616D01*
X1141513Y408979D01*
X1140729Y409269D01*
X1140605Y409393D01*
X1141736Y410524D01*
X1141860Y410400D01*
G37*
G36*
G01X1139060Y407600D02*
X1139350Y406816D01*
X1138713Y406179D01*
X1137929Y406469D01*
X1137805Y406593D01*
X1138936Y407724D01*
X1139060Y407600D01*
G37*
G36*
G01X1148370Y413075D02*
X1148020Y412315D01*
X1147120D01*
X1146770Y413075D01*
Y413250D01*
X1148370D01*
Y413075D01*
G37*
G36*
G01X1154119Y415822D02*
X1154409Y415037D01*
X1153773Y414401D01*
X1152988Y414691D01*
X1152864Y414814D01*
X1153996Y415946D01*
X1154119Y415822D01*
G37*
G36*
G01X1118139Y404537D02*
X1117469Y404887D01*
Y405757D01*
X1118139Y406107D01*
X1118314D01*
Y404537D01*
X1118139D01*
G37*
G36*
G01Y413918D02*
X1117379Y414268D01*
Y415168D01*
X1118139Y415518D01*
X1118314D01*
Y413918D01*
X1118139D01*
G37*
G36*
G01Y410018D02*
X1117379Y410368D01*
Y411268D01*
X1118139Y411618D01*
X1118314D01*
Y410018D01*
X1118139D01*
G37*
G36*
G01X1143572Y409384D02*
X1143282Y410168D01*
X1143919Y410805D01*
X1144703Y410515D01*
X1144827Y410391D01*
X1143696Y409260D01*
X1143572Y409384D01*
G37*
G36*
G01X1148270Y411251D02*
X1148620Y412011D01*
X1149520D01*
X1149870Y411251D01*
Y411076D01*
X1148270D01*
Y411251D01*
G37*
G36*
G01X1140772Y406584D02*
X1140482Y407368D01*
X1141119Y408005D01*
X1141903Y407715D01*
X1142027Y407591D01*
X1140896Y406460D01*
X1140772Y406584D01*
G37*
G36*
G01X1153385Y412294D02*
X1153095Y413078D01*
X1153732Y413715D01*
X1154516Y413425D01*
X1154640Y413301D01*
X1153509Y412170D01*
X1153385Y412294D01*
G37*
G36*
G01X1114478Y408979D02*
X1113718Y409329D01*
Y410229D01*
X1114478Y410579D01*
X1114653D01*
Y408979D01*
X1114478D01*
G37*
G36*
G01X1139950Y410048D02*
X1139660Y410832D01*
X1140297Y411469D01*
X1141081Y411179D01*
X1141205Y411055D01*
X1140074Y409924D01*
X1139950Y410048D01*
G37*
G36*
G01X1137150Y407248D02*
X1136860Y408032D01*
X1137497Y408669D01*
X1138281Y408379D01*
X1138405Y408255D01*
X1137274Y407124D01*
X1137150Y407248D01*
G37*
G36*
G01X1146770Y414175D02*
X1147120Y414935D01*
X1148020D01*
X1148370Y414175D01*
Y414000D01*
X1146770D01*
Y414175D01*
G37*
G36*
G01X1152210Y415469D02*
X1151920Y416253D01*
X1152557Y416890D01*
X1153341Y416600D01*
X1153465Y416476D01*
X1152334Y415345D01*
X1152210Y415469D01*
G37*
G36*
G01X1119763Y408106D02*
X1120433Y407756D01*
Y406886D01*
X1119763Y406536D01*
X1119588D01*
Y408106D01*
X1119763D01*
G37*
G36*
G01X1119239Y415518D02*
X1119999Y415168D01*
Y414268D01*
X1119239Y413918D01*
X1119064D01*
Y415518D01*
X1119239D01*
G37*
G36*
G01Y411618D02*
X1119999Y411268D01*
Y410368D01*
X1119239Y410018D01*
X1119064D01*
Y411618D01*
X1119239D01*
G37*
G36*
G01X1145481Y409737D02*
X1145771Y408952D01*
X1145135Y408316D01*
X1144350Y408606D01*
X1144226Y408729D01*
X1145358Y409861D01*
X1145481Y409737D01*
G37*
G36*
G01X1149870Y410151D02*
X1149520Y409391D01*
X1148620D01*
X1148270Y410151D01*
Y410326D01*
X1149870D01*
Y410151D01*
G37*
G36*
G01X1142681Y406937D02*
X1142971Y406152D01*
X1142335Y405516D01*
X1141550Y405806D01*
X1141426Y405929D01*
X1142558Y407061D01*
X1142681Y406937D01*
G37*
G36*
G01X1155294Y412647D02*
X1155584Y411862D01*
X1154948Y411226D01*
X1154163Y411516D01*
X1154039Y411639D01*
X1155171Y412771D01*
X1155294Y412647D01*
G37*
G36*
G01X1164183Y409138D02*
X1163893Y409923D01*
X1164529Y410559D01*
X1165314Y410269D01*
X1165438Y410146D01*
X1164306Y409014D01*
X1164183Y409138D01*
G37*
G36*
G01X1167996Y411275D02*
X1168346Y412035D01*
X1169246D01*
X1169596Y411275D01*
Y411100D01*
X1167996D01*
Y411275D01*
G37*
G36*
G01X1157694Y405523D02*
X1158044Y406283D01*
X1158944D01*
X1159294Y405523D01*
Y405348D01*
X1157694D01*
Y405523D01*
G37*
G36*
G01X1161383Y406338D02*
X1161093Y407123D01*
X1161729Y407759D01*
X1162514Y407469D01*
X1162638Y407346D01*
X1161506Y406214D01*
X1161383Y406338D01*
G37*
G36*
G01X1166092Y409491D02*
X1166382Y408706D01*
X1165746Y408070D01*
X1164961Y408360D01*
X1164837Y408483D01*
X1165969Y409615D01*
X1166092Y409491D01*
G37*
G36*
G01X1169777Y410175D02*
X1169427Y409415D01*
X1168527D01*
X1168177Y410175D01*
Y410350D01*
X1169777D01*
Y410175D01*
G37*
G36*
G01X1159294Y404423D02*
X1158944Y403663D01*
X1158044D01*
X1157694Y404423D01*
Y404598D01*
X1159294D01*
Y404423D01*
G37*
G36*
G01X1163292Y406691D02*
X1163582Y405906D01*
X1162946Y405270D01*
X1162161Y405560D01*
X1162037Y405683D01*
X1163169Y406815D01*
X1163292Y406691D01*
G37*
G36*
G01X1160056Y409215D02*
X1159766Y410000D01*
X1160402Y410636D01*
X1161187Y410346D01*
X1161311Y410223D01*
X1160179Y409091D01*
X1160056Y409215D01*
G37*
G36*
G01X1168344Y415575D02*
X1168694Y416335D01*
X1169594D01*
X1169944Y415575D01*
Y415400D01*
X1168344D01*
Y415575D01*
G37*
G36*
G01X1162813Y411973D02*
X1162523Y412758D01*
X1163160Y413394D01*
X1163945Y413104D01*
X1164068Y412980D01*
X1162937Y411849D01*
X1162813Y411973D01*
G37*
G36*
G01X1169944Y414475D02*
X1169594Y413715D01*
X1168694D01*
X1168344Y414475D01*
Y414650D01*
X1169944D01*
Y414475D01*
G37*
G36*
G01X1164765Y412368D02*
X1165055Y411583D01*
X1164419Y410947D01*
X1163634Y411237D01*
X1163510Y411360D01*
X1164642Y412492D01*
X1164765Y412368D01*
G37*
G36*
G01X1161965Y409568D02*
X1162255Y408783D01*
X1161619Y408147D01*
X1160834Y408437D01*
X1160710Y408560D01*
X1161842Y409692D01*
X1161965Y409568D01*
G37*
G36*
G01X1258442Y110900D02*
G03I-642J0D01*
G37*
G36*
G01X1366900Y598900D02*
X1363700Y595700D01*
Y590700D01*
X1366700Y587700D01*
Y568200D01*
X1362150Y563650D01*
Y553050D01*
X1361170Y552070D01*
X1334200D01*
X1330700Y555570D01*
Y567650D01*
X1336100Y573050D01*
Y616600D01*
X1340878Y621378D01*
X1361522D01*
X1366900Y616000D01*
Y598900D01*
G37*
G36*
G01X1438242Y-21821D02*
X1435915Y-19494D01*
Y-6539D01*
X1435573Y-3666D01*
X1434478Y-552D01*
X1433075Y1860D01*
X1430694Y4132D01*
X1430358Y4545D01*
X1430284Y4622D01*
X1428046Y6411D01*
X1425326Y7660D01*
X1421921Y8669D01*
X1418626Y8674D01*
X1412402D01*
G02X1412002Y9080I0J400D01*
G03X1409211Y9292I-1402J21D01*
G01X1409202Y9226D01*
X1408650Y8674D01*
X1407991D01*
X1406493Y10172D01*
X1406482Y10235D01*
G03X1405335Y11382I-1382J-235D01*
G01X1405272Y11393D01*
X1404328Y12337D01*
X1400306D01*
X1399300Y13343D01*
Y19388D01*
X1400112Y20200D01*
X1400532D01*
X1400556Y20194D01*
G03X1402476I960J3782D01*
G01X1402500Y20200D01*
X1455900D01*
X1462343Y13757D01*
G02X1462060Y13074I-283J-283D01*
G01X1460237D01*
G03X1459744Y12992I-2J-1511D01*
G02X1459214Y13391I-131J378D01*
G03X1458218Y12124I-1400J75D01*
G02X1458732Y11703I116J-383D01*
G03X1460237Y10052I1505J-140D01*
G01X1465237D01*
G03X1465780Y10152I2J1511D01*
G01X1465901Y10199D01*
X1466300Y9800D01*
Y-5000D01*
X1472000Y-10700D01*
X1495116D01*
X1495165Y-10828D01*
G03X1498155I1495J576D01*
G01X1498204Y-10700D01*
X1500600D01*
X1501050Y-10250D01*
X1501184Y-10329D01*
G03X1503301Y-9183I716J1205D01*
G02X1503700Y-8800I400J-17D01*
G01X1550400D01*
X1551500Y-9900D01*
Y-13794D01*
G03Y-16206I3500J-1206D01*
G01Y-19800D01*
X1549550Y-21750D01*
X1492850D01*
X1492779Y-21821D01*
X1438242D01*
G37*
G36*
G01X1369803Y99600D02*
G03X1367675Y101653I-5103J-3160D01*
G02X1367874Y102400I199J347D01*
G01X1372100D01*
X1372600Y101900D01*
Y100200D01*
X1372000Y99600D01*
X1369803D01*
G37*
G36*
G01X1350400D02*
X1346500Y103500D01*
X1344600D01*
X1343900Y104200D01*
Y104800D01*
X1344600Y105500D01*
X1348900D01*
X1352000Y102400D01*
X1361526D01*
G02X1361725Y101653I0J-400D01*
G03X1359597Y99600I2975J-5213D01*
G01X1350400D01*
G37*
G36*
G01X1371300Y568500D02*
X1373700Y570900D01*
X1382400D01*
X1385193Y568107D01*
Y557504D01*
X1383781Y556092D01*
X1372618D01*
X1371300Y557410D01*
Y568500D01*
G37*
G36*
G01X1443600Y396957D02*
X1443609Y397000D01*
X1449360D01*
X1449400Y396810D01*
Y379000D01*
X1443600D01*
Y396957D01*
G37*
G36*
G01X1447400Y417100D02*
Y429900D01*
X1438000D01*
X1436900Y428800D01*
Y417100D01*
X1447400D01*
G37*
G36*
G01X1440484Y540497D02*
G03I-623J0D01*
G37*
G36*
G01X1528614Y406539D02*
G02X1528921Y405857I24J-399D01*
G01X1528318Y405254D01*
G02X1527709Y405304I-283J282D01*
G03X1525992Y405851I-1185J-750D01*
G03X1525138Y404761I533J-1297D01*
G01X1525113Y404591D01*
X1524727D01*
X1524001Y405317D01*
Y412088D01*
X1523910Y412179D01*
X1524162Y412431D01*
X1524265Y412377D01*
G03X1525975Y412643I685J1223D01*
G03X1526197Y412959I-1025J956D01*
G02X1526896Y412981I356J-183D01*
G03X1527095Y412723I1202J721D01*
G03X1527433Y412467I1006J977D01*
G02Y411783I-208J-342D01*
G03X1526767Y410116I667J-1233D01*
G03X1527302Y409397I1333J433D01*
G02X1527398Y408831I-227J-330D01*
G03X1528614Y406539I1077J-897D01*
G37*
G36*
G01X1529762Y406697D02*
X1529499Y406961D01*
X1529589Y407083D01*
G03X1529872Y408053I-1114J851D01*
G03X1529273Y409087I-1397J-119D01*
G02X1529177Y409653I227J330D01*
G03X1528767Y411783I-1077J897D01*
G02Y412467I208J342D01*
G03X1529227Y414534I-667J1233D01*
G03X1527938Y415093I-1127J-834D01*
G03X1526714Y413909I162J-1393D01*
G02X1526320Y413896I-198J29D01*
G03X1526269Y414075I-1371J-294D01*
G03X1526189Y414257I-1320J-472D01*
G01X1526120Y414388D01*
X1526320Y414588D01*
Y416245D01*
X1526330Y416304D01*
X1526334Y416318D01*
G03X1526395Y416614I-1334J429D01*
G03X1526330Y417193I-1395J137D01*
G01X1526320Y417224D01*
Y417689D01*
X1527440Y418809D01*
Y432671D01*
X1529567Y434798D01*
G02X1530161Y434767I283J-283D01*
G03X1530168Y434758I1110J856D01*
G03X1532483Y434983I1082J892D01*
G02X1533167I342J-208D01*
G03X1535633I1233J667D01*
G02X1536317I342J-208D01*
G03X1538783I1233J667D01*
G02X1539467I342J-208D01*
G03X1541925Y434969I1233J667D01*
G02X1542625I350J-194D01*
G03X1545075I1225J681D01*
G02X1545775I350J-194D01*
G03Y436331I1225J681D01*
G02X1545075I-350J194D01*
G03X1544146Y437020I-1225J-681D01*
G02X1544159Y437414I42J196D01*
G03X1544366Y437461I-206J1387D01*
G03X1545040Y439681I-416J1339D01*
G03X1544591Y440047I-1091J-880D01*
G02X1544569Y440746I183J356D01*
G03X1544757Y443019I-719J1204D01*
G03X1542617Y442617I-907J-1069D01*
G02X1541933I-342J208D01*
G03X1541729Y442902I-1233J-667D01*
G01Y444148D01*
G03Y446052I-1029J952D01*
G01Y447298D01*
G03Y449202I-1029J952D01*
G01Y450448D01*
G03Y452352I-1029J952D01*
G01Y452990D01*
X1542808Y454069D01*
X1547887D01*
X1548575Y453381D01*
X1548589Y453331D01*
G03X1549555Y452365I1349J383D01*
G01X1549605Y452351D01*
X1550778Y451178D01*
G03X1550628Y449665I1097J-873D01*
G01X1550639Y449645D01*
X1550661Y449554D01*
X1550605Y449416D01*
X1550582Y449391D01*
G03X1550413Y448898I506J-449D01*
G03X1550076Y448524I298J-608D01*
G01X1550057Y448471D01*
X1549877Y448328D01*
X1549816Y448324D01*
G03X1548966Y445903I109J-1398D01*
G03X1551327Y446911I959J1023D01*
G02X1551744Y447306I400J-5D01*
G03X1553376Y447705I131J3000D01*
G02X1554274I449J-779D01*
G02X1554724Y446959I-449J-779D01*
G01Y446816D01*
G03X1554953Y445771I3001J110D01*
G03X1555193Y445311I2772J1154D01*
G02X1555060Y444752I-337J-215D01*
G03X1556461Y442323I715J-1206D01*
G02X1557011Y442159I195J-349D01*
G03X1557143Y441931I2663J1389D01*
G02X1557010Y441372I-337J-215D01*
G03X1556885Y441288I718J-1204D01*
G03Y439044I840J-1122D01*
G03X1557010Y438960I843J1120D01*
G02X1557156Y438422I-204J-344D01*
G03X1557001Y438155I2519J-1641D01*
G02X1556471Y438003I-345J202D01*
G03X1555183Y438057I-696J-1217D01*
G03X1555767Y435384I592J-1271D01*
G02X1556165Y434984I-2J-400D01*
G01Y431994D01*
X1553404Y429233D01*
G02X1552844Y429227I-283J283D01*
G03X1550629Y427572I-969J-1013D01*
G03X1551346Y426916I1246J642D01*
G01X1551470Y426865D01*
Y426176D01*
G02X1550825Y425860I-400J0D01*
G03X1548629Y425181I-861J-1107D01*
G02X1548139Y424918I-381J122D01*
G03X1546720Y422624I-384J-1348D01*
G02Y422084I-295J-270D01*
G03X1548772Y420173I1035J-946D01*
G02X1549462Y419898I290J-275D01*
G01Y418927D01*
X1550302Y418088D01*
Y416296D01*
X1549630Y415624D01*
Y413764D01*
X1551580Y411814D01*
Y410384D01*
X1551956Y410008D01*
G02X1551718Y409327I-283J-283D01*
G03X1550482Y407773I157J-1393D01*
G02X1550424Y407515I-397J-46D01*
G03X1548810Y407342I-499J-2961D01*
G01X1548774Y407328D01*
X1547176D01*
X1547140Y407342D01*
G03X1544910I-1115J-2788D01*
G01X1544874Y407328D01*
X1543276D01*
X1543240Y407342D01*
G03X1541010I-1115J-2788D01*
G01X1540974Y407328D01*
X1539376D01*
X1539340Y407342D01*
G03X1537075Y407328I-1115J-2788D01*
G01X1530392D01*
X1530112Y407047D01*
X1529762Y406697D01*
G37*
G36*
G01X1506228Y516131D02*
G03I-500J0D01*
G37*
G36*
G01X1477282Y507294D02*
G03I-500J0D01*
G37*
G36*
G01X1497749Y505317D02*
G03I-500J0D01*
G37*
G36*
G01X1506560Y508180D02*
G03I-500J0D01*
G37*
G36*
G01X1502093Y505345D02*
G03I-500J0D01*
G37*
G36*
G01X1491431Y507104D02*
G03I-500J0D01*
G37*
G36*
G01X1494543Y522797D02*
G03I-500J0D01*
G37*
G36*
G01X1488934Y517796D02*
G03I-500J0D01*
G37*
G36*
G01X1511715Y507781D02*
G03I-500J0D01*
G37*
G36*
G01X1512895Y519029D02*
G03I-500J0D01*
G37*
G36*
G01X1484306Y509928D02*
G03I-500J0D01*
G37*
G36*
G01X1532005Y510804D02*
G03I-500J0D01*
G37*
G36*
G01X1542979Y504418D02*
G03I-500J0D01*
G37*
G36*
G01X1534547Y502895D02*
G03I-500J0D01*
G37*
G36*
G01X1542882Y512188D02*
G03I-500J0D01*
G37*
G36*
G01X1555993Y504662D02*
G03I-500J0D01*
G37*
G36*
G01X1548831Y506629D02*
G03I-500J0D01*
G37*
G36*
G01X1556322Y512305D02*
G03I-500J0D01*
G37*
G36*
G01X1649900Y123200D02*
X1649200Y123900D01*
Y130100D01*
X1647400Y131900D01*
Y139600D01*
X1649200Y141400D01*
Y144300D01*
X1650600Y145700D01*
X1650981D01*
X1651017Y145686D01*
G03X1652055I519J1302D01*
G01X1652091Y145700D01*
X1652400D01*
X1653300Y144800D01*
Y144055D01*
X1653298Y144041D01*
G03Y143633I1387J-204D01*
G01X1653300Y143619D01*
Y143329D01*
X1653267Y143279D01*
G03X1652508Y140740I3867J-2539D01*
G03X1653235Y139086I2245J0D01*
G01X1653300Y139027D01*
Y138707D01*
G02X1652596Y138447I-400J0D01*
G03Y136621I-1064J-913D01*
G02X1653300Y136361I304J-260D01*
G01Y134601D01*
X1653298Y134587D01*
G03Y134191I1388J-198D01*
G01X1653300Y134177D01*
Y131457D01*
X1653298Y131443D01*
G03Y131035I1387J-204D01*
G01X1653300Y131021D01*
Y129900D01*
X1653900Y129300D01*
Y126200D01*
X1653300Y125600D01*
Y125152D01*
X1653298Y125138D01*
G03Y124742I1388J-198D01*
G01X1653300Y124728D01*
Y124300D01*
X1652200Y123200D01*
X1649900D01*
G37*
G36*
G01X1643148Y116407D02*
G03X1641856Y116877I-1064J-913D01*
G02X1641421Y117119I-65J395D01*
G03X1641289Y117288I-370J-153D01*
G02X1640837Y117853I832J1129D01*
G03X1640600Y118071I-366J-160D01*
G02X1640332Y118492I130J378D01*
G03X1637712Y119322I-1394J149D01*
G02X1637013I-350J194D01*
G03X1634563I-1225J-682D01*
G02X1633864I-350J194D01*
G03X1631414Y119321I-1225J-682D01*
G02X1630714I-350J194D01*
G03X1628266Y119325I-1225J-681D01*
G02X1627567Y119328I-349J196D01*
G03X1627054Y119857I-1228J-677D01*
G02X1627060Y120548I204J344D01*
G03X1627018Y123005I-696J1217D01*
G02X1627012Y123710I186J354D01*
G03X1625114Y125622I-673J1230D01*
G02X1624415I-349J194D01*
G03X1623872Y126165I-1225J-682D01*
G02Y126864I194J349D01*
G03X1621965Y128770I-682J1225D01*
G02X1621265I-350J194D01*
G03X1618815Y128771I-1225J-681D01*
G02X1618116I-350J194D01*
G03X1615666Y128770I-1225J-682D01*
G02X1614966I-350J194D01*
G03X1614889Y128894I-1228J-677D01*
G01Y133584D01*
G03X1614966Y133708I-1151J801D01*
G02X1615666I350J-194D01*
G03X1618116Y133707I1225J681D01*
G02X1618815I350J-195D01*
G03X1621265I1225J681D01*
G02X1621965I350J-194D01*
G03Y135069I1225J681D01*
G02X1621265I-350J194D01*
G03X1618815Y135070I-1225J-681D01*
G02X1618116I-350J195D01*
G03X1615666I-1225J-681D01*
G02X1614966I-350J194D01*
G03X1614889Y135194I-1228J-677D01*
G01Y136733D01*
G03Y138343I-1148J805D01*
G01Y139883D01*
G03X1614987Y140046I-1150J802D01*
G02X1615687Y140067I356J-183D01*
G03X1617612Y141986I1206J715D01*
G02X1617614Y142673I205J343D01*
G03X1617607Y145091I-714J1207D01*
G02X1617605Y145780I202J345D01*
G03X1617572Y148212I-714J1207D01*
G02Y148912I194J350D01*
G03X1618235Y150537I-681J1226D01*
G02X1618618Y151050I383J113D01*
G01X1620983D01*
X1621985Y152053D01*
G02X1622260Y152060I141J-142D01*
G03X1623183Y154502I940J1040D01*
G02X1622981Y154702I-2J200D01*
G01Y156101D01*
X1624030Y157150D01*
X1640219D01*
X1646337Y151032D01*
X1646690D01*
G02X1647076Y150528I0J-400D01*
G03X1649784I1354J-365D01*
G02X1650170Y151032I386J104D01*
G01X1650638D01*
X1650914Y150756D01*
Y148714D01*
X1648087Y145887D01*
Y142587D01*
X1645800Y140300D01*
Y131587D01*
X1648087Y129300D01*
Y118113D01*
X1646381Y116407D01*
X1646298D01*
G03X1644176I-1061J-916D01*
G01X1643148D01*
G37*
G36*
G01X1596996Y396510D02*
X1609448D01*
G03X1609596Y396487I289J1372D01*
G01Y386641D01*
X1596996D01*
Y396510D01*
G37*
G36*
G01X1622529Y554814D02*
G03I-500J0D01*
G37*
G36*
G01X1624793Y561747D02*
G03I-500J0D01*
G37*
G36*
G01X1615525Y584226D02*
G03I-500J0D01*
G37*
G36*
G01X1610304Y556639D02*
G03I-500J0D01*
G37*
G36*
G01X1602554Y565752D02*
G03I-500J0D01*
G37*
G36*
G01X1603655Y578077D02*
G03I-500J0D01*
G37*
G36*
G01X1599636Y572815D02*
G03I-500J0D01*
G37*
G36*
G01X1603628Y583041D02*
G03I-500J0D01*
G37*
G36*
G01X1616420Y605625D02*
G03I-500J0D01*
G37*
G36*
G01X1615258Y597118D02*
G03I-500J0D01*
G37*
G36*
G01X1614232Y592306D02*
G03I-500J0D01*
G37*
G36*
G01X1602658Y610859D02*
G03I-500J0D01*
G37*
G36*
G01X1601759Y597094D02*
G03I-500J0D01*
G37*
G36*
G01X1601929Y602750D02*
G03I-500J0D01*
G37*
G36*
G01X1696158Y486945D02*
G03I-500J0D01*
G37*
G36*
G01X1658958Y548404D02*
G03I-500J0D01*
G37*
G36*
G01X1664599Y548380D02*
G03I-500J0D01*
G37*
G36*
G01X1680496Y547904D02*
G03I-500J0D01*
G37*
G36*
G01X1686525Y548238D02*
G03I-500J0D01*
G37*
G36*
G01X1708629Y547525D02*
G03I-500J0D01*
G37*
G36*
G01X1698328Y545746D02*
G03I-500J0D01*
G37*
G36*
G01X1677760Y550231D02*
G03I-500J0D01*
G37*
G36*
G01X1669610Y547910D02*
G03I-500J0D01*
G37*
G36*
G01X1736458Y94000D02*
X1735009Y95450D01*
X1716331D01*
X1714000Y97780D01*
Y99800D01*
X1714700Y100500D01*
X1722589D01*
G03X1722633Y100475I714J1206D01*
G02Y99775I-194J-350D01*
G03X1723995I681J-1225D01*
G02Y100475I194J350D01*
G03X1724039Y100500I-670J1231D01*
G01X1725732D01*
X1725768Y100485D01*
G03X1726820I526J1300D01*
G01X1726856Y100500D01*
X1727500D01*
X1732500Y105500D01*
Y109662D01*
X1737024Y114186D01*
G02X1737696Y113991I282J-283D01*
G03X1740341Y114879I1368J310D01*
G02X1740705Y115444I364J165D01*
G01X1742341D01*
X1744318Y117421D01*
Y118918D01*
G02X1744861Y119291I400J0D01*
G03Y121909I503J1309D01*
G02X1744318Y122282I-143J373D01*
G01Y124116D01*
X1745232Y125030D01*
Y133063D01*
G02X1745756Y133444I400J1D01*
G03Y136110I433J1333D01*
G02X1745232Y136491I-124J380D01*
G01Y140714D01*
X1744339Y141607D01*
Y142939D01*
X1745907Y144507D01*
X1745940Y144522D01*
G03X1746642Y145224I-576J1278D01*
G01X1746657Y145257D01*
X1747100Y145700D01*
Y152184D01*
G03Y154316I-911J1066D01*
G01Y158790D01*
X1747121Y158832D01*
G03Y160268I-1432J718D01*
G01X1747100Y160310D01*
Y164250D01*
X1750740Y167890D01*
X1783893D01*
X1783922Y167724D01*
G03X1787078I1578J276D01*
G01X1787107Y167890D01*
X1806314D01*
G03X1806662Y167630I1124J1142D01*
G02Y166930I-194J-350D01*
G03Y164130I778J-1400D01*
G02Y163430I-194J-350D01*
G03X1808218I778J-1400D01*
G02Y164130I194J350D01*
G03Y166930I-778J1400D01*
G02Y167630I194J350D01*
G03X1808566Y167890I-776J1402D01*
G01X1826510D01*
X1827111Y167289D01*
G02X1827125Y166739I-283J-282D01*
G03X1829529Y164335I1265J-1139D01*
G02X1830079Y164321I268J-297D01*
G01X1840129Y154271D01*
G02X1839811Y153590I-283J-283D01*
G03X1838078Y151793I-144J-1596D01*
G02X1837563Y151361I-397J-50D01*
G03X1837432Y151395I-468J-1532D01*
G02X1837266Y152098I85J391D01*
G03X1834904Y154528I-1066J1327D01*
G02X1834296I-304J259D01*
G03Y152320I-1296J-1104D01*
G02X1834904I304J-259D01*
G03X1835876Y151753I1295J1104D01*
G02X1836057Y151055I-77J-392D01*
G03X1838357Y148850I1033J-1225D01*
G01X1845550D01*
X1846900Y147500D01*
X1847000Y147600D01*
X1851500D01*
X1858800Y140300D01*
Y137850D01*
X1857980Y137030D01*
X1856712D01*
X1856636Y136954D01*
X1854897Y135215D01*
X1854824Y135209D01*
G03X1853366Y133751I138J-1596D01*
G01X1853360Y133678D01*
X1851231Y131550D01*
X1846544D01*
X1845725Y132370D01*
X1844822D01*
G03X1844790Y132369I5J-678D01*
G01X1844785Y132368D01*
X1822493D01*
X1821675Y131550D01*
X1819882D01*
G02X1819582Y132215I0J400D01*
G03X1817272Y134431I-1199J1062D01*
G02X1816994I-139J144D01*
G03X1814684Y132215I-1111J-1154D01*
G02X1814384Y131550I-300J-265D01*
G01X1805350D01*
X1803865Y130065D01*
X1803764Y130082D01*
G03X1802500Y127256I-255J-1582D01*
G01Y125638D01*
X1802392Y125531D01*
Y124293D01*
G02X1801753Y123973I-400J0D01*
G03X1799990Y121304I-960J-1283D01*
G02X1800073Y120675I-200J-346D01*
G01X1791826Y112428D01*
X1788586D01*
X1787158Y111000D01*
X1772252D01*
X1767052Y116200D01*
Y119379D01*
X1765936Y120495D01*
X1765804D01*
X1765760Y120518D01*
G03X1763531Y119703I-745J-1418D01*
G01X1763516Y119666D01*
X1763433Y119583D01*
G02X1762780Y119713I-283J282D01*
G03X1760020Y120063I-1480J-613D01*
G02X1759380I-320J240D01*
G03Y118137I-1280J-963D01*
G02X1760020I320J-240D01*
G03X1762353Y117893I1280J963D01*
G02X1763016Y117591I263J-301D01*
G01Y110593D01*
X1751500Y99077D01*
Y99000D01*
X1748828Y96328D01*
X1747718D01*
G03X1745481Y94677I-1227J-678D01*
G02X1745193Y94000I-288J-277D01*
G01X1736458D01*
G37*
G36*
G01X1734519Y488136D02*
G03I-500J0D01*
G37*
G36*
G01X1743479Y484966D02*
G03I-500J0D01*
G37*
G36*
G01X1749129Y485026D02*
G03I-500J0D01*
G37*
G36*
G01X1755539Y484996D02*
G03I-500J0D01*
G37*
G36*
G01X1761469Y472826D02*
G03I-500J0D01*
G37*
G36*
G01X1765859Y490366D02*
G03I-500J0D01*
G37*
G36*
G01X1770769Y490236D02*
G03I-500J0D01*
G37*
G36*
G01X1774029Y472096D02*
G03I-500J0D01*
G37*
G36*
G01X1767789Y472746D02*
G03I-500J0D01*
G37*
G36*
G01X1740889Y496287D02*
G03I-500J0D01*
G37*
G36*
G01X1729200Y502600D02*
G03I-500J0D01*
G37*
G36*
G01X1734330Y502650D02*
G03I-500J0D01*
G37*
G36*
G01X1752300Y494029D02*
G03I-500J0D01*
G37*
G36*
G01X1749828Y493953D02*
G03I-500J0D01*
G37*
G36*
G01X1759001Y493786D02*
G03I-500J0D01*
G37*
G36*
G01X1785028Y491901D02*
G03I-500J0D01*
G37*
G36*
G01X1780159Y472126D02*
G03I-500J0D01*
G37*
G36*
G01X1796682Y491852D02*
G03I-500J0D01*
G37*
G36*
G01X1790078Y491901D02*
G03I-500J0D01*
G37*
G36*
G01X1795659Y476436D02*
G03I-500J0D01*
G37*
G36*
G01X1790239Y476376D02*
G03I-500J0D01*
G37*
G36*
G01X1801999Y471036D02*
G03I-500J0D01*
G37*
G36*
G01X1807559Y491610D02*
G03I-500J0D01*
G37*
G36*
G01X1812609Y491658D02*
G03I-500J0D01*
G37*
G36*
G01X1812755Y481383D02*
G03I-500J0D01*
G37*
G36*
G01X1807219Y471206D02*
G03I-500J0D01*
G37*
G36*
G01X1817853Y481334D02*
G03I-500J0D01*
G37*
G36*
G01X1824603Y491852D02*
G03I-500J0D01*
G37*
G36*
G01X1819602Y491804D02*
G03I-500J0D01*
G37*
G36*
G01X1801732Y491950D02*
G03I-500J0D01*
G37*
G36*
G01X1787339Y552526D02*
G03I-500J0D01*
G37*
G36*
G01X1810922Y571479D02*
G03I-500J0D01*
G37*
G36*
G01X1810920Y568865D02*
G03I-500J0D01*
G37*
G36*
G01X1872406Y112390D02*
X1887134D01*
X1890755Y116011D01*
Y120491D01*
X1891737Y121473D01*
X1899253D01*
X1900145Y120581D01*
Y111845D01*
X1899778Y111478D01*
X1895328D01*
X1894650Y110800D01*
X1894200D01*
X1890080Y106680D01*
X1890073Y106674D01*
G03X1889900Y106501I901J-1074D01*
G01X1889894Y106494D01*
X1889400Y106000D01*
Y103400D01*
X1889300Y103300D01*
G02X1888754Y103282I-283J283D01*
G03X1886467Y102555I-924J-1055D01*
G02X1885861Y102313I-389J94D01*
G03X1883829Y101722I-759J-1179D01*
G01X1873978D01*
X1872953Y102747D01*
G02X1872929Y103287I283J283D01*
G03X1871362Y105500I-1074J901D01*
G02X1870822Y105875I-140J375D01*
G01Y110806D01*
X1872406Y112390D01*
G37*
G36*
G01X1861700Y157700D02*
Y170500D01*
X1868880D01*
G03X1869020I70J1400D01*
G01X1872100D01*
Y157700D01*
X1861700D01*
G37*
G36*
G01X1879300Y446000D02*
X1878300Y447000D01*
Y448804D01*
X1878450Y448842D01*
G03X1878859Y451379I-350J1358D01*
G02X1878792Y451998I216J337D01*
G01X1888494Y461700D01*
X1899240D01*
X1900890Y460050D01*
Y455646D01*
G03X1900349Y455104I684J-1224D01*
G02X1899650I-350J194D01*
G03X1897200Y455103I-1225J-682D01*
G02X1896500I-350J194D01*
G03Y453741I-1225J-681D01*
G02X1897200I350J-194D01*
G03X1899650Y453740I1225J681D01*
G02X1900349I349J-194D01*
G03X1900890Y453198I1225J682D01*
G01Y449779D01*
X1900490Y449379D01*
X1897860D01*
X1897015Y448534D01*
Y447326D01*
X1897640Y446701D01*
Y446179D01*
X1897461Y446000D01*
X1879300D01*
G37*
G36*
G01X1929774Y67309D02*
X1928490Y68593D01*
Y79900D01*
X1930734Y82144D01*
X1947316D01*
G02X1947572Y81437I0J-400D01*
G03X1949372I900J-1075D01*
G02X1949628Y82144I256J307D01*
G01X1954344D01*
X1955565Y80923D01*
Y80123D01*
X1950060Y74618D01*
X1949921Y74723D01*
G03X1947788Y72346I-970J-1275D01*
G01X1942751Y67309D01*
X1929774D01*
G37*
%LPC*%
G75*
G36*
G01X783207Y-57200D02*
X481500D01*
Y-37300D01*
X746700D01*
Y-37400D01*
X783207D01*
Y-57200D01*
G37*
G36*
G01X397000Y-39100D02*
X450380D01*
Y-57500D01*
X394400D01*
Y-57530D01*
X56000D01*
Y-37300D01*
X145500D01*
Y-39050D01*
X397000D01*
Y-39100D01*
G37*
G36*
G01X813500Y-37100D02*
X1115285D01*
Y-57100D01*
X813500D01*
Y-37100D01*
G37*
G36*
G01X4973Y301570D02*
G02Y303124I-1167J777D01*
G03X5639I333J222D01*
G02Y301570I1167J-777D01*
G03X4973I-333J-222D01*
G37*
G36*
G01X240600Y659600D02*
X399300D01*
Y640000D01*
X240600D01*
Y659600D01*
G37*
G36*
G01X931400D02*
X1216800D01*
Y639900D01*
X931400D01*
Y659600D01*
G37*
G36*
G01X34016Y453011D02*
G03X33427Y453045I-310J-253D01*
G02X33534Y454939I-977J1005D01*
G03X34123Y454905I310J253D01*
G02X34016Y453011I977J-1005D01*
G37*
G36*
G01X28987Y589962D02*
G03X28729Y589961I-128J-153D01*
G02X28720Y592864I-1234J1448D01*
G03X28978Y592865I128J153D01*
G02X31336Y592951I1233J-1448D01*
G02X33799Y593022I1273J-1413D01*
G02X33895Y590137I1286J-1401D01*
G02X31485Y590004I-1286J1401D01*
G02X28987Y589962I-1273J1413D01*
G37*
G36*
G01X47796Y579554D02*
G03Y578946I260J-304D01*
G02X45324I-1236J-1446D01*
G03Y579554I-260J304D01*
G02X47796I1236J1446D01*
G37*
G36*
G01X15150Y573407D02*
G02X15110Y577179I650J1893D01*
G02Y577621I1990J221D01*
G02X14691Y581167I690J1879D01*
G03Y581833I-221J333D01*
G02X14987Y585330I1109J1667D01*
G01X15106Y585382D01*
Y585514D01*
G02X15127Y585804I2002J1D01*
G02X15139Y589600I643J1896D01*
G02X17770Y587783I2000J83D01*
G02X17751Y587409I-2000J-86D01*
G02X18216Y583846I-643J-1896D01*
G03X18224Y583174I221J-333D01*
G02X17800Y579585I-1068J-1693D01*
G02X17790Y579279I-2000J-88D01*
G02Y575521I-690J-1879D01*
G02X17789Y575076I-1990J-218D01*
G02X18703Y571933I-650J-1893D01*
G02X15575I-1564J-1250D01*
G02X15150Y573407I1564J1249D01*
G37*
G36*
G01X20698Y565266D02*
G02Y568134I-1250J1434D01*
G02X23215Y568119I1250J-1434D01*
G03X23481I133J149D01*
G02Y565281I1267J-1419D01*
G03X23215I-133J-149D01*
G02X20698Y565266I-1267J1419D01*
G37*
G36*
G01X28381Y558982D02*
G03X28647I133J149D01*
G02X31315Y558849I1267J-1419D01*
G03X31920Y558868I294J271D01*
G02X34646Y559102I1476J-1200D01*
G02X37163Y559087I1250J-1434D01*
G03X37429I133J149D01*
G02Y556249I1267J-1419D01*
G03X37163I-133J-149D01*
G02X34646Y556234I-1267J1419D01*
G02X31995Y556382I-1250J1434D01*
G03X31390Y556363I-294J-271D01*
G02X28647Y556144I-1476J1200D01*
G03X28381I-133J-149D01*
G02Y558982I-1267J1419D01*
G37*
G36*
G01X47282Y556535D02*
G03Y555995I295J-270D01*
G02X44478I-1402J-1285D01*
G03Y556535I-295J270D01*
G02X47282I1402J1285D01*
G37*
G36*
G01X43566Y534091D02*
G03X43400Y533885I34J-197D01*
G02X41175Y535674I-1900J-85D01*
G03X41341Y535880I-34J197D01*
G02X41933Y537346I1900J85D01*
G03X41958Y537607I-138J145D01*
G02X44210Y540481I1547J1107D01*
G03X44713Y540668I148J371D01*
G02X47636Y538344I1687J-878D01*
G03Y537736I260J-304D01*
G02X45236Y534786I-1235J-1446D01*
G03X44687Y534729I-245J-316D01*
G02X43566Y534091I-1446J1236D01*
G37*
G36*
G01X28200Y530824D02*
G02Y533776I-1200J1476D01*
G02Y530824I1200J-1476D01*
G37*
G36*
G01X45419Y525634D02*
G03X45563Y526142I-217J336D01*
G02X49355Y526752I1806J863D01*
G03X49760Y526302I397J-50D01*
G02X48580Y522713I40J-2002D01*
G03X48031Y522655I-244J-317D01*
G02X45419Y525634I-1524J1298D01*
G37*
G36*
G01X38219Y521278D02*
G03X37933Y521799I-378J132D01*
G02X40008Y524925I456J1949D01*
G03X40609Y524871I324J235D01*
G02X42391Y521463I1384J-1446D01*
G03X42078Y520996I80J-392D01*
G02X38219Y521278I-1967J-373D01*
G37*
G36*
G01X39597Y507538D02*
G02X35628Y507055I-1997J-137D01*
G02X33705Y509088I79J2000D01*
G02X33295Y509269I598J1910D01*
G02X32805Y512331I-1495J1331D01*
G02X35541Y512571I1495J-1331D01*
G02X38981Y511490I1459J-1371D01*
G02X39597Y507538I218J-1990D01*
G37*
G36*
G01X45515Y505748D02*
G03X46098Y505745I293J272D01*
G02X46085Y503002I1452J-1378D01*
G03X45502Y503005I-293J-272D01*
G02X45515Y505748I-1452J1378D01*
G37*
G36*
G01X58175Y255329D02*
G02X56785Y255306I-675J-1229D01*
G03X56753Y256011I-204J344D01*
G02X58183Y256034I692J1445D01*
G03X58175Y255329I184J-355D01*
G37*
G36*
G01X193499Y359219D02*
G03X192922Y359213I-286J-280D01*
G02X192901Y361154I-1022J960D01*
G03X193478Y361160I286J280D01*
G02X195472Y361211I1022J-960D01*
G03X196057Y361244I277J288D01*
G02X196165Y359339I1080J-894D01*
G03X195580Y359306I-277J-288D01*
G02X193499Y359219I-1080J894D01*
G37*
G36*
G01X193564Y331470D02*
G03X193010I-277J-288D01*
G02Y333490I-973J1010D01*
G03X193564I277J288D01*
G02X195510I973J-1010D01*
G03X196064I277J288D01*
G02Y331470I973J-1010D01*
G03X195510I-277J-288D01*
G02X193564I-973J1010D01*
G37*
G36*
G01X376998Y330627D02*
G03X377585Y330641I287J279D01*
G02X379464Y328129I1200J-1061D01*
G03X379286Y327569I170J-362D01*
G02X376816Y325592I-1392J-792D01*
G03X376282Y325596I-269J-296D01*
G02X374111Y325645I-1059J1202D01*
G03X373545Y325635I-278J-288D01*
G02X371263Y325609I-1154J1111D01*
G03X370735Y325640I-282J-284D01*
G02X368626Y325759I-987J1262D01*
G03X368101Y325790I-280J-286D01*
G02X368083Y325776I-992J1257D01*
G03X368050Y325488I120J-160D01*
G02X365736Y325637I-1228J-1029D01*
G03X365796Y326156I-271J294D01*
G02X368243Y328200I1325J901D01*
G03X368768Y328169I280J286D01*
G02X370876Y328039I980J-1267D01*
G03X371404Y328008I282J284D01*
G02X373503Y327899I987J-1262D01*
G03X374069Y327909I278J288D01*
G02X374351Y328142I1155J-1110D01*
G03X374476Y328684I-217J336D01*
G02X376998Y330627I1371J828D01*
G37*
G36*
G01X434694Y323112D02*
G03X434094I-300J-265D01*
G02Y325234I-1200J1061D01*
G03X434694I300J265D01*
G02Y323112I1200J-1061D01*
G37*
G36*
G01X427494D02*
G03X426894I-300J-265D01*
G02Y325234I-1200J1061D01*
G03X427494I300J265D01*
G02Y323112I1200J-1061D01*
G37*
G36*
G01X367579Y311230D02*
G03X367069Y311072I-167J-363D01*
G02X366528Y313260I-1376J821D01*
G03X367053Y313358I208J342D01*
G02X369157Y313494I1112J-854D01*
G03X369709Y313480I283J283D01*
G02X371644Y313430I941J-1039D01*
G03X372201Y313421I283J282D01*
G02X374123I961J-1021D01*
G03X374680Y313430I274J291D01*
G02X376640Y313458I994J-989D01*
G03X377190I275J290D01*
G02Y311424I966J-1017D01*
G03X376640I-275J-290D01*
G02X374713Y311420I-966J1017D01*
G03X374156Y311411I-274J-291D01*
G02X372168I-994J989D01*
G03X371611Y311420I-283J-282D01*
G02X369658Y311451I-961J1021D01*
G03X369106Y311465I-283J-283D01*
G02X367579Y311230I-941J1039D01*
G37*
G36*
G01X193564Y298740D02*
G03X193010I-277J-288D01*
G02Y300760I-973J1010D01*
G03X193564I277J288D01*
G02X195510I973J-1010D01*
G03X196064I277J288D01*
G02Y298740I973J-1010D01*
G03X195510I-277J-288D01*
G02X193564I-973J1010D01*
G37*
G36*
G01X405894Y294843D02*
G03X405294I-300J-265D01*
G02Y296965I-1200J1061D01*
G03X405894I300J265D01*
G02Y294843I1200J-1061D01*
G37*
G36*
G01X398694D02*
G03X398094I-300J-265D01*
G02Y296965I-1200J1061D01*
G03X398694I300J265D01*
G02Y294843I1200J-1061D01*
G37*
G36*
G01X391494D02*
G03X390894I-300J-265D01*
G02Y296965I-1200J1061D01*
G03X391494I300J265D01*
G02Y294843I1200J-1061D01*
G37*
G36*
G01X384294D02*
G03X383694I-300J-265D01*
G02Y296965I-1200J1061D01*
G03X384294I300J265D01*
G02Y294843I1200J-1061D01*
G37*
G36*
G01X377094D02*
G03X376494I-300J-265D01*
G02Y296965I-1200J1061D01*
G03X377094I300J265D01*
G02Y294843I1200J-1061D01*
G37*
G36*
G01X369894D02*
G03X369294I-300J-265D01*
G02Y296965I-1200J1061D01*
G03X369894I300J265D01*
G02Y294843I1200J-1061D01*
G37*
G36*
G01X434727Y292127D02*
G03X434061I-333J-222D01*
G02X431986Y293972I-1167J777D01*
G03X431960Y294602I-259J305D01*
G02X434094Y296965I934J1302D01*
G03X434694I300J265D01*
G02X436828Y294602I1200J-1061D01*
G03X436802Y293972I233J-325D01*
G02X434727Y292127I-908J-1068D01*
G37*
G36*
G01X427527D02*
G03X426861I-333J-222D01*
G02X424786Y293972I-1167J777D01*
G03X424760Y294602I-259J305D01*
G02X426894Y296965I934J1302D01*
G03X427494I300J265D01*
G02X429628Y294602I1200J-1061D01*
G03X429602Y293972I233J-325D01*
G02X427527Y292127I-908J-1068D01*
G37*
G36*
G01X420327D02*
G03X419661I-333J-222D01*
G02X417586Y293972I-1167J777D01*
G03X417560Y294602I-259J305D01*
G02X419694Y296965I934J1302D01*
G03X420294I300J265D01*
G02X422428Y294602I1200J-1061D01*
G03X422402Y293972I233J-325D01*
G02X420327Y292127I-908J-1068D01*
G37*
G36*
G01X413127D02*
G03X412461I-333J-222D01*
G02X410386Y293972I-1167J777D01*
G03X410360Y294602I-259J305D01*
G02X412494Y296965I934J1302D01*
G03X413094I300J265D01*
G02X415228Y294602I1200J-1061D01*
G03X415202Y293972I233J-325D01*
G02X413127Y292127I-908J-1068D01*
G37*
G36*
G01X434704Y277866D02*
G03X434104Y277860I-297J-268D01*
G02X434084Y279982I-1210J1050D01*
G03X434684Y279988I297J268D01*
G02X434704Y277866I1210J-1050D01*
G37*
G36*
G01X427494Y277849D02*
G03X426894I-300J-265D01*
G02Y279971I-1200J1061D01*
G03X427494I300J265D01*
G02Y277849I1200J-1061D01*
G37*
G36*
G01X420335Y277870D02*
G03X419735Y277863I-297J-268D01*
G02X419711Y279984I-1212J1047D01*
G03X420311Y279991I297J268D01*
G02X420335Y277870I1212J-1047D01*
G37*
G36*
G01X413039Y277813D02*
G03X412456I-291J-273D01*
G02Y280007I-1168J1097D01*
G03X413039I291J273D01*
G02Y277813I1168J-1097D01*
G37*
G36*
G01X391494Y277843D02*
G03X390894I-300J-265D01*
G02Y279965I-1200J1061D01*
G03X391494I300J265D01*
G02Y277843I1200J-1061D01*
G37*
G36*
G01X377094D02*
G03X376494I-300J-265D01*
G02Y279965I-1200J1061D01*
G03X377094I300J265D01*
G02Y277843I1200J-1061D01*
G37*
G36*
G01X369894D02*
G03X369294I-300J-265D01*
G02Y279965I-1200J1061D01*
G03X369894I300J265D01*
G02Y277843I1200J-1061D01*
G37*
G36*
G01X193564Y269740D02*
G03X193010I-277J-288D01*
G02Y271760I-973J1010D01*
G03X193564I277J288D01*
G02X195510I973J-1010D01*
G03X196064I277J288D01*
G02Y269740I973J-1010D01*
G03X195510I-277J-288D01*
G02X193564I-973J1010D01*
G37*
G36*
G01X381946Y272676D02*
G03Y272076I265J-300D01*
G02X379824I-1061J-1200D01*
G03Y272676I-265J300D01*
G02X381946I1061J1200D01*
G37*
G36*
G01X430888Y265654D02*
G03X431491Y265621I316J245D01*
G02X431294Y263644I1152J-1113D01*
G03X430696Y263731I-337J-216D01*
G02X430888Y265654I-915J1062D01*
G37*
G36*
G01X198627Y239616D02*
G03Y239062I288J-277D01*
G02X196607I-1010J-973D01*
G03Y239616I-288J277D01*
G02Y241562I1010J973D01*
G03Y242116I-288J277D01*
G02X198627I1010J973D01*
G03Y241562I288J-277D01*
G02Y239616I-1010J-973D01*
G37*
G36*
G01X192547Y239516D02*
G03Y238962I288J-277D01*
G02X190527I-1010J-973D01*
G03Y239516I-288J277D01*
G02Y241462I1010J973D01*
G03Y242016I-288J277D01*
G02X192547I1010J973D01*
G03Y241462I288J-277D01*
G02Y239516I-1010J-973D01*
G37*
G36*
G01X386654Y323068D02*
G02Y325278I-1160J1105D01*
G03X387234I290J275D01*
G02X389494Y325337I1160J-1105D01*
G03X390044I275J291D01*
G02X392244I1100J-1164D01*
G03X392794I275J291D01*
G02X395094Y325234I1100J-1164D01*
G03X395694I300J265D01*
G02X398094I1200J-1061D01*
G03X398694I300J265D01*
G02X401094I1200J-1061D01*
G03X401694I300J265D01*
G02X404094I1200J-1061D01*
G03X404694I300J265D01*
G02X407094I1200J-1061D01*
G03X407694I300J265D01*
G02X410094I1200J-1061D01*
G03X410694I300J265D01*
G02X413094I1200J-1061D01*
G03X413694I300J265D01*
G02X416334Y324874I1200J-1061D01*
G03X417054I360J175D01*
G02X419694Y325234I1440J-701D01*
G03X420294I300J265D01*
G02Y323112I1200J-1061D01*
G03X419694I-300J-265D01*
G02X417054Y323472I-1200J1061D01*
G03X416334I-360J-175D01*
G02X413694Y323112I-1440J701D01*
G03X413094I-300J-265D01*
G02X410694I-1200J1061D01*
G03X410094I-300J-265D01*
G02X407694I-1200J1061D01*
G03X407094I-300J-265D01*
G02X404694I-1200J1061D01*
G03X404094I-300J-265D01*
G02X401694I-1200J1061D01*
G03X401094I-300J-265D01*
G02X398694I-1200J1061D01*
G03X398094I-300J-265D01*
G02X395694I-1200J1061D01*
G03X395094I-300J-265D01*
G02X392794Y323009I-1200J1061D01*
G03X392244I-275J-291D01*
G02X390044I-1100J1164D01*
G03X389494I-275J-291D01*
G02X387234Y323068I-1100J1164D01*
G03X386654I-290J-275D01*
G37*
G36*
G01X434061Y309127D02*
G02Y310681I-1167J777D01*
G03X434727I333J222D01*
G02Y309127I1167J-777D01*
G03X434061I-333J-222D01*
G37*
G36*
G01X426861D02*
G02Y310681I-1167J777D01*
G03X427527I333J222D01*
G02Y309127I1167J-777D01*
G03X426861I-333J-222D01*
G37*
G36*
G01X419661D02*
G02Y310681I-1167J777D01*
G03X420327I333J222D01*
G02Y309127I1167J-777D01*
G03X419661I-333J-222D01*
G37*
G36*
G01X412461D02*
G02Y310681I-1167J777D01*
G03X413127I333J222D01*
G02Y309127I1167J-777D01*
G03X412461I-333J-222D01*
G37*
G36*
G01X405294Y277849D02*
G02X402792Y277977I-1200J1061D01*
G03X402142Y277978I-325J-233D01*
G02X402144Y279847I-1300J936D01*
G03X402794Y279846I325J233D01*
G02X405294Y279971I1300J-936D01*
G03X405894I300J265D01*
G02Y277849I1200J-1061D01*
G03X405294I-300J-265D01*
G37*
G36*
G01X384661Y279438D02*
G02X384467Y277861I1284J-958D01*
G03X383778Y277946I-369J-154D01*
G02X383972Y279523I-1284J958D01*
G03X384661Y279438I369J154D01*
G37*
G36*
G01X463914Y314235D02*
G03X463891Y313677I275J-291D01*
G02X461882Y313757I-1043J-936D01*
G03X461905Y314315I-275J291D01*
G02X463914Y314235I1043J936D01*
G37*
G36*
G01X591383Y214711D02*
G03Y214089I252J-311D01*
G02X589617I-883J-1089D01*
G03Y214711I-252J311D01*
G02X591383I883J1089D01*
G37*
G36*
G01X566196Y244399D02*
G03X566805Y244396I306J258D01*
G02X566796Y242579I1063J-914D01*
G03X566187Y242582I-306J-258D01*
G02X564139Y242499I-1063J914D01*
G03X563576I-282J-285D01*
G02Y244493I-985J997D01*
G03X564139I282J285D01*
G02X566196Y244399I985J-997D01*
G37*
G36*
G01X571629Y229697D02*
G03X572169Y229539I350J194D01*
G02X571456Y227504I761J-1409D01*
G03X570936Y227718I-368J-156D01*
G02X569455Y230047I-532J1297D01*
G03X569483Y230608I-270J295D01*
G02X570896Y232896I1045J935D01*
G03X571386Y233176I104J386D01*
G02X572350Y231257I1544J-426D01*
G03X571833Y231031I-145J-373D01*
G02X571477Y230511I-1305J512D01*
G03X571449Y229950I270J-295D01*
G02X571629Y229697I-1045J-934D01*
G37*
G36*
G01X565773Y212929D02*
G02X564656Y211694I278J-1374D01*
G03X564178Y212126I-398J40D01*
G02X565295Y213361I-278J1374D01*
G03X565773Y212929I398J-40D01*
G37*
G36*
G01X844127Y361990D02*
G03X843573I-277J-288D01*
G02Y364010I-973J1010D01*
G03X844127I277J288D01*
G02X846073I973J-1010D01*
G03X846627I277J288D01*
G02Y361990I973J-1010D01*
G03X846073I-277J-288D01*
G02X844127I-973J1010D01*
G37*
G36*
G01X1069992Y337612D02*
G03X1069392I-300J-265D01*
G02Y339734I-1200J1061D01*
G03X1069992I300J265D01*
G02Y337612I1200J-1061D01*
G37*
G36*
G01X1062792D02*
G03X1062192I-300J-265D01*
G02Y339734I-1200J1061D01*
G03X1062792I300J265D01*
G02Y337612I1200J-1061D01*
G37*
G36*
G01X1079082Y337472D02*
G03X1078482I-300J-265D01*
G02Y339594I-1200J1061D01*
G03X1079082I300J265D01*
G02Y337472I1200J-1061D01*
G37*
G36*
G01X844127Y330490D02*
G03X843573I-277J-288D01*
G02Y332510I-973J1010D01*
G03X844127I277J288D01*
G02X846073I973J-1010D01*
G03X846627I277J288D01*
G02Y330490I973J-1010D01*
G03X846073I-277J-288D01*
G02X844127I-973J1010D01*
G37*
G36*
G01X1017937Y325288D02*
G03X1017717Y324783I156J-368D01*
G02X1015855Y325596I-1318J-479D01*
G03X1016075Y326101I-156J368D01*
G02X1018366Y327590I1318J480D01*
G03X1018920I277J288D01*
G02X1020866I973J-1010D01*
G03X1021420I277J288D01*
G02X1023366I973J-1010D01*
G03X1023920I277J288D01*
G02X1024287Y327844I971J-1011D01*
G03X1024479Y328371I-172J361D01*
G02X1026567Y330094I1276J580D01*
G03X1027153Y330233I232J326D01*
G02X1028642Y328200I1240J-653D01*
G03X1028420Y327534I71J-394D01*
G02X1026420Y325570I-1027J-955D01*
G03X1025866I-277J-288D01*
G02X1023920I-973J1010D01*
G03X1023366I-277J-288D01*
G02X1021420I-973J1010D01*
G03X1020866I-277J-288D01*
G02X1018920I-973J1010D01*
G03X1018366I-277J-288D01*
G02X1017937Y325288I-972J1011D01*
G37*
G36*
G01X1077820Y323113D02*
G03X1077220I-300J-265D01*
G02Y325235I-1200J1061D01*
G03X1077820I300J265D01*
G02Y323113I1200J-1061D01*
G37*
G36*
G01X1017207Y311236D02*
G03X1016654Y311109I-213J-338D01*
G02X1016286Y313212I-1361J846D01*
G03X1016850Y313281I248J314D01*
G02X1018914Y313445I1107J-860D01*
G03X1019458Y313442I274J292D01*
G02X1021395Y313399I946J-1034D01*
G03X1021953Y313391I283J283D01*
G02X1023893Y313377I963J-1019D01*
G03X1024453Y313379I279J286D01*
G02X1026438Y313364I985J-998D01*
G03X1027015Y313371I285J281D01*
G02X1027039Y311431I1024J-957D01*
G03X1026462Y311424I-285J-281D01*
G02X1024460Y311376I-1025J957D01*
G03X1023900Y311374I-279J-286D01*
G02X1021924Y311381I-984J998D01*
G03X1021366Y311389I-283J-283D01*
G02X1019447Y311384I-962J1019D01*
G03X1018903Y311387I-274J-292D01*
G02X1017207Y311236I-947J1034D01*
G37*
G36*
G01X844127Y298890D02*
G03X843573I-277J-288D01*
G02Y300910I-973J1010D01*
G03X844127I277J288D01*
G02X846073I973J-1010D01*
G03X846627I277J288D01*
G02Y298890I973J-1010D01*
G03X846073I-277J-288D01*
G02X844127I-973J1010D01*
G37*
G36*
G01X1055367Y294798D02*
G03X1054767I-300J-265D01*
G02Y296920I-1200J1061D01*
G03X1055367I300J265D01*
G02Y294798I1200J-1061D01*
G37*
G36*
G01X1048167D02*
G03X1047567I-300J-265D01*
G02Y296920I-1200J1061D01*
G03X1048167I300J265D01*
G02Y294798I1200J-1061D01*
G37*
G36*
G01X1040967D02*
G03X1040367I-300J-265D01*
G02Y296920I-1200J1061D01*
G03X1040967I300J265D01*
G02Y294798I1200J-1061D01*
G37*
G36*
G01X1033767D02*
G03X1033167I-300J-265D01*
G02Y296920I-1200J1061D01*
G03X1033767I300J265D01*
G02Y294798I1200J-1061D01*
G37*
G36*
G01X1026567D02*
G03X1025967I-300J-265D01*
G02Y296920I-1200J1061D01*
G03X1026567I300J265D01*
G02Y294798I1200J-1061D01*
G37*
G36*
G01X1019367D02*
G03X1018767I-300J-265D01*
G02Y296920I-1200J1061D01*
G03X1019367I300J265D01*
G02Y294798I1200J-1061D01*
G37*
G36*
G01X1084335Y292127D02*
G03X1083669I-333J-222D01*
G02X1081527Y293911I-1167J777D01*
G03X1081472Y294530I-278J287D01*
G02X1083567Y296920I895J1329D01*
G03X1084167I300J265D01*
G02X1086379Y294617I1200J-1061D01*
G03X1086381Y293996I253J-310D01*
G02X1084335Y292127I-879J-1092D01*
G37*
G36*
G01X1077135D02*
G03X1076469I-333J-222D01*
G02X1074327Y293911I-1167J777D01*
G03X1074272Y294530I-278J287D01*
G02X1076367Y296920I895J1329D01*
G03X1076967I300J265D01*
G02X1079179Y294617I1200J-1061D01*
G03X1079181Y293996I253J-310D01*
G02X1077135Y292127I-879J-1092D01*
G37*
G36*
G01X1069935D02*
G03X1069269I-333J-222D01*
G02X1067127Y293911I-1167J777D01*
G03X1067072Y294530I-278J287D01*
G02X1069167Y296920I895J1329D01*
G03X1069767I300J265D01*
G02X1071979Y294617I1200J-1061D01*
G03X1071981Y293996I253J-310D01*
G02X1069935Y292127I-879J-1092D01*
G37*
G36*
G01X1062735D02*
G03X1062069I-333J-222D01*
G02X1059927Y293911I-1167J777D01*
G03X1059872Y294530I-278J287D01*
G02X1061967Y296920I895J1329D01*
G03X1062567I300J265D01*
G02X1064779Y294617I1200J-1061D01*
G03X1064781Y293996I253J-310D01*
G02X1062735Y292127I-879J-1092D01*
G37*
G36*
G01X1084242Y277941D02*
G03X1083606I-318J-242D01*
G02Y279879I-1276J969D01*
G03X1084242I318J242D01*
G02Y277941I1276J-969D01*
G37*
G36*
G01X1077102Y277849D02*
G03X1076502I-300J-265D01*
G02Y279971I-1200J1061D01*
G03X1077102I300J265D01*
G02Y277849I1200J-1061D01*
G37*
G36*
G01X1069668Y277918D02*
G03X1069041I-314J-248D01*
G02Y279902I-1258J992D01*
G03X1069668I314J248D01*
G02Y277918I1258J-992D01*
G37*
G36*
G01X1062574Y277725D02*
G03X1062036I-269J-296D01*
G02Y280095I-1078J1185D01*
G03X1062574I269J296D01*
G02Y277725I1078J-1185D01*
G37*
G36*
G01X1026702Y277843D02*
G03X1026102I-300J-265D01*
G02Y279965I-1200J1061D01*
G03X1026702I300J265D01*
G02Y277843I1200J-1061D01*
G37*
G36*
G01X1019502D02*
G03X1018902I-300J-265D01*
G02Y279965I-1200J1061D01*
G03X1019502I300J265D01*
G02Y277843I1200J-1061D01*
G37*
G36*
G01X1031550Y272689D02*
G03Y272089I265J-300D01*
G02X1029428I-1061J-1200D01*
G03Y272689I-265J300D01*
G02X1031550I1061J1200D01*
G37*
G36*
G01X844127Y267190D02*
G03X843573I-277J-288D01*
G02Y269210I-973J1010D01*
G03X844127I277J288D01*
G02X846073I973J-1010D01*
G03X846627I277J288D01*
G02Y267190I973J-1010D01*
G03X846073I-277J-288D01*
G02X844127I-973J1010D01*
G37*
G36*
G01X1080905Y265934D02*
G03X1081449Y265885I298J266D01*
G02X1081125Y263694I983J-1265D01*
G03X1080590Y263804I-326J-231D01*
G02X1080905Y265934I-731J1196D01*
G37*
G36*
G01X848610Y239927D02*
G03Y239373I288J-277D01*
G02X846590I-1010J-973D01*
G03Y239927I-288J277D01*
G02Y241873I1010J973D01*
G03Y242427I-288J277D01*
G02X848610I1010J973D01*
G03Y241873I288J-277D01*
G02Y239927I-1010J-973D01*
G37*
G36*
G01X842410Y239827D02*
G03Y239273I288J-277D01*
G02X840390I-1010J-973D01*
G03Y239827I-288J277D01*
G02Y241773I1010J973D01*
G03Y242327I-288J277D01*
G02X842410I1010J973D01*
G03Y241773I288J-277D01*
G02Y239827I-1010J-973D01*
G37*
G36*
G01X1048923Y337564D02*
G02Y339118I-1167J777D01*
G03X1049589I333J222D01*
G02X1051885Y339173I1167J-777D01*
G03X1052539Y339187I322J237D01*
G02X1054735Y339352I1163J-783D01*
G03X1055382Y339433I295J270D01*
G02X1055534Y337681I1410J-760D01*
G03X1054883Y337649I-314J-248D01*
G02X1052573Y337572I-1181J755D01*
G03X1051919Y337558I-322J-237D01*
G02X1049589Y337564I-1163J783D01*
G03X1048923I-333J-222D01*
G37*
G36*
G01X1036980Y323069D02*
G02Y325279I-1160J1105D01*
G03X1037560I290J275D01*
G02X1039820Y325338I1160J-1105D01*
G03X1040370I275J291D01*
G02X1042570I1100J-1164D01*
G03X1043120I275J291D01*
G02X1045420Y325235I1100J-1164D01*
G03X1046020I300J265D01*
G02X1048420I1200J-1061D01*
G03X1049020I300J265D01*
G02X1051420I1200J-1061D01*
G03X1052020I300J265D01*
G02X1054420I1200J-1061D01*
G03X1055020I300J265D01*
G02X1057420I1200J-1061D01*
G03X1058020I300J265D01*
G02X1060420I1200J-1061D01*
G03X1061020I300J265D01*
G02X1063420I1200J-1061D01*
G03X1064020I300J265D01*
G02X1066660Y324875I1200J-1061D01*
G03X1067380I360J175D01*
G02X1070020Y325235I1440J-701D01*
G03X1070620I300J265D01*
G02Y323113I1200J-1061D01*
G03X1070020I-300J-265D01*
G02X1067380Y323473I-1200J1061D01*
G03X1066660I-360J-175D01*
G02X1064020Y323113I-1440J701D01*
G03X1063420I-300J-265D01*
G02X1061020I-1200J1061D01*
G03X1060420I-300J-265D01*
G02X1058020I-1200J1061D01*
G03X1057420I-300J-265D01*
G02X1055020I-1200J1061D01*
G03X1054420I-300J-265D01*
G02X1052020I-1200J1061D01*
G03X1051420I-300J-265D01*
G02X1049020I-1200J1061D01*
G03X1048420I-300J-265D01*
G02X1046020I-1200J1061D01*
G03X1045420I-300J-265D01*
G02X1043120Y323010I-1200J1061D01*
G03X1042570I-275J-291D01*
G02X1040370I-1100J1164D01*
G03X1039820I-275J-291D01*
G02X1037560Y323069I-1100J1164D01*
G03X1036980I-290J-275D01*
G37*
G36*
G01X1083669Y309127D02*
G02Y310681I-1167J777D01*
G03X1084335I333J222D01*
G02Y309127I1167J-777D01*
G03X1083669I-333J-222D01*
G37*
G36*
G01X1076469D02*
G02Y310681I-1167J777D01*
G03X1077135I333J222D01*
G02Y309127I1167J-777D01*
G03X1076469I-333J-222D01*
G37*
G36*
G01X1069269D02*
G02Y310681I-1167J777D01*
G03X1069935I333J222D01*
G02Y309127I1167J-777D01*
G03X1069269I-333J-222D01*
G37*
G36*
G01X1062069D02*
G02Y310681I-1167J777D01*
G03X1062735I333J222D01*
G02Y309127I1167J-777D01*
G03X1062069I-333J-222D01*
G37*
G36*
G01X1054717Y277918D02*
G02X1052004Y278239I-1258J992D01*
G03X1051287Y278257I-363J-168D01*
G02X1051322Y279670I-1420J742D01*
G03X1052039Y279652I363J168D01*
G02X1054717Y279902I1420J-742D01*
G03X1055344I314J248D01*
G02Y277918I1258J-992D01*
G03X1054717I-314J-248D01*
G37*
G36*
G01X1037239Y278042D02*
G02X1037181Y279611I-1425J733D01*
G03X1037877Y279637I341J209D01*
G02X1040502Y279965I1425J-733D01*
G03X1041102I300J265D01*
G02Y277843I1200J-1061D01*
G03X1040502I-300J-265D01*
G02X1037935Y278068I-1200J1061D01*
G03X1037239Y278042I-341J-209D01*
G37*
G36*
G01X1224394Y258062D02*
G02X1223990Y259683I-1294J538D01*
G03X1224614Y259838I255J309D01*
G02X1224898Y260273I1296J-536D01*
G03Y260827I-288J277D01*
G02X1224659Y261164I1012J971D01*
G03X1224126Y261341I-356J-182D01*
G02X1224757Y263236I-618J1258D01*
G03X1225290Y263059I356J182D01*
G02X1226918Y260827I619J-1258D01*
G03Y260273I288J-277D01*
G02X1225018Y258217I-1009J-973D01*
G03X1224394Y258062I-255J-309D01*
G37*
G36*
G01X1434351Y6244D02*
G03X1433976Y5706I0J-400D01*
G02X1431459Y5942I-1315J-486D01*
G03X1431287Y6244I-172J102D01*
G01X1431025D01*
G02Y9268I0J1512D01*
G01X1436026D01*
G02X1437536Y7766I-1J-1512D01*
G01Y7671D01*
X1437527Y7587D01*
G02X1437150Y6746I-1502J168D01*
G03X1437155Y6206I297J-267D01*
G02X1434808Y5712I-1024J-958D01*
G03X1434431Y6244I-377J132D01*
G01X1434351D01*
G37*
G36*
G01X1452057Y4078D02*
G03X1451713Y3473I0J-400D01*
G02X1449420Y3640I-1205J-717D01*
G03X1449294Y4248I-310J253D01*
G02X1449991Y7100I697J1341D01*
G01X1454992D01*
G02X1456502Y5599I-1J-1511D01*
G01Y5504D01*
X1456493Y5420D01*
G02X1455827Y4330I-1502J169D01*
G03X1455752Y3727I221J-334D01*
G02X1453498Y3479I-1037J-943D01*
G03X1453150Y4078I-348J199D01*
G01X1452057D01*
G37*
G36*
G01X1446340Y10052D02*
X1441340D01*
G02X1439842Y11758I1J1511D01*
G03X1439328Y12192I-397J52D01*
G02X1440314Y13405I-410J1341D01*
G03X1440844Y12991I398J-36D01*
G02X1441340Y13074I494J-1428D01*
G01X1446340D01*
G02X1446519Y13064I5J-1511D01*
G03X1446966Y13477I47J397D01*
G02X1448271Y12134I1401J56D01*
G03X1447845Y11699I-28J-399D01*
G02X1447852Y11573I-1504J-147D01*
G01Y11478D01*
X1447842Y11394D01*
G02X1446340Y10052I-1502J169D01*
G37*
G36*
G01X1427442D02*
X1422442D01*
G02X1420937Y11703I0J1511D01*
G03X1420423Y12124I-398J38D01*
G02X1418864Y12672I-404J1342D01*
G03X1418165Y12599I-330J-227D01*
G02X1415646Y12458I-1294J540D01*
G03X1414946I-350J-194D01*
G02X1412489Y12470I-1225J681D01*
G03X1411790Y12477I-351J-191D01*
G02X1409353Y12476I-1219J693D01*
G03X1408654Y12469I-348J-198D01*
G02X1408640Y13833I-1232J669D01*
G03X1409339Y13840I348J198D01*
G02X1411803Y13839I1232J-670D01*
G03X1412502Y13832I351J191D01*
G02X1414946Y13820I1219J-693D01*
G03X1415646I350J194D01*
G02X1418026Y13933I1225J-681D01*
G03X1418725Y14006I330J227D01*
G02X1421419Y13391I1294J-540D01*
G03X1421949Y12992I399J-21D01*
G02X1422442Y13074I491J-1429D01*
G01X1427443D01*
G02X1427620Y13064I3J-1511D01*
G03X1428067Y13462I47J397D01*
G02X1429377Y12067I1402J4D01*
G03X1428951Y11646I-27J-399D01*
G02X1428954Y11573I-1508J-99D01*
G01Y11478D01*
X1428944Y11394D01*
G02X1427442Y10052I-1502J169D01*
G37*
G36*
G01X1548776Y429391D02*
G03Y428844I292J-274D01*
G02X1546732I-1022J-960D01*
G03Y429391I-292J274D01*
G02X1548097Y431710I1022J960D01*
G03X1548579Y431986I98J388D01*
G02X1549582Y430235I1346J-392D01*
G03X1549100Y429959I-98J-388D01*
G02X1548776Y429391I-1346J392D01*
G37*
G36*
G01X1535647Y412859D02*
G02X1535604Y414219I-1247J641D01*
G03X1536303Y414241I343J205D01*
G02X1536869Y414825I1246J-642D01*
G03Y415525I-194J350D01*
G02X1536325Y416069I681J1225D01*
G03X1535625I-350J-194D01*
G02X1533719Y417975I-1225J681D01*
G03Y418675I-194J350D01*
G02X1533175Y419219I681J1225D01*
G03X1532475I-350J-194D01*
G02X1530569Y421125I-1225J681D01*
G03Y421825I-194J350D01*
G02Y424275I681J1225D01*
G03Y424975I-194J350D01*
G02Y427425I681J1225D01*
G03Y428125I-194J350D01*
G02X1532475Y430031I681J1225D01*
G03X1533175I350J194D01*
G02X1535625I1225J-681D01*
G03X1536325I350J194D01*
G02X1538775I1225J-681D01*
G03X1539475I350J194D01*
G02X1541925I1225J-681D01*
G03X1542625I350J194D01*
G02X1544531Y428125I1225J-681D01*
G03Y427425I194J-350D01*
G02X1542625Y425519I-681J-1225D01*
G03X1541925I-350J-194D01*
G02X1541381Y424975I-1225J681D01*
G03Y424275I194J-350D01*
G02Y421825I-681J-1225D01*
G03Y421125I194J-350D01*
G02Y418675I-681J-1225D01*
G03Y417975I194J-350D01*
G02X1541925Y417431I-681J-1225D01*
G03X1542625I350J194D01*
G02X1545075I1225J-681D01*
G03X1545775I350J194D01*
G02Y416069I1225J-681D01*
G03X1545075I-350J-194D01*
G02X1544531Y415525I-1225J681D01*
G03Y414825I194J-350D01*
G02X1543169I-681J-1225D01*
G03Y415525I-194J350D01*
G02X1542625Y416069I681J1225D01*
G03X1541925I-350J-194D01*
G02X1539475I-1225J681D01*
G03X1538775I-350J-194D01*
G02X1538231Y415525I-1225J681D01*
G03Y414825I194J-350D01*
G02X1536346Y412881I-681J-1225D01*
G03X1535647Y412859I-343J-205D01*
G37*
G36*
G01X1637013Y152605D02*
G02Y153967I-1225J681D01*
G03X1637713I350J194D01*
G02Y152605I1225J-681D01*
G03X1637013I-350J-194D01*
G37*
G36*
G01X1627564Y149455D02*
G02Y150817I-1225J681D01*
G03X1628264I350J194D01*
G02X1628808Y151361I1225J-681D01*
G03Y152061I-194J350D01*
G02X1630170I681J1225D01*
G03Y151361I194J-350D01*
G02X1628264Y149455I-681J-1225D01*
G03X1627564I-350J-194D01*
G37*
G36*
G01X1637013Y143155D02*
G02Y144519I-1225J682D01*
G03X1637712I350J194D01*
G02X1640162Y144518I1225J-682D01*
G03X1640862I350J194D01*
G02Y143156I1225J-681D01*
G03X1640162I-350J-194D01*
G02X1637712Y143155I-1225J681D01*
G03X1637013I-350J-194D01*
G37*
G36*
G01Y136856D02*
G02Y138220I-1225J682D01*
G03X1637712I350J194D01*
G02Y136856I1225J-682D01*
G03X1637013I-350J-194D01*
G37*
G36*
G01X1636542Y129397D02*
G02X1634987Y129417I-793J-1157D01*
G03X1634996Y130082I-217J336D01*
G02X1637013Y131921I792J1157D01*
G03X1637712I350J194D01*
G02Y130557I1225J-682D01*
G03X1637013I-350J-194D01*
G02X1636551Y130062I-1226J681D01*
G03X1636542Y129397I217J-336D01*
G37*
G36*
G01X1643312Y124259D02*
G02Y125621I-1225J681D01*
G03X1644012I350J194D01*
G02Y124259I1225J-681D01*
G03X1643312I-350J-194D01*
G37*
G36*
G01X1794515Y164444D02*
G03X1794527Y163920I308J-255D01*
G02X1791958Y163861I-1259J-1146D01*
G03X1791946Y164385I-308J255D01*
G02X1794515Y164444I1259J1146D01*
G37*
G36*
G01X1819521Y154398D02*
X1817475D01*
G02X1815275Y154347I-1127J1139D01*
G01X1815218Y154398D01*
X1815098D01*
Y154532D01*
X1815059Y154585D01*
G02X1815098Y156540I1289J952D01*
G01Y162434D01*
G02X1815059Y164389I1250J1003D01*
G01X1815098Y164442D01*
Y164802D01*
X1815507D01*
X1815553Y164828D01*
G02X1817187Y164802I795J-1391D01*
G01X1819809D01*
G02X1821443Y164828I839J-1365D01*
G01X1821489Y164802D01*
X1821902D01*
Y164437D01*
X1821940Y164384D01*
G02X1821902Y162439I-1292J-948D01*
G01Y156535D01*
G02X1821940Y154590I-1254J-997D01*
G01X1821902Y154537D01*
Y154398D01*
X1821778D01*
X1821721Y154347D01*
G02X1819521Y154398I-1073J1190D01*
G37*
G36*
G01X1789002Y155728D02*
G03X1789521Y155494I375J139D01*
G02X1788598Y153442I579J-1494D01*
G03X1788079Y153676I-375J-139D01*
G02X1789002Y155728I-579J1494D01*
G37*
G36*
G01X1829700Y151589D02*
G03X1829576Y150980I184J-355D01*
G02X1827600Y151381I-1236J-1020D01*
G03X1827724Y151990I-184J355D01*
G02X1829700Y151589I1236J1020D01*
G37*
G36*
G01X1801405Y144914D02*
G03X1801963Y144902I285J280D01*
G02X1801917Y142608I1095J-1169D01*
G03X1801359Y142620I-285J-280D01*
G02X1801405Y144914I-1095J1169D01*
G37*
G36*
G01X1846842Y136325D02*
G03X1847368Y136175I343J206D01*
G02X1846727Y133925I732J-1425D01*
G03X1846201Y134075I-343J-206D01*
G02X1846842Y136325I-732J1425D01*
G37*
G36*
G01X1822680Y142546D02*
G02X1822546Y144501I-1332J891D01*
G03X1823177Y144544I299J265D01*
G02X1825344Y145020I1331J-891D01*
G03X1825941Y145270I208J342D01*
G02X1828977Y145520I1559J-370D01*
G03X1829689Y145468I369J154D01*
G02X1831540Y146248I1459J-876D01*
G03X1832006Y146497I91J389D01*
G02X1833208Y144244I1594J-597D01*
G03X1832742Y143995I-91J-389D01*
G02X1829563Y143973I-1594J597D01*
G03X1828852Y144041I-373J-146D01*
G02X1826665Y143533I-1352J859D01*
G03X1826068Y143283I-208J-342D01*
G02X1823311Y142589I-1559J370D01*
G03X1822680Y142546I-299J-265D01*
G37*
G36*
G01X1736595Y106075D02*
G02X1735233I-681J-1225D01*
G03Y106775I-194J350D01*
G02X1737139Y108681I681J1225D01*
G03X1737839I350J194D01*
G02Y107319I1225J-681D01*
G03X1737139I-350J-194D01*
G02X1736595Y106775I-1225J681D01*
G03Y106075I194J-350D01*
G37*
G36*
G01X1742895Y99775D02*
G02X1741533I-681J-1225D01*
G03Y100475I-194J350D01*
G02X1742895I681J1225D01*
G03Y99775I194J-350D01*
G37*
G54D47*
X691900Y531350D03*
Y534850D03*
X697500Y534750D03*
Y531250D03*
X1757689Y123850D03*
G54D44*
X27280Y510420D03*
X51607Y511747D03*
X57936Y516012D03*
G54D40*
X448593Y652514D03*
Y646514D03*
X438681D03*
Y652514D03*
X567029Y652238D03*
Y646238D03*
X576941D03*
Y652238D03*
X1265293Y652264D03*
Y646264D03*
X1255381D03*
Y652264D03*
X1509696Y652236D03*
Y646236D03*
X1519608D03*
Y652236D03*
X19800Y257900D03*
X1032102Y278904D03*
X1089702D03*
X1083220Y324174D03*
X1750189Y159550D03*
X1758650Y158650D03*
X1776828Y155211D03*
X1768886Y156173D03*
X1800000Y132627D03*
X1811348Y143448D03*
X1801366Y151937D03*
X1808226Y136171D03*
X1788000Y129000D03*
X1796500Y120000D03*
X1815348Y143437D03*
X1809810Y155858D03*
X1787373Y120188D03*
X1807166Y147401D03*
X1800420Y148240D03*
X1785500Y164000D03*
X1778900Y165800D03*
G54D42*
X20512Y467244D03*
X50512D03*
G54D48*
X1241712Y187710D03*
G54D39*
X5120Y276058D03*
X2269Y273532D03*
X1500Y295000D03*
X19904Y254162D03*
X37000Y265350D03*
X33490Y267900D03*
X37000Y275000D03*
X271239Y273460D03*
X284759Y265660D03*
X291519D03*
Y277360D03*
X281379Y275409D03*
Y271509D03*
X284759Y277360D03*
Y273460D03*
X288139Y275409D03*
Y271509D03*
X277999Y277360D03*
Y269560D03*
X274619Y275409D03*
Y267609D03*
X291519Y269560D03*
X294899Y275409D03*
X281379Y267609D03*
X284759Y269560D03*
X288139Y267609D03*
X277999Y265660D03*
X274619Y271509D03*
X294899D03*
Y267609D03*
X291519Y273460D03*
X277999D03*
X291519Y285160D03*
Y292959D03*
X284759Y285160D03*
X277999Y308560D03*
Y300760D03*
Y292959D03*
Y285160D03*
X291519Y308560D03*
X284759D03*
Y300760D03*
X291519D03*
X284759Y292959D03*
X277999Y316360D03*
X308418Y275409D03*
X301659D03*
X321938Y283209D03*
Y275409D03*
X315178Y279310D03*
X318558Y277360D03*
X315178Y283209D03*
X318558Y281260D03*
X325318Y269560D03*
X305039D03*
X318558D03*
X328698Y267609D03*
Y283209D03*
X332078Y269560D03*
Y281260D03*
X325318D03*
Y273460D03*
Y265660D03*
X301659Y267609D03*
X298279Y265660D03*
X305039Y273460D03*
Y277360D03*
X311798D03*
Y269560D03*
X305039Y265660D03*
X298279Y277360D03*
X338838Y265660D03*
X335458Y267609D03*
X338838Y281260D03*
X335458Y283209D03*
X345598Y265660D03*
Y273460D03*
Y269560D03*
X342218Y271509D03*
Y267609D03*
Y283209D03*
Y279310D03*
Y275409D03*
X332078Y265660D03*
X315178Y275409D03*
Y267609D03*
Y271509D03*
X311798Y265660D03*
Y273460D03*
X321938Y267609D03*
Y271509D03*
X308418Y267609D03*
Y271509D03*
X318558Y265660D03*
Y273460D03*
X338838D03*
Y269560D03*
X332078Y273460D03*
X298279D03*
X335458Y275409D03*
X328698D03*
X338838Y277360D03*
X332078D03*
X325318D03*
X335458Y279310D03*
X328698D03*
X321938D03*
X335458Y271509D03*
X301659D03*
X328698D03*
X298279Y269560D03*
X311798Y292959D03*
X305039D03*
X318558D03*
X311798Y285160D03*
X328698Y310509D03*
X332078Y300760D03*
Y292959D03*
X298279Y308560D03*
X321938Y310509D03*
X315178D03*
X305039Y308560D03*
X311798D03*
X305039Y300760D03*
X325318D03*
X311798D03*
X298279D03*
X318558D03*
X325318Y292959D03*
X305039Y285160D03*
X298279D03*
Y292959D03*
X318558Y312460D03*
X325318D03*
X315178Y314409D03*
X332078Y312460D03*
X335458Y310509D03*
X338838Y300760D03*
Y292959D03*
X342218Y310509D03*
Y314409D03*
X338838Y312460D03*
Y316360D03*
X345598Y328060D03*
X342218Y322209D03*
Y318309D03*
X355737Y337809D03*
X345598Y320260D03*
Y324160D03*
X328698Y314409D03*
X321938D03*
X335458D03*
X338838Y320260D03*
X359117Y339760D03*
X362497Y341709D03*
X365877Y343660D03*
X441743Y348497D03*
X433854Y352696D03*
X445123Y346546D03*
X427094Y352696D03*
X453013Y245447D03*
Y237647D03*
X449633Y251296D03*
Y247396D03*
X436113Y243496D03*
X442873D03*
X432733Y249347D03*
X436113Y251296D03*
X446253Y245447D03*
X432733D03*
X439493Y237647D03*
X446253D03*
X439493Y241547D03*
Y233746D03*
X432733Y237647D03*
X439493Y253247D03*
X449633Y255196D03*
Y259096D03*
X446253Y257147D03*
X442873Y255196D03*
X453013Y257147D03*
Y261047D03*
X466533Y245447D03*
X480052Y237647D03*
Y233746D03*
Y241547D03*
X476672Y243496D03*
X473292Y237647D03*
X466533D03*
X456393Y243496D03*
Y251296D03*
X459773Y233746D03*
Y241547D03*
Y237647D03*
X463153Y243496D03*
Y251296D03*
Y259096D03*
X456393D03*
X459773Y261047D03*
X466533Y233746D03*
Y241547D03*
X476672Y235696D03*
Y239596D03*
X463153Y235696D03*
Y239596D03*
X473292Y233746D03*
Y241547D03*
X469913Y243496D03*
Y235696D03*
Y239596D03*
X436113Y235696D03*
Y239596D03*
X432733Y233746D03*
Y241547D03*
X446253Y233746D03*
Y241547D03*
X456393Y235696D03*
Y239596D03*
X442873Y235696D03*
Y239596D03*
X453013Y233746D03*
Y241547D03*
X456393Y247396D03*
Y255196D03*
X466533Y249347D03*
X453013D03*
Y253247D03*
X463153Y247396D03*
Y255196D03*
X459773Y245447D03*
X449633Y243496D03*
X459773Y257147D03*
X449633Y235696D03*
X459773Y249347D03*
X449633Y239596D03*
X459773Y253247D03*
X438363Y257446D03*
X441743Y259397D03*
X511592Y218147D03*
X498072Y222047D03*
X501452Y212296D03*
X508212Y220096D03*
Y212296D03*
X521731D03*
X514972D03*
X508212Y216196D03*
X501452Y220096D03*
X504832Y214247D03*
X498072Y218147D03*
Y214247D03*
X518352D03*
X514972Y216196D03*
X511592Y214247D03*
X504832Y222047D03*
Y218147D03*
X501452Y216196D03*
X498072Y233746D03*
X486812D03*
X494692Y235696D03*
X504832Y229847D03*
X498072Y225947D03*
X486812Y237647D03*
Y241547D03*
X483432Y243496D03*
X501452Y223996D03*
X508212Y231797D03*
Y223996D03*
X483432Y235696D03*
X511592Y229847D03*
Y225947D03*
X498072Y229847D03*
X504832Y233746D03*
X494692Y227896D03*
X501452Y235696D03*
X498072Y237647D03*
X508212Y227896D03*
X501452D03*
Y231797D03*
X494692D03*
Y239596D03*
X483432D03*
X465100Y280300D03*
X477792Y342947D03*
Y327347D03*
X474413Y340996D03*
Y337096D03*
X481172Y344896D03*
X474413D03*
X481172Y321496D03*
Y325396D03*
Y333196D03*
X463671Y319386D03*
X471033Y339047D03*
X481172Y329296D03*
X477792Y339047D03*
Y335147D03*
Y331247D03*
X481172Y340996D03*
Y337096D03*
X477792Y362447D03*
Y354647D03*
Y358547D03*
X481172Y372197D03*
X474413Y364396D03*
Y348796D03*
X471033Y350747D03*
X474413Y352696D03*
X471033Y358547D03*
X481172Y360496D03*
X467653Y348796D03*
X481172Y352696D03*
X477792Y346847D03*
X481172Y348796D03*
X477792Y350747D03*
X481172Y364396D03*
Y368296D03*
X477792Y366347D03*
X474413Y356596D03*
Y360496D03*
X471033Y354647D03*
X467653Y356596D03*
Y352696D03*
X471033Y346847D03*
X481172Y356596D03*
X508212Y329296D03*
X504832Y342947D03*
X484552Y323446D03*
X501452Y344896D03*
X508212Y325396D03*
X491312Y339047D03*
X494692Y337096D03*
Y344896D03*
X511592Y327347D03*
Y339047D03*
Y331247D03*
Y335147D03*
Y323446D03*
X498072Y342947D03*
X494692Y340996D03*
X504832Y331247D03*
X508212Y337096D03*
Y333196D03*
X504832Y335147D03*
X501452Y333196D03*
X504832Y339047D03*
X501452Y340996D03*
X504832Y323446D03*
X498072Y327347D03*
X491312Y331247D03*
X514972Y333196D03*
Y329296D03*
Y325396D03*
Y337096D03*
X518352Y323446D03*
X521731Y325396D03*
X518352Y327347D03*
Y339047D03*
Y342947D03*
X531871Y335147D03*
X525111D03*
X528491Y337096D03*
X525111Y342947D03*
X531871Y327347D03*
X535251Y329296D03*
X538631Y335147D03*
Y339047D03*
X484552Y331247D03*
X501452Y337096D03*
X531871Y331247D03*
X525111Y323446D03*
X531871D03*
X525111Y327347D03*
X528491Y333196D03*
X521731Y329296D03*
X518352Y335147D03*
X521731Y340996D03*
X528491Y325396D03*
Y329296D03*
X525111Y331247D03*
X521731Y333196D03*
Y337096D03*
X535251Y344896D03*
X542011D03*
Y340996D03*
Y337096D03*
X538631Y331247D03*
X535251Y340996D03*
X538631Y342947D03*
X542011Y333196D03*
Y329296D03*
X491312Y323446D03*
X535251Y337096D03*
X528491Y340996D03*
X531871Y339047D03*
Y342947D03*
X528491Y344896D03*
X491312Y342947D03*
X487932Y344896D03*
X484552Y342947D03*
X501452Y325396D03*
X498072Y323446D03*
Y335147D03*
X501452Y321496D03*
X498072Y331247D03*
X501452Y329296D03*
X494692Y325396D03*
Y321496D03*
Y333196D03*
X491312Y335147D03*
X487932Y333196D03*
Y337096D03*
X484552Y339047D03*
Y335147D03*
X491312Y327347D03*
X494692Y329296D03*
X487932D03*
Y340996D03*
Y321496D03*
X484552Y327347D03*
X487932Y325396D03*
X491312Y370247D03*
X498072Y366347D03*
X494692Y372197D03*
X504832Y366347D03*
X501452Y368296D03*
X487932D03*
X484552Y362447D03*
X498072D03*
X491312D03*
X494692Y360496D03*
X487932D03*
X504832Y354647D03*
X494692Y348796D03*
X491312Y350747D03*
Y366347D03*
X487932Y372197D03*
X484552Y370247D03*
Y366347D03*
X487932Y364396D03*
X494692D03*
X501452D03*
X491312Y358547D03*
X498072Y350747D03*
Y346847D03*
X501452Y360496D03*
X491312Y346847D03*
X494692Y356596D03*
X498072Y358547D03*
Y354647D03*
X484552Y346847D03*
X508212Y352696D03*
Y360496D03*
X504832Y346847D03*
Y358547D03*
X501452Y356596D03*
Y348796D03*
Y352696D03*
X511592Y370247D03*
X498072Y385847D03*
X508212Y387796D03*
X501452Y391696D03*
X504832Y381947D03*
Y378047D03*
X501452Y379996D03*
X511592Y378047D03*
Y397546D03*
X491312Y378047D03*
X487932Y376096D03*
X491312Y374146D03*
X514972Y372197D03*
Y356596D03*
X521731Y360496D03*
Y356596D03*
Y348796D03*
X518352Y362447D03*
X521731Y372197D03*
X518352Y370247D03*
X525111Y354647D03*
X531871Y346847D03*
X535251Y356596D03*
X538631Y366347D03*
X528491Y364396D03*
X542011Y348796D03*
X514972Y379996D03*
X531871Y374146D03*
X521731Y399496D03*
X518352Y397546D03*
Y389747D03*
X535251Y383896D03*
X525111Y381947D03*
X538631Y393647D03*
Y378047D03*
X531871Y401447D03*
Y389747D03*
X525111Y393647D03*
X484552Y374146D03*
X511592Y362447D03*
X514972Y368296D03*
X508212Y364396D03*
X504832Y370247D03*
X508212Y376096D03*
X501452Y372197D03*
X498072Y378047D03*
X494692Y379996D03*
Y387796D03*
X518352Y350747D03*
Y354647D03*
X511592Y358547D03*
X514972Y360496D03*
Y364396D03*
X511592Y366347D03*
X508212Y368296D03*
Y372197D03*
X504832Y374146D03*
X501452Y376096D03*
X498072Y381947D03*
X494692Y383896D03*
X518352Y346847D03*
X521731Y352696D03*
X511592Y354647D03*
X498072Y370247D03*
Y374146D03*
X504832Y393647D03*
X511592D03*
X501452Y387796D03*
X511592Y385847D03*
X518352D03*
Y381947D03*
Y378047D03*
X508212Y395597D03*
X504832Y389747D03*
X508212Y391696D03*
X504832Y385847D03*
X511592Y381947D03*
X514972Y383896D03*
X521731Y379996D03*
X518352Y374146D03*
X525111Y401447D03*
X528491Y395597D03*
X535251Y399496D03*
X531871Y393647D03*
X538631Y389747D03*
Y385847D03*
X518352Y401447D03*
X528491Y399496D03*
X531871Y397546D03*
X535251Y395597D03*
Y391696D03*
Y387796D03*
X528491D03*
X521731D03*
Y391696D03*
X518352Y393647D03*
X514972Y395597D03*
X511592Y389747D03*
X528491Y379996D03*
Y383896D03*
X525111Y385847D03*
X521731Y383896D03*
X525111Y389747D03*
X521731Y395597D03*
X514972Y391696D03*
Y387796D03*
X528491Y376096D03*
X531871Y381947D03*
X535251Y348796D03*
X538631Y346847D03*
X525111Y370247D03*
X531871D03*
X525111Y362447D03*
X528491Y360496D03*
Y356596D03*
X535251Y352696D03*
X525111Y378047D03*
Y374146D03*
Y366347D03*
X528491Y368296D03*
X521731Y364396D03*
X525111Y358547D03*
X531871Y354647D03*
Y350747D03*
X521731Y376096D03*
X528491Y372197D03*
X538631Y354647D03*
Y358547D03*
Y362447D03*
X531871D03*
Y366347D03*
X535251Y372197D03*
Y376096D03*
Y379996D03*
X538631Y350747D03*
X535251Y360496D03*
X531871Y358547D03*
X535251Y364396D03*
Y368296D03*
X538631Y374146D03*
X531871Y378047D03*
X525111Y346847D03*
X528491Y348796D03*
Y352696D03*
X487932Y356596D03*
X491312Y354647D03*
X511592Y401447D03*
X508212Y383896D03*
X514972Y376096D03*
X487932Y352696D03*
X484552Y354647D03*
Y350747D03*
Y358547D03*
X487932Y348796D03*
X545391Y335147D03*
Y331247D03*
Y339047D03*
Y346847D03*
Y350747D03*
X477792Y307851D03*
X481172Y309797D03*
X477792Y303947D03*
X481172Y313696D03*
Y305896D03*
X491312Y300047D03*
X487932Y309797D03*
X498072Y303947D03*
X501452Y298096D03*
X514972Y294196D03*
X531871Y288347D03*
X528491Y286396D03*
X538631Y284447D03*
X487932Y305896D03*
X491312Y303947D03*
X484552D03*
X494692Y301996D03*
X487932D03*
X542011Y286396D03*
X535251D03*
X484552Y311747D03*
X504832Y300045D03*
X521731Y294196D03*
X525111Y288347D03*
X528491Y290296D03*
X525111Y292245D03*
X521731Y290296D03*
X518352Y292245D03*
X498072Y300047D03*
X508212Y298096D03*
X511592Y296147D03*
X501452Y301996D03*
X484552Y307847D03*
X491312D03*
X494692Y305896D03*
X599773Y199596D03*
X563800Y275900D03*
X559211Y280547D03*
X548771Y282496D03*
X555531Y278596D03*
Y282496D03*
X552151Y280547D03*
Y284447D03*
X545391D03*
X538631Y225947D03*
Y237647D03*
Y249347D03*
X535251Y235696D03*
Y247396D03*
Y251296D03*
X542011Y239596D03*
X535251D03*
X542011Y247396D03*
X535251Y259096D03*
X531871Y261047D03*
Y268847D03*
Y276646D03*
X535251Y266896D03*
X538631Y257147D03*
X542011Y274696D03*
X531871Y257147D03*
X535251Y243496D03*
X542011Y266896D03*
X538631Y272747D03*
X531871D03*
X538631Y276646D03*
X535251Y278596D03*
X538631Y241547D03*
X542011Y243496D03*
Y251296D03*
Y255196D03*
Y262996D03*
X538631Y261047D03*
X531871Y245447D03*
X538631Y264947D03*
Y268847D03*
X535251Y270796D03*
Y274696D03*
X538631Y245447D03*
Y253247D03*
X542011Y259096D03*
X535251Y262996D03*
X542011Y227896D03*
Y235696D03*
X535251Y231797D03*
Y227896D03*
X531871Y229847D03*
X542011Y231797D03*
X538631Y233746D03*
Y229847D03*
X531871Y233746D03*
Y253247D03*
X555531Y216196D03*
X558911Y222047D03*
X562591Y220096D03*
X545391Y222047D03*
X552151Y218147D03*
X555531Y220096D03*
X548771D03*
X552151Y222047D03*
Y225947D03*
Y233746D03*
X548771Y235696D03*
X558911Y229847D03*
X552151D03*
X564084Y235685D03*
X545391Y225947D03*
Y233746D03*
X552151Y241547D03*
X548771Y239596D03*
X552151Y249347D03*
X555531Y247396D03*
X562591Y251296D03*
X548771Y243496D03*
X552151Y257147D03*
X562591Y255196D03*
X548771D03*
Y266896D03*
X558911Y264947D03*
X552151Y261047D03*
X545391Y272747D03*
Y264947D03*
Y268847D03*
Y245447D03*
Y253247D03*
X548771Y259096D03*
X545391Y241547D03*
X548771Y247396D03*
X545391Y249347D03*
Y257147D03*
Y261047D03*
Y229847D03*
X548771Y231797D03*
X562616Y223996D03*
X555531Y259096D03*
Y266896D03*
X552151Y268847D03*
X562640Y231735D03*
X555531Y243496D03*
X552151Y253247D03*
X558911Y249347D03*
Y257147D03*
Y225947D03*
X555531Y262996D03*
X552151Y264947D03*
X562630Y227896D03*
X558911Y241547D03*
X555531Y251296D03*
X558911Y253247D03*
X555531Y255196D03*
Y227896D03*
Y223996D03*
X548771D03*
X511592Y307847D03*
Y315647D03*
X538631Y311747D03*
X531871Y303947D03*
Y311747D03*
Y307847D03*
X535251Y309797D03*
X514972Y317596D03*
X518352Y315647D03*
X521731Y317596D03*
X525111Y315647D03*
X528491Y317596D03*
X538631Y319547D03*
X531871Y315647D03*
X511592Y311747D03*
X542011Y313696D03*
Y309797D03*
X538631Y307847D03*
Y303947D03*
X535251Y317596D03*
X542011D03*
Y305896D03*
X535251D03*
Y313696D03*
X538631Y315647D03*
X545391Y307847D03*
X555831Y309797D03*
Y305896D03*
X548771Y309797D03*
X545391Y303947D03*
X548771Y313696D03*
X561971Y317320D03*
X558911Y335147D03*
X555531Y333196D03*
X558911Y342947D03*
X562591Y333196D03*
Y344896D03*
X561966Y325502D03*
X559211Y319547D03*
X552151Y323446D03*
X545391Y319547D03*
Y315647D03*
X555531Y340996D03*
X545391Y311747D03*
X552151Y319547D03*
Y315647D03*
Y311747D03*
X548771Y305896D03*
X562591Y340996D03*
X558911Y339047D03*
X559211Y331103D03*
X555531Y329296D03*
X559211Y323446D03*
X555531Y321496D03*
X548771Y317596D03*
X555831Y313696D03*
X552151Y307847D03*
Y303947D03*
X555531Y344896D03*
X562591Y337096D03*
X555531D03*
X559211Y327347D03*
X555531Y325396D03*
X555831Y317446D03*
X559212Y370247D03*
X548771Y368296D03*
X562591Y352696D03*
X563200Y356596D03*
X559212Y374146D03*
X555531Y387797D03*
X559212Y381947D03*
Y393647D03*
X552151Y378047D03*
X559212Y385847D03*
X552151Y393647D03*
X548771Y387796D03*
X552151Y385847D03*
X559212Y389747D03*
X555531Y352696D03*
Y348796D03*
X552151Y354647D03*
X558911Y350747D03*
X552151Y374146D03*
X548771Y364396D03*
Y360496D03*
Y383896D03*
Y376096D03*
Y372196D03*
X552151Y358547D03*
X548771Y379996D03*
X559211Y366347D03*
X552151D03*
Y370247D03*
X555531Y379996D03*
X552151Y381947D03*
X558911Y354647D03*
X563500Y360500D03*
X552151Y362447D03*
X555531Y372197D03*
X548990Y403670D03*
X555750Y399770D03*
X690000Y15300D03*
X680200Y13100D03*
X722050Y221150D03*
X720369Y205199D03*
X742937Y218574D03*
X742897Y229573D03*
X686375Y527778D03*
X684500Y532900D03*
X930987Y275409D03*
X937747D03*
Y271509D03*
X934367Y277360D03*
X930987Y271509D03*
X934367Y273460D03*
X927607Y269560D03*
X924227Y267609D03*
X934367Y265660D03*
X924227Y275409D03*
X927607Y277360D03*
X920847Y273460D03*
X968166Y277360D03*
X951267Y275409D03*
X961406Y277360D03*
X968166Y269560D03*
X974926Y265660D03*
X954647Y277360D03*
Y265660D03*
X951267Y267609D03*
X954647Y273460D03*
X958026Y275409D03*
X954647Y269560D03*
X961406D03*
X964786Y283209D03*
X971546D03*
Y275409D03*
X974926Y269560D03*
X941127Y277360D03*
Y265660D03*
X944507Y275409D03*
X941127Y269560D03*
X947887Y277360D03*
Y265660D03*
X964786Y279310D03*
X974926Y273460D03*
Y281260D03*
X968166D03*
X930987Y267609D03*
X934367Y269560D03*
X937747Y267609D03*
X927607Y265660D03*
X964786Y275409D03*
Y267609D03*
Y271509D03*
X961406Y265660D03*
Y273460D03*
X971546Y267609D03*
Y271509D03*
X958026Y267609D03*
Y271509D03*
X968166Y265660D03*
Y273460D03*
X944507Y267609D03*
X947887Y269560D03*
X951267Y271509D03*
X947887Y273460D03*
X941127D03*
X927607D03*
X974926Y277360D03*
X971546Y279310D03*
X944507Y271509D03*
X924227D03*
X934367Y285160D03*
Y300760D03*
X927607D03*
Y308560D03*
X934367D03*
X927607Y285160D03*
Y292959D03*
X934367D03*
X927607Y316360D03*
X961406Y292959D03*
Y285160D03*
X954647Y292959D03*
Y285160D03*
X968166Y292959D03*
Y300760D03*
X971546Y310509D03*
X964786D03*
X954647Y308560D03*
X961406D03*
X954647Y300760D03*
X961406D03*
X974926D03*
X947887Y308560D03*
X941127D03*
Y300760D03*
X947887D03*
X941127Y285160D03*
Y292959D03*
X947887D03*
Y285160D03*
X974926Y292959D03*
Y312460D03*
X968166D03*
X964786Y314409D03*
X971546D03*
X981686Y269560D03*
Y281260D03*
X995206Y269560D03*
X985066Y267609D03*
X988446Y265660D03*
X991826Y271509D03*
X995206Y273460D03*
X991826Y283209D03*
Y279310D03*
Y275409D03*
X988446Y281260D03*
X985066Y283209D03*
X978306D03*
Y267609D03*
X995206Y265660D03*
X991826Y267609D03*
X981686Y265660D03*
X988446Y269560D03*
X985066Y271509D03*
X978306D03*
X988446Y273460D03*
X981686D03*
X985066Y275409D03*
X978306D03*
X988446Y277360D03*
X981686D03*
X985066Y279310D03*
X978306D03*
X981686Y292959D03*
Y300760D03*
X988446D03*
X978306Y310509D03*
X991826D03*
X985066D03*
X988446Y292959D03*
X995206Y328060D03*
X981686Y312460D03*
X988446D03*
X991826Y314409D03*
X995206Y324160D03*
X988446Y316360D03*
X991826Y318309D03*
X995206Y320260D03*
X991826Y322209D03*
X988446Y320260D03*
X978306Y314409D03*
X985066D03*
X1044256Y338341D03*
X1089101Y233746D03*
Y237647D03*
X1095861D03*
Y245447D03*
X1092481Y243496D03*
X1085721Y251296D03*
Y243496D03*
X1089101Y241547D03*
X1099241Y251296D03*
Y247396D03*
X1089101Y253247D03*
X1092481Y255196D03*
X1099241D03*
Y259096D03*
X1095861Y257147D03*
X1085721Y235696D03*
Y239596D03*
X1095861Y233746D03*
Y241547D03*
X1092481Y235696D03*
Y239596D03*
X1099241Y243496D03*
Y235696D03*
Y239596D03*
X1147680Y222047D03*
X1157820Y220096D03*
X1154440Y214247D03*
X1151060Y220096D03*
X1157820Y216196D03*
X1154440Y218147D03*
Y222047D03*
X1161200Y214247D03*
X1109381Y233746D03*
X1116141Y237647D03*
X1109381D03*
X1102621D03*
Y245447D03*
X1112761Y251296D03*
X1116141Y245447D03*
X1106001Y243496D03*
X1112761D03*
X1109381Y241547D03*
X1106001Y251296D03*
X1119521Y247396D03*
Y251296D03*
X1116141Y264947D03*
X1106001Y262996D03*
Y259096D03*
X1119521Y255196D03*
X1102621Y261047D03*
Y257147D03*
X1109381Y261047D03*
X1116141Y257147D03*
X1112761Y259096D03*
X1129660Y237647D03*
X1122900D03*
X1129660Y233746D03*
Y241547D03*
X1126280Y251296D03*
Y243496D03*
X1122900Y245447D03*
X1144300Y243496D03*
X1151060Y247396D03*
X1154440Y245447D03*
X1144300Y247396D03*
X1136420Y245447D03*
X1154440Y241547D03*
X1136420D03*
X1157820Y239596D03*
X1144300Y235696D03*
X1136420Y233746D03*
Y237647D03*
X1133040Y235696D03*
Y243496D03*
Y251296D03*
X1147680Y225947D03*
X1151060Y223996D03*
X1147680Y233746D03*
X1154440Y229847D03*
X1157820Y223996D03*
Y231797D03*
X1129660Y261047D03*
X1126280Y259096D03*
X1122900Y257147D03*
X1133040Y259096D03*
X1136420Y257147D03*
X1151060Y251296D03*
X1116141Y233746D03*
Y241547D03*
X1126280Y235696D03*
Y239596D03*
X1112761Y235696D03*
Y239596D03*
X1122900Y233746D03*
Y241547D03*
X1119521Y243496D03*
Y235696D03*
Y239596D03*
X1106001Y235696D03*
Y239596D03*
X1102621Y233746D03*
Y241547D03*
X1106001Y247396D03*
Y255196D03*
X1116141Y249347D03*
Y253247D03*
X1102621Y249347D03*
Y253247D03*
X1112761Y247396D03*
Y255196D03*
X1126280Y247396D03*
Y255196D03*
X1136420Y249347D03*
Y253247D03*
X1122900Y249347D03*
Y253247D03*
X1133040Y247396D03*
Y255196D03*
X1109381Y245447D03*
X1129660D03*
X1109381Y257147D03*
X1129660D03*
X1109381Y249347D03*
X1129660D03*
X1109381Y253247D03*
X1129660D03*
X1154440Y249347D03*
X1157820Y247396D03*
X1109381Y264947D03*
X1151060Y243496D03*
X1144300Y239596D03*
X1151060Y235696D03*
X1144300Y227896D03*
X1154440Y233746D03*
X1147680Y229847D03*
X1154440Y237647D03*
X1157820Y227896D03*
X1147680Y241547D03*
Y237647D03*
X1151060Y239596D03*
X1144300Y231797D03*
X1151060D03*
Y227896D03*
X1157820Y235696D03*
X1161200Y237647D03*
X1119521Y262996D03*
X1122900Y261047D03*
X1119521Y259096D03*
X1157820Y243496D03*
X1133040Y239596D03*
X1122900Y264947D03*
X1126280Y262996D03*
X1167960Y218147D03*
X1174719D03*
X1171339Y220096D03*
X1178099Y216196D03*
Y220096D03*
X1161200Y218147D03*
X1181479Y222047D03*
X1188239D03*
X1201759Y218147D03*
X1198379Y212296D03*
X1194999Y210346D03*
Y222047D03*
X1188239Y214247D03*
X1181479D03*
X1184859Y220096D03*
X1191619Y216196D03*
X1194999Y214247D03*
Y218147D03*
X1198379Y220096D03*
X1201759Y222047D03*
X1167960Y214247D03*
X1184859Y216196D03*
X1188239Y218147D03*
X1191619Y220096D03*
Y212296D03*
X1198379Y216196D03*
X1205139Y220096D03*
X1164580Y216196D03*
X1174719Y214247D03*
Y222047D03*
X1164580Y235696D03*
X1167960Y229847D03*
X1164580Y223996D03*
Y227896D03*
Y239596D03*
X1178099Y247396D03*
X1161200Y241547D03*
X1171339Y247396D03*
X1178099Y243496D03*
X1171339Y235696D03*
Y231797D03*
X1178099Y227896D03*
Y235696D03*
X1174719Y237647D03*
X1191619Y239596D03*
X1188239Y225947D03*
X1184859Y235696D03*
X1188239Y237647D03*
X1184859Y247396D03*
X1188239Y249347D03*
X1201759Y229847D03*
Y225947D03*
Y233746D03*
X1198379Y235696D03*
Y243496D03*
X1201759Y241547D03*
Y249347D03*
X1198379Y239596D03*
X1194999Y225947D03*
Y233746D03*
X1184859Y239596D03*
Y251296D03*
X1208519Y233746D03*
X1188239Y257147D03*
X1198379Y255196D03*
X1201759Y257147D03*
X1161200Y245447D03*
X1164580Y243496D03*
X1181479Y257147D03*
X1167960Y241547D03*
Y245447D03*
Y237647D03*
X1171339Y239596D03*
Y243496D03*
X1174719Y241547D03*
X1178099Y239596D03*
X1174719Y249347D03*
Y245447D03*
X1205139Y255196D03*
X1208519Y249347D03*
X1201759Y253247D03*
X1205139Y243496D03*
Y235696D03*
X1208519Y225947D03*
Y253247D03*
X1205139Y251296D03*
X1208519Y241547D03*
Y237647D03*
X1205139Y239596D03*
Y223996D03*
X1198379D03*
X1205139Y227896D03*
X1194999Y257147D03*
X1188239Y253247D03*
X1194999Y249347D03*
X1198379Y247396D03*
X1191619Y243496D03*
X1188239Y241547D03*
X1181479Y245447D03*
X1191619Y255196D03*
Y251296D03*
X1194999Y253247D03*
Y245447D03*
Y241547D03*
X1188239Y245447D03*
X1184859Y243496D03*
X1174719Y229847D03*
X1167960Y225947D03*
X1174719Y233746D03*
X1181479Y229847D03*
X1184859Y227896D03*
Y231797D03*
X1191619Y235696D03*
Y227896D03*
X1198379Y231797D03*
X1161200Y233746D03*
Y229847D03*
X1171339Y227896D03*
Y223996D03*
X1174719Y225947D03*
X1178099Y231797D03*
X1181479Y233746D03*
Y225947D03*
X1188239Y229847D03*
Y233746D03*
X1191619Y231797D03*
X1194999Y229847D03*
X1161200Y225947D03*
X1164580Y231797D03*
X1181479Y253247D03*
X1178099Y251296D03*
X1208519Y229847D03*
X1130780Y290296D03*
X1151060D03*
X1134160Y292247D03*
X1140920D03*
Y288347D03*
X1147680D03*
X1151060Y286396D03*
X1144300Y290296D03*
X1147680Y292247D03*
X1154440Y288347D03*
Y284447D03*
X1157820Y286396D03*
X1130780Y294196D03*
X1127400Y296147D03*
Y292247D03*
X1137540Y290296D03*
X1134160Y288347D03*
X1161200D03*
X1174719Y280547D03*
X1208519Y272747D03*
X1212199Y274696D03*
X1205139D03*
X1164580Y282496D03*
X1167960Y280547D03*
X1171339Y282496D03*
X1178099Y278596D03*
X1194999Y276646D03*
X1171339Y278596D03*
X1205139D03*
X1201759Y276646D03*
X1178099Y282496D03*
X1184859Y278596D03*
X1188239Y280547D03*
X1181479D03*
X1184859Y282496D03*
X1191619Y278596D03*
X1164580Y286396D03*
X1161200Y284447D03*
X1167960D03*
X1540700Y410450D03*
X1551875Y436786D03*
X1549925Y440166D03*
X1551875Y443546D03*
X1651536Y128089D03*
X1638250Y125750D03*
X1645378Y128378D03*
X1629489Y131239D03*
Y143837D03*
Y137538D03*
X1623190Y140687D03*
Y146987D03*
X1637363Y149484D03*
X1720164Y97550D03*
X1742214Y111150D03*
X1751800Y141700D03*
X1752889Y146250D03*
X1754189Y124250D03*
X1752389Y132250D03*
X1752189Y136750D03*
X1755089Y150750D03*
X1754600Y109200D03*
X1745364Y114300D03*
X1748425Y119190D03*
X1745500Y104500D03*
X1887497Y105444D03*
X1881165Y105561D03*
X1876001Y105438D03*
X1882677Y447930D03*
G54D49*
X1472000Y-15000D03*
X1462000Y-5000D03*
Y-15000D03*
X1452000Y-5000D03*
Y-15000D03*
X1442000Y-5000D03*
Y-15000D03*
X1525000D03*
X1515000D03*
X1505000D03*
X1482000D03*
X1492000D03*
X1545000D03*
X1535000D03*
G54D43*
X24400Y519500D03*
G54D36*
X40500Y-42250D03*
Y-52250D03*
X467246Y-52301D03*
Y-42301D03*
X798984Y-52057D03*
Y-42057D03*
X1135583Y-52285D03*
Y-42285D03*
X1155583Y-52285D03*
Y-42285D03*
X1392258Y-52257D03*
Y-42257D03*
X1412258Y-52257D03*
Y-42257D03*
X1432258Y-52257D03*
Y-42257D03*
X1452258Y-52257D03*
Y-42257D03*
G54D46*
X638541Y171945D03*
G54D41*
X40512Y458744D03*
G54D37*
X-7874Y216181D03*
Y325315D03*
G54D38*
X18228Y178386D03*
G54D35*
X-3937Y-43307D03*
X1956693D03*
X-3937Y646063D03*
X1956693D03*
G54D45*
X224410Y301378D03*
X602362Y387992D03*
X874016Y301378D03*
%LPD*%
G75*
G36*
G01X573530Y228130D02*
G03I-600J0D01*
G37*
G36*
G01Y232750D02*
G03I-600J0D01*
G37*
G36*
G01X1242512Y187710D02*
G03I-800J0D01*
G37*
G36*
G01X1903400Y122500D02*
Y135250D01*
X1913800D01*
Y122500D01*
X1903400D01*
G37*
G54D10*
X-17936Y-49379D03*
Y-53779D03*
Y-44979D03*
Y-40579D03*
X-18079Y-35764D03*
Y-58764D03*
X-14186Y196989D03*
Y199989D03*
X-17179Y643156D03*
X-17194Y638753D03*
X-17179Y647556D03*
Y660756D03*
Y651956D03*
Y656356D03*
X-13636Y-40479D03*
Y-44879D03*
Y-53679D03*
X-9079Y-50164D03*
X-4679D03*
X-279D03*
X-9079Y-54264D03*
X-4679D03*
X-279D03*
X22964Y-40379D03*
Y-44779D03*
Y-53579D03*
Y-49179D03*
X18964Y-53579D03*
Y-49179D03*
X13964Y-53579D03*
Y-49179D03*
X8964Y-40379D03*
Y-44779D03*
Y-53579D03*
Y-49179D03*
X3964Y-40379D03*
Y-44779D03*
Y-53579D03*
Y-49179D03*
X25921Y-35764D03*
X30321D03*
X43521D03*
X39121D03*
X34721D03*
X8321D03*
X12721D03*
X21521D03*
X17121D03*
X-13679D03*
X-9279D03*
X3921D03*
X-4879D03*
X-479D03*
X17121Y-58764D03*
X21521D03*
X12721D03*
X8321D03*
X34721D03*
X39121D03*
X43521D03*
X30321D03*
X25921D03*
X-479D03*
X-13679D03*
X-4879D03*
X3921D03*
X-13636Y-49279D03*
X-9279Y-58764D03*
X875Y211336D03*
X6074Y211293D03*
X3474Y211263D03*
X875Y208352D03*
X36200Y208600D03*
X33200D03*
X20700D03*
X17700Y211600D03*
X20700D03*
X17700Y208600D03*
X23700Y211600D03*
Y208600D03*
X33200Y211600D03*
X30200D03*
Y208600D03*
X36200Y211600D03*
X6074Y208321D03*
X3474Y208263D03*
X5500Y218500D03*
X-5300Y200191D03*
X-7900D03*
X-2700Y200202D03*
X-11586Y196989D03*
Y199989D03*
X-2600Y232300D03*
X-5246Y232351D03*
X-7846D03*
X20500Y221000D03*
Y224000D03*
X17500Y221000D03*
Y224000D03*
X23500D03*
Y221000D03*
X33300Y224000D03*
Y221000D03*
X30300D03*
Y224000D03*
X36300D03*
Y221000D03*
X-14129Y235221D03*
X-11484Y235215D03*
Y232215D03*
X-14084D03*
X2678Y221018D03*
X5277Y221110D03*
X5173Y224042D03*
X2574Y223963D03*
X-26Y223982D03*
X28868Y457576D03*
Y454576D03*
X28988Y460876D03*
X23718Y460866D03*
X26318D03*
X21118D03*
X20998Y457566D03*
Y454566D03*
X23598D03*
X26198D03*
Y457566D03*
X23598D03*
X22421Y647556D03*
X26821D03*
X31221D03*
X18021D03*
Y643156D03*
X31221D03*
X26821D03*
X22421D03*
X18006Y638753D03*
X9221Y647556D03*
X13621D03*
Y643156D03*
X9221D03*
X4821D03*
Y647556D03*
X22406Y638753D03*
X26806D03*
X31206D03*
X-12794D03*
X-12779Y647556D03*
Y643156D03*
X40006Y638753D03*
X44406D03*
X35606D03*
X35621Y647556D03*
Y643156D03*
X18021Y660756D03*
X35621Y656356D03*
X26821Y660756D03*
X18021Y651956D03*
X31221D03*
X22421Y660756D03*
X26821Y651956D03*
X22421D03*
X4821D03*
X13621D03*
X9221D03*
X-8379Y660756D03*
X4821Y656356D03*
X9221D03*
X13621D03*
X-3979D03*
X421D03*
X13621Y660756D03*
X-3979D03*
X421D03*
X4821D03*
X-12779Y651956D03*
X22421Y656356D03*
X26821D03*
X31221D03*
X18021D03*
X-8379D03*
X-12779D03*
X31221Y660756D03*
X35621Y651956D03*
Y660756D03*
X44421D03*
X40021D03*
X-12779D03*
X9221D03*
X107921Y-58764D03*
X102921D03*
X97921D03*
X92921D03*
X87921D03*
X82921D03*
X77921D03*
X72921D03*
X67921D03*
X62921D03*
X57921D03*
X52921D03*
X47921Y-35764D03*
Y-58764D03*
X107921Y-35764D03*
X102921D03*
X97921D03*
X92921D03*
X87921D03*
X82921D03*
X77921D03*
X72921D03*
X67921D03*
X62921D03*
X57921D03*
X52921D03*
X50500Y205696D03*
X58200Y230400D03*
Y233400D03*
X55600Y230400D03*
X53000Y230300D03*
Y233300D03*
X55600Y233400D03*
X58200Y227400D03*
X53000Y227300D03*
X55600Y227400D03*
X58200Y239400D03*
X53000Y239300D03*
X55600Y239400D03*
X58200Y236400D03*
X55600D03*
X53000Y236300D03*
X71500Y263300D03*
X68800D03*
X53004Y244632D03*
X55275Y245900D03*
X57875D03*
X57457Y248537D03*
Y251237D03*
X57600Y262800D03*
X57500Y260200D03*
X62800Y265500D03*
X71500Y266000D03*
X65500Y265500D03*
X68800Y266000D03*
X60000Y265500D03*
X48806Y638753D03*
X75206D03*
X106006D03*
X70806D03*
X53206D03*
X66406D03*
X92806D03*
X97206D03*
X101606D03*
X57606D03*
X62006D03*
X79606D03*
X84006D03*
X88406D03*
X53221Y660756D03*
X101621D03*
X97221D03*
X92821D03*
X106021D03*
X48821D03*
X70821D03*
X66421D03*
X62021D03*
X57621D03*
X75221D03*
X88421D03*
X84021D03*
X79621D03*
X167921Y-58764D03*
X162921D03*
X157921D03*
X152921D03*
X147921D03*
X142921D03*
X137921D03*
X132921D03*
X127921D03*
X122921D03*
X117921D03*
X112921D03*
X162921Y-35764D03*
X157921D03*
X152921D03*
X147921D03*
X142921D03*
X137921D03*
X132921D03*
X127921D03*
X122921D03*
X117921D03*
X112921D03*
X167921D03*
X166000Y212900D03*
X168600D03*
X164300Y207870D03*
X160800Y212900D03*
X163400D03*
X157800Y207300D03*
X161216Y209533D03*
Y206933D03*
X154500Y205500D03*
X150600Y212900D03*
X151000Y205500D03*
X140889Y211972D03*
X137615Y212039D03*
X143900Y204600D03*
X147500Y205500D03*
X153200Y212900D03*
X139815Y268974D03*
X137900Y272800D03*
X139800Y237000D03*
X165825Y239543D03*
X168425Y236943D03*
Y239543D03*
X165825Y236943D03*
X163225D03*
X152825D03*
X145025D03*
X147625D03*
X150225D03*
X142425D03*
X163225Y239543D03*
X158025Y236943D03*
X155425D03*
X160625D03*
X142371Y244384D03*
X142466Y268982D03*
X142700Y276200D03*
X136729Y276386D03*
X139683Y276174D03*
X163225Y242143D03*
X168425Y244743D03*
X165825D03*
X163225D03*
X168425Y242143D03*
X165825D03*
X150700Y276800D03*
X157633Y268727D03*
X162833D03*
X160233D03*
X165433D03*
X168033Y271327D03*
X162833Y276527D03*
Y273927D03*
Y271327D03*
X165433Y276527D03*
Y273927D03*
Y271327D03*
X159983Y276507D03*
X168033Y276527D03*
Y273927D03*
Y268727D03*
X153300Y276800D03*
X139866Y333016D03*
X160233Y306257D03*
Y308857D03*
Y303657D03*
X157518Y335391D03*
X157745Y332800D03*
X139900Y302400D03*
X142433Y301057D03*
X147633D03*
X150233D03*
X145033D03*
X145200Y341300D03*
X148200D03*
X142465Y332940D03*
X152833Y301057D03*
X163233Y306257D03*
Y308857D03*
X168433Y306257D03*
Y308857D03*
Y301057D03*
X165833D03*
X163233D03*
X160633D03*
X158033D03*
X155433D03*
X165833Y306257D03*
X163233Y303657D03*
X168433D03*
X165833D03*
Y308857D03*
X151000Y341300D03*
X160501Y332965D03*
X160274Y335556D03*
X165701Y338165D03*
Y335565D03*
X163101Y332965D03*
X168301D03*
X165701D03*
X163101Y335565D03*
X168301Y340765D03*
Y338165D03*
Y335565D03*
X163101Y338165D03*
Y340765D03*
X165701D03*
X154200Y341100D03*
X139767Y364883D03*
X147833Y364457D03*
X142421Y364908D03*
X145033Y364457D03*
X142863Y402829D03*
X140219Y402894D03*
X137619Y402900D03*
X134992D03*
X142818Y400163D03*
X143073Y397194D03*
X140475Y397310D03*
X140218Y400163D03*
X137529Y400296D03*
X134929D03*
X150633Y364457D03*
X167433Y369657D03*
X167700Y363900D03*
X161833Y364457D03*
X164633D03*
X159033D03*
X156233D03*
X153433D03*
X164633Y369657D03*
X161833D03*
X161933Y372357D03*
X164733D03*
X167533D03*
X166340Y374785D03*
X167670Y383993D03*
Y387993D03*
X110406Y638753D03*
X145606D03*
X141206D03*
X136806D03*
X132406D03*
X158806D03*
X119206D03*
X123606D03*
X114806D03*
X128006D03*
X163206D03*
X154406D03*
X167606D03*
X150006D03*
X132421Y660756D03*
X145621D03*
X141221D03*
X136821D03*
X123621D03*
X114821D03*
X128021D03*
X110421D03*
X119221D03*
X150021D03*
X167621D03*
X163221D03*
X158821D03*
X154421D03*
X182921Y-58764D03*
X177921D03*
X172921D03*
X227921Y-35764D03*
X222921D03*
X217921D03*
X212921D03*
X207921D03*
X202921D03*
X197921D03*
X192921D03*
X187921D03*
X182921D03*
X177921D03*
X227921Y-58764D03*
X222921D03*
X217921D03*
X212921D03*
X207921D03*
X202921D03*
X197921D03*
X192921D03*
X187921D03*
X172921Y-35764D03*
X176300Y211900D03*
X182300Y216108D03*
X179300D03*
Y213208D03*
X176300Y217308D03*
Y214500D03*
X173300Y217700D03*
Y214800D03*
Y211900D03*
X176400Y234300D03*
X176508Y231609D03*
X179400Y234300D03*
X182400D03*
X176400Y239900D03*
X182400D03*
X179400D03*
X173400D03*
Y231400D03*
Y234300D03*
Y237000D03*
X176400D03*
X182400D03*
X179400D03*
X188200Y236800D03*
X188300Y234000D03*
X185250Y239850D03*
X204200Y249500D03*
X201100Y246500D03*
X198200Y249500D03*
Y246500D03*
X201200Y249500D03*
X203900Y246500D03*
X207200Y249500D03*
X185768Y270065D03*
X173835Y277804D03*
X198082Y277995D03*
X203847Y274933D03*
X203947Y277933D03*
X188510Y272666D03*
X176835Y277804D03*
X182935Y278204D03*
Y275604D03*
X191400Y278400D03*
X188475Y270065D03*
X185735Y275604D03*
X188600Y278300D03*
X188535Y275604D03*
X185735Y278204D03*
X195300Y229250D03*
X188100Y239800D03*
X185250Y234250D03*
Y236950D03*
X176835Y275204D03*
X185754Y272689D03*
X179835Y277804D03*
Y275204D03*
X195100Y252000D03*
X201200Y252500D03*
X198200D03*
X204200D03*
X207200D03*
X200947Y277933D03*
X200847Y274933D03*
X200947Y280933D03*
X173835Y275204D03*
X230800Y265200D03*
X224390Y258920D03*
X219500Y254500D03*
X190800Y295500D03*
X196956Y295583D03*
X193800Y295500D03*
X190665Y306877D03*
X198119Y339710D03*
X191792Y327743D03*
X197792Y327643D03*
X194792D03*
X184800Y295500D03*
X187956Y295583D03*
X181800Y295500D03*
X201177Y330728D03*
Y333728D03*
Y336728D03*
X201163Y339476D03*
Y342476D03*
X204177Y336728D03*
X204060Y342527D03*
X204163Y339476D03*
X188654Y330973D03*
Y327973D03*
X197684Y307227D03*
X200251Y306548D03*
X188630Y333923D03*
X190570Y309539D03*
X185630Y333923D03*
X172800Y295500D03*
Y298400D03*
X198182Y280995D03*
X178956Y295583D03*
X175800Y295500D03*
X187900Y306900D03*
X191300Y339800D03*
X172800Y304000D03*
X175800D03*
X178800D03*
X187800D03*
X181800D03*
X184800D03*
X172800Y301100D03*
X175800D03*
X178800D03*
X181800D03*
X187800D03*
X184800D03*
Y298400D03*
X181800D03*
X175800D03*
X178800D03*
X187800D03*
X185300Y336900D03*
X173300Y337000D03*
Y339900D03*
X188300D03*
Y336900D03*
X179300Y337000D03*
X176300Y339900D03*
X179300D03*
X182300D03*
Y337000D03*
X198223Y342430D03*
X176300Y337000D03*
X185300Y339900D03*
X224000Y330900D03*
X229100Y325900D03*
X219000Y335900D03*
X214000Y340900D03*
X197730Y309959D03*
X204060Y345527D03*
X191300Y343248D03*
X173300Y343448D03*
X188300Y343348D03*
X201045Y345449D03*
X198233Y345402D03*
X195233D03*
X176300Y343448D03*
X201045Y348449D03*
X198233Y348402D03*
Y351402D03*
X195233D03*
X173424Y359621D03*
X188424D03*
X182424D03*
X185424D03*
X176424D03*
X179424D03*
X182300Y343448D03*
X173471Y363281D03*
X188471D03*
X182471D03*
X185471D03*
X176471D03*
X179471D03*
X179300Y343448D03*
X185300Y343348D03*
X211606Y638753D03*
X224806D03*
X220406D03*
X216006D03*
X189606D03*
X198406D03*
X202806D03*
X207206D03*
X176406D03*
X172006D03*
X185206D03*
X180806D03*
X194006D03*
X226500Y649900D03*
X229206Y638753D03*
X224821Y660756D03*
X220421D03*
X198421D03*
X211621D03*
X189621D03*
X202821D03*
X207221D03*
X194021D03*
X185221D03*
X172021D03*
X176421D03*
X180821D03*
X229221D03*
X216021D03*
X292921Y-35764D03*
X287921D03*
X282921D03*
X277921D03*
X272921D03*
X267921D03*
X262921D03*
X257921D03*
X252921D03*
X247921D03*
X242921D03*
X237921D03*
X232921D03*
X292921Y-58764D03*
X287921D03*
X282921D03*
X277921D03*
X272921D03*
X267921D03*
X262921D03*
X257921D03*
X252921D03*
X247921D03*
X242921D03*
X237921D03*
X232921D03*
X234501Y270392D03*
X234000Y320900D03*
X261125Y646784D03*
X290806Y638753D03*
X268806D03*
X273206D03*
X277606D03*
X282006D03*
X260006D03*
X264406D03*
X255606D03*
X251206D03*
X286406D03*
X242406D03*
X246806D03*
X233606D03*
X238006D03*
X261125Y652784D03*
X286421Y660756D03*
X268821D03*
X282021D03*
X273221D03*
X277621D03*
X264421D03*
X251221D03*
X255621D03*
X260021D03*
X246821D03*
X242421D03*
X238021D03*
X233621D03*
X290821D03*
X352921Y-58764D03*
Y-35764D03*
X347921Y-58764D03*
Y-35764D03*
X342921Y-58764D03*
Y-35764D03*
X337921Y-58764D03*
Y-35764D03*
X332921Y-58764D03*
Y-35764D03*
X327921Y-58764D03*
Y-35764D03*
X322921Y-58764D03*
Y-35764D03*
X317921Y-58764D03*
Y-35764D03*
X312921Y-58764D03*
X307921D03*
Y-35764D03*
X302921Y-58764D03*
Y-35764D03*
X297921D03*
Y-58764D03*
X312921Y-35764D03*
X330406Y638753D03*
X348006D03*
X326006D03*
X312806D03*
X317206D03*
X321606D03*
X352406D03*
X295206D03*
X299606D03*
X308406D03*
X304006D03*
X334806D03*
X339206D03*
X343606D03*
X312821Y660756D03*
X317221D03*
X308421D03*
X304021D03*
X352421D03*
X295221D03*
X326021D03*
X321621D03*
X339221D03*
X299621D03*
X334821D03*
X330421D03*
X343621D03*
X348021D03*
X392921Y-35764D03*
X387921Y-58764D03*
Y-35764D03*
X382921Y-58764D03*
Y-35764D03*
X377921Y-58764D03*
Y-35764D03*
X372921Y-58764D03*
Y-35764D03*
X367921Y-58764D03*
Y-35764D03*
X362921Y-58764D03*
Y-35764D03*
X357921Y-58764D03*
Y-35764D03*
X392921Y-58764D03*
X402921Y-35764D03*
X397921Y-58764D03*
Y-35764D03*
X412921Y-58764D03*
Y-35764D03*
X407921Y-58764D03*
Y-35764D03*
X402921Y-58764D03*
X385494Y309904D03*
X367914Y309910D03*
X371237Y309846D03*
X389502Y309910D03*
X389528Y292910D03*
X392694Y292904D03*
X368116Y293087D03*
X371094Y292904D03*
X373736Y293068D03*
X382625Y293207D03*
X378294Y292904D03*
X385494D03*
X392694Y309904D03*
X374994Y309910D03*
X382497D03*
X378577Y309795D03*
X407094Y292904D03*
X396897Y293058D03*
X399894Y292904D03*
X404266Y293030D03*
X407094Y309904D03*
X396709Y309910D03*
X399894Y309904D03*
X404117Y309910D03*
X379561Y646508D03*
X383206Y638753D03*
X387606D03*
X392006D03*
X396406D03*
X400806D03*
X405206D03*
X409606D03*
X414006D03*
X370006D03*
X365606D03*
X374406D03*
X378806D03*
X356806D03*
X361206D03*
X379561Y652508D03*
X374421Y660756D03*
X387621D03*
X383221D03*
X400821D03*
X396421D03*
X392021D03*
X405221D03*
X409621D03*
X414021D03*
X361221D03*
X365621D03*
X356821D03*
X370021D03*
X378821D03*
X477921Y-58764D03*
Y-35764D03*
X472921Y-58764D03*
Y-35764D03*
X467921Y-58764D03*
Y-35764D03*
X462921Y-58764D03*
Y-35764D03*
X457921Y-58764D03*
Y-35764D03*
X452921Y-58764D03*
Y-35764D03*
X447921Y-58764D03*
Y-35764D03*
X442921Y-58764D03*
Y-35764D03*
X437921Y-58764D03*
Y-35764D03*
X432921Y-58764D03*
X422921Y-35764D03*
X417921Y-58764D03*
Y-35764D03*
X432921D03*
X427921Y-58764D03*
Y-35764D03*
X422921Y-58764D03*
X436329Y264826D03*
X466806Y638753D03*
X462406D03*
X475606D03*
X471206D03*
X418406D03*
X422806D03*
X427206D03*
X440406D03*
X436006D03*
X431606D03*
X449206D03*
X458006D03*
X453606D03*
X444806D03*
X458021Y660756D03*
X449221D03*
X462421D03*
X466821D03*
X471221D03*
X418421D03*
X475621D03*
X453621D03*
X422821D03*
X427221D03*
X440421D03*
X431621D03*
X436021D03*
X444821D03*
X537921Y-58764D03*
Y-35764D03*
X532921Y-58764D03*
Y-35764D03*
X527921Y-58764D03*
Y-35764D03*
X522921Y-58764D03*
Y-35764D03*
X517921Y-58764D03*
Y-35764D03*
X512921Y-58764D03*
Y-35764D03*
X507921Y-58764D03*
Y-35764D03*
X502921Y-58764D03*
Y-35764D03*
X497921Y-58764D03*
Y-35764D03*
X492921Y-58764D03*
Y-35764D03*
X487921Y-58764D03*
Y-35764D03*
X482921Y-58764D03*
Y-35764D03*
X480006Y638753D03*
X484406D03*
X488806D03*
X493206D03*
X497606D03*
X510806D03*
X537206D03*
X519606D03*
X524006D03*
X532806D03*
X528406D03*
X515206D03*
X502006D03*
X506406D03*
X524021Y660756D03*
X480021D03*
X484421D03*
X497621D03*
X493221D03*
X488821D03*
X519621D03*
X532821D03*
X537221D03*
X528421D03*
X515221D03*
X510821D03*
X506421D03*
X502021D03*
X597921Y-35764D03*
Y-58764D03*
X592921Y-35764D03*
Y-58764D03*
X587921Y-35764D03*
Y-58764D03*
X582921Y-35764D03*
Y-58764D03*
X577921Y-35764D03*
Y-58764D03*
X572921Y-35764D03*
Y-58764D03*
X567921Y-35764D03*
Y-58764D03*
X562921Y-35764D03*
Y-58764D03*
X557921Y-35764D03*
Y-58764D03*
X552921Y-35764D03*
Y-58764D03*
X547921D03*
Y-35764D03*
X542921Y-58764D03*
Y-35764D03*
X590006Y638753D03*
X572406D03*
X559206D03*
X568006D03*
X563606D03*
X550406D03*
X581206D03*
X585606D03*
X576806D03*
X598806D03*
X594406D03*
X601500Y649500D03*
X554806Y638753D03*
X541606D03*
X546006D03*
X559221Y660756D03*
X546021D03*
X554821D03*
X598821D03*
X572421D03*
X568021D03*
X563621D03*
X585621D03*
X541621D03*
X594421D03*
X576821D03*
X590021D03*
X581221D03*
X550421D03*
X637921Y-58764D03*
X632921Y-35764D03*
Y-58764D03*
X627921Y-35764D03*
Y-58764D03*
X622921Y-35764D03*
Y-58764D03*
X617921Y-35764D03*
Y-58764D03*
X612921Y-35764D03*
Y-58764D03*
X607921Y-35764D03*
Y-58764D03*
X602921Y-35764D03*
Y-58764D03*
X652921Y-35764D03*
Y-58764D03*
X647921Y-35764D03*
Y-58764D03*
X642921Y-35764D03*
Y-58764D03*
X637921Y-35764D03*
X662921D03*
Y-58764D03*
X657921Y-35764D03*
Y-58764D03*
X638406Y638753D03*
X634006D03*
X642806D03*
X629606D03*
X616406D03*
X612006D03*
X603206D03*
X625206D03*
X651606D03*
X647206D03*
X660406D03*
X620806D03*
X656006D03*
X607606D03*
X607621Y660756D03*
X638421D03*
X647221D03*
X616421D03*
X634021D03*
X612021D03*
X620821D03*
X625221D03*
X629621D03*
X642821D03*
X603221D03*
X656021D03*
X660421D03*
X651621D03*
X692921Y-58764D03*
X687921Y-35764D03*
Y-58764D03*
X682921Y-35764D03*
Y-58764D03*
X677921Y-35764D03*
Y-58764D03*
X672921Y-35764D03*
Y-58764D03*
X667921Y-35764D03*
Y-58764D03*
X697921Y-35764D03*
Y-58764D03*
X692921Y-35764D03*
X722921D03*
Y-58764D03*
X717921Y-35764D03*
Y-58764D03*
X712921Y-35764D03*
Y-58764D03*
X707921Y-35764D03*
Y-58764D03*
X702921Y-35764D03*
Y-58764D03*
X695606Y638753D03*
X673606D03*
X708806D03*
X704406D03*
X700006D03*
X722006D03*
X717606D03*
X713206D03*
X664806D03*
X669206D03*
X686806D03*
X682406D03*
X678006D03*
X691206D03*
X664821Y660756D03*
X695621D03*
X708821D03*
X700021D03*
X704421D03*
X669221D03*
X686821D03*
X691221D03*
X678021D03*
X673621D03*
X682421D03*
X722021D03*
X717621D03*
X713221D03*
X777921Y-58764D03*
X772921Y-35764D03*
Y-58764D03*
X767921Y-35764D03*
Y-58764D03*
X762921Y-35764D03*
Y-58764D03*
X757921Y-35764D03*
Y-58764D03*
X752921Y-35764D03*
Y-58764D03*
X787921Y-35764D03*
Y-58764D03*
X782921Y-35764D03*
Y-58764D03*
X777921Y-35764D03*
X747921D03*
Y-58764D03*
X742921Y-35764D03*
Y-58764D03*
X737921Y-35764D03*
Y-58764D03*
X732921Y-35764D03*
Y-58764D03*
X727921Y-35764D03*
Y-58764D03*
X786674Y211463D03*
X785920Y204763D03*
X786300Y207400D03*
X787200Y244200D03*
Y271900D03*
X787100Y241100D03*
X787200Y276400D03*
X787100Y303900D03*
X787000Y308300D03*
X787400Y340400D03*
X785400Y372400D03*
X770406Y638753D03*
X779206D03*
X774806D03*
X730806D03*
X726406D03*
X739606D03*
X735206D03*
X748406D03*
X744006D03*
X766006D03*
X761606D03*
X757206D03*
X752806D03*
X783606D03*
X744021Y660756D03*
X735221D03*
X779221D03*
X770421D03*
X774821D03*
X726421D03*
X730821D03*
X739621D03*
X748421D03*
X783621D03*
X757221D03*
X761621D03*
X752821D03*
X766021D03*
X842921Y-35764D03*
X837921Y-58764D03*
Y-35764D03*
X832921Y-58764D03*
X847921D03*
Y-35764D03*
X842921Y-58764D03*
X832921Y-35764D03*
X827921Y-58764D03*
Y-35764D03*
X822921Y-58764D03*
Y-35764D03*
X817921Y-58764D03*
Y-35764D03*
X812921Y-58764D03*
Y-35764D03*
X807921Y-58764D03*
Y-35764D03*
X802921Y-58764D03*
Y-35764D03*
X797921D03*
Y-58764D03*
X792921Y-35764D03*
Y-58764D03*
X816900Y216300D03*
X816874Y212863D03*
X814274D03*
X811674D03*
X808818Y211179D03*
X808618Y208579D03*
X803200Y213100D03*
X800600D03*
X794474Y211463D03*
X791874D03*
X789274D03*
X788522Y204343D03*
X791122Y204339D03*
X829327Y214740D03*
X827322Y217430D03*
X826700Y214802D03*
X824072Y214865D03*
X824446Y217476D03*
X821775Y217617D03*
X821466Y214925D03*
X789432Y236947D03*
X789400Y273700D03*
X811983Y244843D03*
Y242243D03*
X814583Y239643D03*
X815432Y237000D03*
X814583Y244843D03*
Y242243D03*
X812832Y237000D03*
X811983Y239643D03*
X802432Y237000D03*
X799832D03*
X792032D03*
X794632D03*
X810232D03*
X797232D03*
X805032D03*
X807632D03*
X791000Y244400D03*
X793600D03*
X816800Y234300D03*
X816900Y230900D03*
X817000Y252500D03*
X789800Y276400D03*
X792400D03*
X801991Y276557D03*
X804591D03*
X792191Y269101D03*
X789591D03*
X814891Y271657D03*
Y274257D03*
Y276857D03*
Y269057D03*
X812291D03*
Y274257D03*
Y276857D03*
Y271657D03*
X817000Y255100D03*
Y257700D03*
X848282Y251727D03*
X828180Y231748D03*
X828682Y237027D03*
X831682D03*
X828682Y234327D03*
X837500Y239500D03*
X845050Y229400D03*
X837500Y234050D03*
Y236650D03*
X834682Y236877D03*
X840155Y234245D03*
X834700Y234200D03*
X831682Y234327D03*
X834682Y239627D03*
X831682D03*
X828682D03*
X848282Y246427D03*
Y249027D03*
X825682Y239627D03*
Y234327D03*
Y237027D03*
X825313Y231753D03*
X848382Y279727D03*
Y277027D03*
Y274427D03*
X825464Y277510D03*
Y274910D03*
Y280110D03*
X822464D03*
Y277510D03*
Y274910D03*
X834464Y280110D03*
X831464D03*
X828464Y277510D03*
Y274910D03*
Y280110D03*
X834464Y277510D03*
X831464D03*
X834464Y274910D03*
X845050Y252250D03*
X817491Y276857D03*
Y274257D03*
Y271657D03*
Y269057D03*
X837264Y274910D03*
Y280110D03*
Y277510D03*
X840064D03*
Y280110D03*
X817183Y242243D03*
Y239643D03*
Y244843D03*
X818032Y237000D03*
X822682Y234327D03*
Y231727D03*
Y237027D03*
Y239627D03*
X831464Y274910D03*
X844400Y280500D03*
X848282Y254327D03*
X788600Y306100D03*
X789500Y301200D03*
X797300D03*
X799900D03*
X810300D03*
X802500D03*
X812900D03*
X807700D03*
X805100D03*
X815500D03*
X811991Y308957D03*
Y306357D03*
Y303757D03*
X814591Y306357D03*
Y308957D03*
Y303757D03*
X792900Y308400D03*
X789900D03*
X794700Y301200D03*
X792100D03*
X793000Y340400D03*
X790300Y340300D03*
X816991Y337357D03*
Y334757D03*
Y339957D03*
X814391D03*
Y337357D03*
Y334757D03*
X811791Y337357D03*
Y339957D03*
Y334757D03*
X791879Y332798D03*
X794600Y332600D03*
X816938Y319888D03*
Y323888D03*
X817100Y317000D03*
X848382Y282327D03*
X834682Y298527D03*
X828682D03*
X825682D03*
Y295527D03*
Y301227D03*
Y303927D03*
X822682D03*
Y301227D03*
Y295527D03*
Y298527D03*
X844300Y312450D03*
X831682Y298527D03*
X837782Y298127D03*
Y301027D03*
Y303927D03*
X818100Y301200D03*
X817191Y303757D03*
Y306357D03*
Y308957D03*
X834682Y301227D03*
X831682D03*
X828682D03*
X831682Y303927D03*
X834682D03*
X822482Y339827D03*
Y337027D03*
X831482D03*
X834482D03*
X828482Y339827D03*
X831482D03*
X834482D03*
X840282Y340227D03*
X840382Y337427D03*
X837382Y339877D03*
Y337077D03*
X847682Y314627D03*
X847982Y338327D03*
Y341327D03*
X828482Y337027D03*
X828682Y303927D03*
X847682Y309327D03*
Y312027D03*
Y306727D03*
X825482Y339827D03*
Y337027D03*
X789860Y364947D03*
X816591Y369857D03*
Y372457D03*
X811391Y369857D03*
X813991D03*
Y372457D03*
X811391D03*
X790900Y372300D03*
X788300Y372400D03*
X802759Y364575D03*
X816672Y358809D03*
X795310Y364721D03*
X816593Y356210D03*
X807959Y364575D03*
X805359D03*
X810559D03*
X815759D03*
X813159D03*
X816900Y361400D03*
X792610Y364821D03*
X816591Y375057D03*
X792238Y396753D03*
X789600Y396809D03*
X811515Y397289D03*
X808915D03*
X813648Y395557D03*
X815472Y390442D03*
X814877Y393138D03*
X792000Y399409D03*
X789400D03*
X822089Y362782D03*
Y359782D03*
X822482Y342827D03*
X828482D03*
X831482D03*
X834482D03*
X828089Y359841D03*
X834089D03*
X831089D03*
X844350Y344000D03*
X840262Y343011D03*
X837382Y342877D03*
X847982Y344327D03*
X834089Y362782D03*
X831089D03*
X828089D03*
X825482Y342827D03*
X825089Y359841D03*
Y362782D03*
X849606Y638753D03*
X836406D03*
X832006D03*
X796806D03*
X801206D03*
X792406D03*
X827606D03*
X818806D03*
X823206D03*
X810006D03*
X788006D03*
X845206D03*
X814406D03*
X805606D03*
X840806D03*
X849621Y660756D03*
X832021D03*
X810021D03*
X818821D03*
X836421D03*
X788021D03*
X814421D03*
X801221D03*
X805621D03*
X823221D03*
X827621D03*
X840821D03*
X796821D03*
X792421D03*
X845221D03*
X907921Y-58764D03*
Y-35764D03*
X902921Y-58764D03*
Y-35764D03*
X897921Y-58764D03*
Y-35764D03*
X892921Y-58764D03*
Y-35764D03*
X887921Y-58764D03*
Y-35764D03*
X882921Y-58764D03*
Y-35764D03*
X877921Y-58764D03*
Y-35764D03*
X872921Y-58764D03*
Y-35764D03*
X867921Y-58764D03*
Y-35764D03*
X862921Y-58764D03*
Y-35764D03*
X857921Y-58764D03*
Y-35764D03*
X852921Y-58764D03*
Y-35764D03*
X854282Y251727D03*
X857282D03*
X851282D03*
X857282Y249027D03*
Y246427D03*
X851282D03*
Y249027D03*
X854282D03*
Y246427D03*
X851382Y277027D03*
Y274427D03*
X857382Y277027D03*
X854382Y279727D03*
X857382D03*
X854382Y274427D03*
X857382D03*
X854382Y277027D03*
X874586Y259278D03*
X854282Y254327D03*
X857282D03*
X869586Y254278D03*
X851282Y254327D03*
X851382Y279727D03*
X884586Y269278D03*
X879586Y264278D03*
X889586Y274278D03*
X851382Y282327D03*
X854382D03*
X857382D03*
X851075Y335405D03*
X857075D03*
X856982Y338327D03*
X853982D03*
X856682Y314627D03*
X853682D03*
X850682D03*
X856982Y341327D03*
X853982D03*
X862008Y341100D03*
X850982Y338327D03*
Y341327D03*
X872008Y331100D03*
X867008Y336100D03*
X850682Y306727D03*
Y309327D03*
Y312027D03*
X856682Y309327D03*
X853682D03*
X856682Y306727D03*
X853682D03*
X856682Y312027D03*
X853682D03*
X877008Y326100D03*
X854075Y335405D03*
X856982Y344327D03*
X853982D03*
X850982D03*
X858406Y638753D03*
X854006D03*
X884806D03*
X880406D03*
X876006D03*
X871606D03*
X867206D03*
X911206D03*
X906806D03*
X889206D03*
X898006D03*
X902406D03*
X893606D03*
X862806D03*
X854021Y660756D03*
X858421D03*
X862821D03*
X898021D03*
X902421D03*
X871621D03*
X884821D03*
X893621D03*
X867221D03*
X889221D03*
X911221D03*
X906821D03*
X880421D03*
X876021D03*
X937921Y-35764D03*
X932921Y-58764D03*
Y-35764D03*
X927921Y-58764D03*
Y-35764D03*
X922921Y-58764D03*
Y-35764D03*
X917921Y-58764D03*
Y-35764D03*
X912921Y-58764D03*
Y-35764D03*
X942921D03*
X967921D03*
X962921Y-58764D03*
Y-35764D03*
X957921Y-58764D03*
Y-35764D03*
X952921Y-58764D03*
Y-35764D03*
X947921Y-58764D03*
Y-35764D03*
X942921Y-58764D03*
X972921D03*
Y-35764D03*
X967921Y-58764D03*
X937921D03*
X941883Y646234D03*
X924406Y638753D03*
X920006D03*
X915606D03*
X972806D03*
X968406D03*
X964006D03*
X917100Y649300D03*
X942006Y638753D03*
X937606D03*
X933206D03*
X928806D03*
X959606D03*
X955206D03*
X950806D03*
X946406D03*
X941883Y652234D03*
X959621Y660756D03*
X964021D03*
X968421D03*
X972821D03*
X920021D03*
X915621D03*
X924421D03*
X946421D03*
X942021D03*
X937621D03*
X933221D03*
X928821D03*
X955221D03*
X950821D03*
X1002921Y-58764D03*
Y-35764D03*
X997921Y-58764D03*
Y-35764D03*
X992921Y-58764D03*
Y-35764D03*
X987921Y-58764D03*
Y-35764D03*
X982921Y-58764D03*
Y-35764D03*
X977921Y-58764D03*
Y-35764D03*
X1032921Y-58764D03*
Y-35764D03*
X1027921Y-58764D03*
Y-35764D03*
X1022921Y-58764D03*
Y-35764D03*
X1017921Y-58764D03*
Y-35764D03*
X1012921Y-58764D03*
Y-35764D03*
X1007921Y-58764D03*
Y-35764D03*
X1024994Y292918D03*
X1017630Y292910D03*
X1020702Y292904D03*
X1027902D03*
X1031953Y292910D03*
X1024140Y309910D03*
X1021065Y309759D03*
X1017083Y309910D03*
X1032042D03*
X1028136Y309815D03*
X1003606Y638753D03*
X1012406D03*
X977206D03*
X990406D03*
X986006D03*
X994806D03*
X1016806D03*
X1021206D03*
X981606D03*
X999206D03*
X1025606D03*
X1008006D03*
X1030006D03*
X1034406D03*
X999221Y660756D03*
X1034421D03*
X1030021D03*
X1008021D03*
X1012421D03*
X1003621D03*
X1016821D03*
X977221D03*
X981621D03*
X1021221D03*
X1025621D03*
X994821D03*
X986021D03*
X990421D03*
X1067921Y-58764D03*
Y-35764D03*
X1062921Y-58764D03*
Y-35764D03*
X1057921Y-58764D03*
Y-35764D03*
X1052921Y-58764D03*
Y-35764D03*
X1047921Y-58764D03*
Y-35764D03*
X1042921Y-58764D03*
Y-35764D03*
X1037921Y-58764D03*
Y-35764D03*
X1092921Y-58764D03*
Y-35764D03*
X1087921Y-58764D03*
Y-35764D03*
X1082921Y-58764D03*
Y-35764D03*
X1077921Y-58764D03*
Y-35764D03*
X1072921Y-58764D03*
Y-35764D03*
X1086000Y264900D03*
X1046276Y292910D03*
X1049502Y292904D03*
X1053684Y292910D03*
X1056702Y292904D03*
X1039182Y292919D03*
X1042302Y292904D03*
X1035102D03*
X1049547Y309904D03*
X1046612Y309910D03*
X1056747Y309904D03*
X1053594Y309910D03*
X1042347Y309904D03*
X1039383Y309910D03*
X1035147Y309904D03*
X1086126Y338758D03*
X1083301Y338841D03*
X1096006Y638753D03*
X1078406D03*
X1082806D03*
X1074006D03*
X1069606D03*
X1091606D03*
X1052006D03*
X1038806D03*
X1087206D03*
X1060806D03*
X1056406D03*
X1065206D03*
X1043206D03*
X1047606D03*
X1078421Y660756D03*
X1060821D03*
X1087221D03*
X1038821D03*
X1091621D03*
X1052021D03*
X1074021D03*
X1065221D03*
X1096021D03*
X1056421D03*
X1043221D03*
X1047621D03*
X1082821D03*
X1069621D03*
X1157921Y-58764D03*
Y-35764D03*
X1152921Y-58764D03*
Y-35764D03*
X1147921Y-58764D03*
Y-35764D03*
X1142921Y-58764D03*
Y-35764D03*
X1137921Y-58764D03*
Y-35764D03*
X1132921Y-58764D03*
Y-35764D03*
X1127921Y-58764D03*
Y-35764D03*
X1122921Y-58764D03*
Y-35764D03*
X1117921Y-58764D03*
Y-35764D03*
X1112921Y-58764D03*
Y-35764D03*
X1107921Y-58764D03*
Y-35764D03*
X1102921Y-58764D03*
Y-35764D03*
X1097921Y-58764D03*
Y-35764D03*
X1135606Y638753D03*
X1126806D03*
X1144406D03*
X1140006D03*
X1118006D03*
X1122406D03*
X1153206D03*
X1157606D03*
X1104806D03*
X1100406D03*
X1131206D03*
X1148806D03*
X1109206D03*
X1113606D03*
X1157621Y660756D03*
X1148821D03*
X1122421D03*
X1126821D03*
X1100421D03*
X1118021D03*
X1140021D03*
X1113621D03*
X1109221D03*
X1153221D03*
X1144421D03*
X1104821D03*
X1131221D03*
X1135621D03*
X1217921Y-58764D03*
Y-35764D03*
X1212921Y-58764D03*
Y-35764D03*
X1207921Y-58764D03*
Y-35764D03*
X1202921Y-58764D03*
Y-35764D03*
X1197921Y-58764D03*
Y-35764D03*
X1192921Y-58764D03*
Y-35764D03*
X1187921Y-58764D03*
Y-35764D03*
X1182921Y-58764D03*
Y-35764D03*
X1177921Y-58764D03*
Y-35764D03*
X1172921Y-58764D03*
Y-35764D03*
X1167921Y-58764D03*
Y-35764D03*
X1162921Y-58764D03*
Y-35764D03*
X1206110Y646206D03*
X1188406Y638753D03*
X1214806D03*
X1197206D03*
X1201606D03*
X1192806D03*
X1170806D03*
X1162006D03*
X1166406D03*
X1206006D03*
X1219206D03*
X1179606D03*
X1175206D03*
X1210406D03*
X1184006D03*
X1206110Y652206D03*
X1184021Y660756D03*
X1219221D03*
X1192821D03*
X1188421D03*
X1201621D03*
X1179621D03*
X1214821D03*
X1206021D03*
X1166421D03*
X1210421D03*
X1170821D03*
X1162021D03*
X1175221D03*
X1197221D03*
X1232921Y-58764D03*
Y-35764D03*
X1227921Y-58764D03*
Y-35764D03*
X1222921Y-58764D03*
Y-35764D03*
X1252921Y-58764D03*
Y-35764D03*
X1247921Y-58764D03*
Y-35764D03*
X1242921Y-58764D03*
Y-35764D03*
X1237921Y-58764D03*
Y-35764D03*
X1257921D03*
X1272921Y-58764D03*
Y-35764D03*
X1267921Y-58764D03*
Y-35764D03*
X1262921Y-58764D03*
Y-35764D03*
X1257921Y-58764D03*
X1277921D03*
Y-35764D03*
X1263206Y638753D03*
X1223606D03*
X1228006D03*
X1258806D03*
X1241206D03*
X1236806D03*
X1250006D03*
X1245606D03*
X1276406D03*
X1254406D03*
X1280806D03*
X1272006D03*
X1267606D03*
X1232406D03*
X1228021Y660756D03*
X1232421D03*
X1280821D03*
X1245621D03*
X1236821D03*
X1223621D03*
X1276421D03*
X1241221D03*
X1272021D03*
X1258821D03*
X1250021D03*
X1254421D03*
X1263221D03*
X1267621D03*
X1342921Y-35764D03*
Y-58764D03*
X1317921D03*
X1312921Y-35764D03*
Y-58764D03*
X1307921Y-35764D03*
Y-58764D03*
X1302921Y-35764D03*
Y-58764D03*
X1297921D03*
Y-35764D03*
X1292921Y-58764D03*
Y-35764D03*
X1287921Y-58764D03*
Y-35764D03*
X1282921Y-58764D03*
Y-35764D03*
X1322921D03*
Y-58764D03*
X1317921Y-35764D03*
X1337921D03*
Y-58764D03*
X1332921Y-35764D03*
Y-58764D03*
X1327921Y-35764D03*
Y-58764D03*
X1324806Y638753D03*
X1298406D03*
X1285206D03*
X1294006D03*
X1302806D03*
X1333606D03*
X1338006D03*
X1320406D03*
X1311606D03*
X1329206D03*
X1307206D03*
X1342406D03*
X1289606D03*
X1316006D03*
X1329221Y660756D03*
X1311621D03*
X1316021D03*
X1333621D03*
X1342421D03*
X1285221D03*
X1324821D03*
X1338021D03*
X1298421D03*
X1289621D03*
X1294021D03*
X1320421D03*
X1302821D03*
X1307221D03*
X1402921Y-58764D03*
X1397921D03*
X1402921Y-35764D03*
X1392921Y-58764D03*
X1397921Y-35764D03*
X1387921Y-58764D03*
X1392921Y-35764D03*
X1382921Y-58764D03*
X1387921Y-35764D03*
X1377921Y-58764D03*
X1382921Y-35764D03*
X1372921Y-58764D03*
X1377921Y-35764D03*
X1367921Y-58764D03*
X1362921Y-35764D03*
Y-58764D03*
X1357921Y-35764D03*
Y-58764D03*
X1352921Y-35764D03*
Y-58764D03*
X1347921Y-35764D03*
Y-58764D03*
X1351206Y638753D03*
X1360006D03*
X1404506Y638853D03*
X1355606Y638753D03*
X1386906Y638853D03*
X1364406Y638753D03*
X1391306Y638853D03*
X1346806Y638753D03*
X1400106Y638853D03*
X1382006Y638753D03*
X1377606D03*
X1373206D03*
X1395706Y638853D03*
X1368806Y638753D03*
X1368821Y660756D03*
X1346821D03*
X1355621D03*
X1360021D03*
X1364421D03*
X1351221D03*
X1404521Y660856D03*
X1400121D03*
X1395721D03*
X1386921D03*
X1377621Y660756D03*
X1382021D03*
X1373221D03*
X1391321Y660856D03*
X1407921Y-58764D03*
X1412921Y-35764D03*
X1407921D03*
X1442921Y-58764D03*
X1447921Y-35764D03*
X1437921Y-58764D03*
X1442921Y-35764D03*
X1432921Y-58764D03*
X1437921Y-35764D03*
X1427921Y-58764D03*
X1432921Y-35764D03*
X1422921Y-58764D03*
X1427921Y-35764D03*
X1417921Y-58764D03*
X1422921Y-35764D03*
X1412921Y-58764D03*
X1417921Y-35764D03*
X1462921Y-58764D03*
X1457921D03*
X1462921Y-35764D03*
X1452921Y-58764D03*
X1457921Y-35764D03*
X1447921Y-58764D03*
X1452921Y-35764D03*
X1457300Y563900D03*
X1422106Y638853D03*
X1466106D03*
X1448506D03*
X1457306D03*
X1417706D03*
X1413306D03*
X1461706D03*
X1452906D03*
X1408906D03*
X1444106D03*
X1435306D03*
X1426506D03*
X1430906D03*
X1439706D03*
X1457321Y660856D03*
X1417721D03*
X1413321D03*
X1408921D03*
X1422121D03*
X1426521D03*
X1435321D03*
X1444121D03*
X1439721D03*
X1430921D03*
X1448521D03*
X1452921D03*
X1466121D03*
X1461721D03*
X1502921Y-58764D03*
X1507921Y-35764D03*
X1497921Y-58764D03*
X1502921Y-35764D03*
X1492921Y-58764D03*
X1497921Y-35764D03*
X1487921Y-58764D03*
X1492921Y-35764D03*
X1482921Y-58764D03*
X1487921Y-35764D03*
X1477921Y-58764D03*
X1482921Y-35764D03*
X1472921Y-58764D03*
X1477921Y-35764D03*
X1467921Y-58764D03*
X1472921Y-35764D03*
X1467921D03*
X1527921Y-58764D03*
X1522921D03*
X1527921Y-35764D03*
X1517921Y-58764D03*
X1522921Y-35764D03*
X1512921Y-58764D03*
X1517921Y-35764D03*
X1507921Y-58764D03*
X1512921Y-35764D03*
X1496906Y638853D03*
X1492506D03*
X1501706Y638753D03*
X1506106D03*
X1514906D03*
X1483706Y638853D03*
X1523706Y638753D03*
X1510506D03*
X1488106Y638853D03*
X1474906D03*
X1519306Y638753D03*
X1479306Y638853D03*
X1528106Y638753D03*
X1470506Y638853D03*
X1496921Y660856D03*
X1483721D03*
X1488121D03*
X1492521D03*
X1479321D03*
X1510521Y660756D03*
X1528121D03*
X1523721D03*
X1501721D03*
X1506121D03*
X1514921D03*
X1519321D03*
X1474921Y660856D03*
X1470521D03*
X1587921Y-58764D03*
X1582921D03*
X1587921Y-35764D03*
X1532921D03*
X1542921D03*
X1532921Y-58764D03*
X1537921Y-35764D03*
X1577921Y-58764D03*
X1582921Y-35764D03*
X1572921Y-58764D03*
X1577921Y-35764D03*
X1567921Y-58764D03*
X1572921Y-35764D03*
X1562921Y-58764D03*
X1567921Y-35764D03*
X1557921Y-58764D03*
X1562921Y-35764D03*
X1552921Y-58764D03*
X1557921Y-35764D03*
X1547921Y-58764D03*
X1552921Y-35764D03*
X1542921Y-58764D03*
X1547921Y-35764D03*
X1537921Y-58764D03*
X1580121Y647556D03*
X1555106Y638753D03*
X1555121Y647556D03*
X1590121D03*
X1590106Y638753D03*
X1590121Y643156D03*
X1585121Y647556D03*
X1585106Y638753D03*
X1585121Y643156D03*
X1565121Y647556D03*
X1570121Y643156D03*
X1570106Y638753D03*
X1565106D03*
X1565121Y643156D03*
X1570121Y647556D03*
X1560121D03*
X1560106Y638753D03*
X1560121Y643156D03*
X1575121D03*
X1575106Y638753D03*
X1575121Y647556D03*
X1555121Y643156D03*
X1580106Y638753D03*
X1580121Y643156D03*
X1550121Y647556D03*
X1541306Y638753D03*
X1545706D03*
X1550106D03*
X1550121Y643156D03*
X1536906Y638753D03*
X1532506D03*
X1565121Y651956D03*
X1570121Y660756D03*
Y656356D03*
X1565121Y660756D03*
X1555121Y651956D03*
X1590121Y660756D03*
Y656356D03*
Y651956D03*
X1585121Y660756D03*
Y656356D03*
Y651956D03*
X1580121Y660756D03*
Y656356D03*
Y651956D03*
X1560121Y660756D03*
Y656356D03*
Y651956D03*
X1555121Y660756D03*
Y656356D03*
X1570121Y651956D03*
X1575121D03*
Y656356D03*
Y660756D03*
X1565121Y656356D03*
X1550121Y651956D03*
Y656356D03*
X1541321Y660756D03*
X1550121D03*
X1545721D03*
X1532521D03*
X1536921D03*
X1642921Y-35764D03*
Y-58764D03*
X1637921Y-35764D03*
Y-58764D03*
X1632921Y-35764D03*
Y-58764D03*
X1627921D03*
X1622921D03*
X1627921Y-35764D03*
X1617921Y-58764D03*
X1622921Y-35764D03*
X1612921Y-58764D03*
X1617921Y-35764D03*
X1607921Y-58764D03*
X1612921Y-35764D03*
X1602921Y-58764D03*
X1607921Y-35764D03*
X1597921Y-58764D03*
X1602921Y-35764D03*
X1592921Y-58764D03*
X1597921Y-35764D03*
X1592921D03*
X1647921D03*
Y-58764D03*
X1625106Y638753D03*
X1625121Y647556D03*
X1630121Y643156D03*
X1630106Y638753D03*
X1630121Y647556D03*
X1635121Y643156D03*
X1635106Y638753D03*
X1635121Y647556D03*
X1640121Y643156D03*
Y647556D03*
X1640106Y638753D03*
X1650121Y647556D03*
X1650106Y638753D03*
X1650121Y643156D03*
X1645121Y647556D03*
X1645106Y638753D03*
X1645121Y643156D03*
X1625121D03*
X1620121Y647556D03*
X1620106Y638753D03*
X1620121Y643156D03*
X1615121Y647556D03*
X1615106Y638753D03*
X1615121Y643156D03*
X1610121Y647556D03*
X1610106Y638753D03*
X1610121Y643156D03*
X1605121Y647556D03*
X1605106Y638753D03*
X1605121Y643156D03*
X1600121Y647556D03*
X1600106Y638753D03*
X1600121Y643156D03*
X1595121Y647556D03*
X1595106Y638753D03*
X1595121Y643156D03*
X1625121Y651956D03*
Y660756D03*
X1630121Y651956D03*
Y656356D03*
Y660756D03*
X1635121Y651956D03*
Y656356D03*
Y660756D03*
X1625121Y656356D03*
X1640121D03*
Y651956D03*
X1650121Y660756D03*
Y656356D03*
Y651956D03*
X1645121Y660756D03*
Y656356D03*
Y651956D03*
X1640121Y660756D03*
X1620121D03*
Y656356D03*
Y651956D03*
X1615121Y660756D03*
Y656356D03*
Y651956D03*
X1610121Y660756D03*
Y656356D03*
Y651956D03*
X1605121Y660756D03*
Y656356D03*
Y651956D03*
X1600121Y660756D03*
Y656356D03*
Y651956D03*
X1595121Y660756D03*
Y656356D03*
Y651956D03*
X1692921Y-40764D03*
X1702921Y-54764D03*
X1687921D03*
X1682921D03*
X1677921D03*
X1672921D03*
X1692921D03*
X1697921D03*
X1707921D03*
X1712921D03*
X1697921Y-40764D03*
X1692921Y-50764D03*
X1687921D03*
X1682921D03*
X1677921D03*
X1672921D03*
X1712921D03*
X1707921D03*
X1702921D03*
X1697921Y-45764D03*
X1707921D03*
X1702921D03*
X1712921D03*
X1697921Y-50764D03*
X1667921Y-35764D03*
X1712921D03*
Y-58764D03*
X1707921Y-35764D03*
Y-58764D03*
X1702921Y-35764D03*
Y-58764D03*
X1697921Y-35764D03*
Y-58764D03*
X1687921Y-40764D03*
X1672921Y-45764D03*
X1677921D03*
X1682921D03*
Y-40764D03*
X1687921Y-45764D03*
X1692921D03*
X1667921Y-58764D03*
X1662921Y-35764D03*
Y-58764D03*
X1657921Y-35764D03*
Y-58764D03*
X1652921Y-35764D03*
Y-58764D03*
X1712921Y-40764D03*
X1707921D03*
X1702921D03*
X1677921D03*
X1672921D03*
X1677921Y-35764D03*
Y-58764D03*
X1672921Y-35764D03*
Y-58764D03*
X1682921Y-35764D03*
Y-58764D03*
X1692921Y-35764D03*
Y-58764D03*
X1687921Y-35764D03*
Y-58764D03*
X1690121Y647556D03*
X1710121D03*
X1710106Y638753D03*
X1710121Y643156D03*
X1705121Y647556D03*
X1705106Y638753D03*
X1695121Y643156D03*
X1695106Y638753D03*
X1695121Y647556D03*
X1700121Y643156D03*
X1700106Y638753D03*
X1685121Y647556D03*
X1685106Y638753D03*
X1685121Y643156D03*
X1680121Y647556D03*
X1680106Y638753D03*
X1680121Y643156D03*
X1675121Y647556D03*
X1675106Y638753D03*
X1675121Y643156D03*
X1670121Y647556D03*
X1670106Y638753D03*
X1670121Y643156D03*
X1665121Y647556D03*
X1665106Y638753D03*
X1665121Y643156D03*
X1660121Y647556D03*
X1660106Y638753D03*
X1660121Y643156D03*
X1655121Y647556D03*
X1655106Y638753D03*
X1655121Y643156D03*
X1690121D03*
X1690106Y638753D03*
X1700121Y647556D03*
X1705121Y643156D03*
X1690121Y656356D03*
Y651956D03*
X1710121Y660756D03*
Y656356D03*
Y651956D03*
X1705121Y660756D03*
Y656356D03*
Y651956D03*
X1690121Y660756D03*
X1695121Y651956D03*
Y656356D03*
Y660756D03*
X1685121Y651956D03*
X1680121Y660756D03*
Y656356D03*
Y651956D03*
X1675121Y660756D03*
Y656356D03*
Y651956D03*
X1670121Y660756D03*
Y656356D03*
Y651956D03*
X1665121Y660756D03*
Y656356D03*
Y651956D03*
X1660121Y660756D03*
Y656356D03*
Y651956D03*
X1655121Y660756D03*
Y656356D03*
Y651956D03*
X1685121Y660756D03*
Y656356D03*
X1700121Y651956D03*
Y656356D03*
Y660756D03*
X1737921Y-50764D03*
X1722921Y-45764D03*
X1727921D03*
X1732921D03*
X1747921D03*
X1752921D03*
X1727921Y-54764D03*
X1757921D03*
X1717921D03*
X1722921D03*
X1767921Y-40764D03*
Y-50764D03*
X1762921D03*
X1757921D03*
X1762921Y-54764D03*
X1752921D03*
X1747921D03*
X1742921D03*
X1737921D03*
X1732921D03*
X1772921D03*
X1767921D03*
X1762921Y-40764D03*
X1772921D03*
X1722921Y-50764D03*
X1717921D03*
X1732921D03*
X1757921Y-40764D03*
X1717921Y-45764D03*
Y-58764D03*
X1742921Y-50764D03*
X1747921D03*
X1752921D03*
X1742921Y-58764D03*
X1737921Y-35764D03*
Y-58764D03*
X1732921Y-35764D03*
Y-58764D03*
X1727921Y-35764D03*
Y-58764D03*
X1722921Y-35764D03*
Y-58764D03*
X1717921Y-35764D03*
X1757921Y-45764D03*
X1762921D03*
X1742921D03*
X1752921Y-40764D03*
X1747921D03*
X1742921D03*
X1737921D03*
X1732921D03*
X1727921D03*
X1722921D03*
X1717921D03*
X1727921Y-50764D03*
X1767921Y-45764D03*
X1772921D03*
X1737921D03*
X1772921Y-35764D03*
Y-58764D03*
X1767921Y-35764D03*
Y-58764D03*
X1762921Y-35764D03*
Y-58764D03*
X1757921Y-35764D03*
Y-58764D03*
X1752921Y-35764D03*
Y-58764D03*
X1747921Y-35764D03*
Y-58764D03*
X1742921Y-35764D03*
X1772921Y-50764D03*
X1775121Y643156D03*
Y647556D03*
X1775106Y638753D03*
X1730121Y647556D03*
X1730106Y638753D03*
X1730121Y643156D03*
X1725121Y647556D03*
X1725106Y638753D03*
X1725121Y643156D03*
X1720121Y647556D03*
X1720106Y638753D03*
X1720121Y643156D03*
X1715121Y647556D03*
X1715106Y638753D03*
X1715121Y643156D03*
X1770121Y647556D03*
X1770106Y638753D03*
X1770121Y643156D03*
X1765121Y647556D03*
X1765106Y638753D03*
X1765121Y643156D03*
X1760121Y647556D03*
X1760106Y638753D03*
X1760121Y643156D03*
X1755121Y647556D03*
X1755106Y638753D03*
X1755121Y643156D03*
X1750121Y647556D03*
X1750106Y638753D03*
X1750121Y643156D03*
X1745121Y647556D03*
X1745106Y638753D03*
X1745121Y643156D03*
X1740121Y647556D03*
X1740106Y638753D03*
X1740121Y643156D03*
X1735121Y647556D03*
X1735106Y638753D03*
X1735121Y643156D03*
X1770121Y660756D03*
X1775121D03*
Y656356D03*
Y651956D03*
X1725121Y660756D03*
Y656356D03*
Y651956D03*
X1720121Y660756D03*
Y656356D03*
Y651956D03*
X1715121Y660756D03*
Y656356D03*
Y651956D03*
X1770121D03*
X1765121Y660756D03*
Y656356D03*
Y651956D03*
X1760121Y660756D03*
Y656356D03*
Y651956D03*
X1755121Y660756D03*
Y656356D03*
Y651956D03*
X1750121Y660756D03*
Y656356D03*
Y651956D03*
X1745121Y660756D03*
Y656356D03*
Y651956D03*
X1740121Y660756D03*
Y656356D03*
Y651956D03*
X1735121Y660756D03*
Y656356D03*
Y651956D03*
X1730121Y660756D03*
Y656356D03*
X1770121D03*
X1730121Y651956D03*
X1817921Y-40764D03*
X1832921Y-45764D03*
Y-54764D03*
X1827921D03*
X1822921D03*
X1817921D03*
X1812921D03*
X1807921D03*
X1802921D03*
X1797921D03*
X1792921D03*
X1787921D03*
X1782921D03*
X1777921D03*
X1832921Y-50764D03*
X1827921D03*
X1822921D03*
X1817921D03*
X1812921D03*
X1807921D03*
X1802921D03*
X1797921D03*
X1792921D03*
X1787921D03*
X1782921Y-40764D03*
X1792921D03*
X1802921D03*
X1807921D03*
X1822921D03*
X1827921D03*
X1832921D03*
X1812921D03*
X1797921D03*
X1777921Y-45764D03*
X1782921D03*
X1787921D03*
X1792921D03*
X1797921D03*
X1802921D03*
X1807921D03*
X1812921D03*
X1817921D03*
X1822921D03*
X1787921Y-40764D03*
X1832921Y-35764D03*
Y-58764D03*
X1827921Y-35764D03*
Y-58764D03*
X1822921Y-35764D03*
Y-58764D03*
X1817921Y-35764D03*
Y-58764D03*
X1812921Y-35764D03*
Y-58764D03*
X1807921Y-35764D03*
Y-58764D03*
X1802921Y-35764D03*
Y-58764D03*
X1797921Y-35764D03*
Y-58764D03*
X1792921Y-35764D03*
Y-58764D03*
X1787921Y-35764D03*
Y-58764D03*
X1782921Y-35764D03*
Y-58764D03*
X1777921Y-35764D03*
Y-58764D03*
X1782921Y-50764D03*
X1777921D03*
Y-40764D03*
X1827921Y-45764D03*
X1780121Y643156D03*
X1780106Y638753D03*
X1780121Y647556D03*
X1785121Y643156D03*
X1790121D03*
X1835121Y647556D03*
X1835106Y638753D03*
X1835121Y643156D03*
X1830121Y647556D03*
X1830106Y638753D03*
X1830121Y643156D03*
X1825121Y647556D03*
X1825106Y638753D03*
X1825121Y643156D03*
X1820121Y647556D03*
X1820106Y638753D03*
X1820121Y643156D03*
X1815121Y647556D03*
X1815106Y638753D03*
X1815121Y643156D03*
X1810121Y647556D03*
X1810106Y638753D03*
X1810121Y643156D03*
X1805121Y647556D03*
X1805106Y638753D03*
X1805121Y643156D03*
X1800121Y647556D03*
X1800106Y638753D03*
X1800121Y643156D03*
X1795121Y647556D03*
X1795106Y638753D03*
X1795121Y643156D03*
X1790121Y647556D03*
X1790106Y638753D03*
X1785121Y647556D03*
X1785106Y638753D03*
X1800121Y656356D03*
X1780121Y651956D03*
Y656356D03*
Y660756D03*
X1835121D03*
Y656356D03*
Y651956D03*
X1830121Y660756D03*
Y656356D03*
Y651956D03*
X1825121Y660756D03*
Y656356D03*
Y651956D03*
X1820121Y660756D03*
Y656356D03*
Y651956D03*
X1815121Y660756D03*
Y656356D03*
Y651956D03*
X1810121Y660756D03*
Y656356D03*
Y651956D03*
X1805121Y660756D03*
Y656356D03*
Y651956D03*
X1800121Y660756D03*
Y651956D03*
X1795121Y660756D03*
Y656356D03*
Y651956D03*
X1790121Y660756D03*
Y656356D03*
Y651956D03*
X1785121Y660756D03*
Y656356D03*
Y651956D03*
X1857921Y-45764D03*
X1837921D03*
X1897921D03*
X1892921D03*
X1887921D03*
X1882921D03*
X1877921D03*
X1872921D03*
X1867921D03*
X1862921D03*
X1842921Y-54764D03*
X1852921Y-45764D03*
X1847921D03*
X1842921D03*
X1897921Y-54764D03*
X1892921D03*
X1887921D03*
X1882921D03*
X1877921D03*
X1872921D03*
X1867921D03*
X1862921D03*
X1857921D03*
X1852921D03*
X1847921D03*
X1837921D03*
X1897921Y-50764D03*
X1892921D03*
X1887921D03*
X1882921D03*
X1877921D03*
X1872921D03*
X1867921D03*
X1862921D03*
X1857921D03*
X1852921D03*
X1847921D03*
X1842921D03*
X1837921D03*
X1892921Y-40764D03*
X1897921D03*
X1877921D03*
X1882921D03*
X1887921D03*
X1857921D03*
X1862921D03*
X1867921D03*
X1872921D03*
X1837921D03*
X1842921D03*
X1847921D03*
X1852921D03*
Y-35764D03*
Y-58764D03*
X1847921Y-35764D03*
Y-58764D03*
X1842921Y-35764D03*
Y-58764D03*
X1837921Y-35764D03*
Y-58764D03*
X1862921D03*
X1857921Y-35764D03*
Y-58764D03*
X1882921D03*
X1877921Y-35764D03*
Y-58764D03*
X1872921Y-35764D03*
Y-58764D03*
X1867921Y-35764D03*
Y-58764D03*
X1862921Y-35764D03*
X1897921D03*
Y-58764D03*
X1892921Y-35764D03*
Y-58764D03*
X1887921Y-35764D03*
Y-58764D03*
X1882921Y-35764D03*
X1846667Y75106D03*
X1886200Y454280D03*
X1882669Y454368D03*
X1886330Y448010D03*
X1892118Y454383D03*
X1888968D03*
X1888976Y448054D03*
X1892126D03*
X1895275D03*
X1895121Y647556D03*
X1895106Y638753D03*
X1895121Y643156D03*
X1890121Y647556D03*
X1890106Y638753D03*
X1890121Y643156D03*
X1885121Y647556D03*
X1885106Y638753D03*
X1885121Y643156D03*
X1880121Y647556D03*
X1880106Y638753D03*
X1880121Y643156D03*
X1875121Y647556D03*
X1875106Y638753D03*
X1875121Y643156D03*
X1870121Y647556D03*
X1870106Y638753D03*
X1870121Y643156D03*
X1865121Y647556D03*
X1865106Y638753D03*
X1865121Y643156D03*
X1860121Y647556D03*
X1860106Y638753D03*
X1860121Y643156D03*
X1855121Y647556D03*
X1855106Y638753D03*
X1855121Y643156D03*
X1850121Y647556D03*
X1850106Y638753D03*
X1850121Y643156D03*
X1845121Y647556D03*
X1845106Y638753D03*
X1845121Y643156D03*
X1840121Y647556D03*
X1840106Y638753D03*
X1840121Y643156D03*
X1895121Y660756D03*
Y656356D03*
Y651956D03*
X1890121Y660756D03*
Y656356D03*
Y651956D03*
X1885121Y660756D03*
Y656356D03*
Y651956D03*
X1880121Y660756D03*
Y656356D03*
Y651956D03*
X1875121Y660756D03*
Y656356D03*
Y651956D03*
X1870121Y660756D03*
Y656356D03*
Y651956D03*
X1865121Y660756D03*
Y656356D03*
Y651956D03*
X1860121Y660756D03*
Y656356D03*
Y651956D03*
X1855121Y660756D03*
Y656356D03*
Y651956D03*
X1850121Y660756D03*
Y656356D03*
Y651956D03*
X1845121Y660756D03*
Y656356D03*
Y651956D03*
X1840121Y660756D03*
Y656356D03*
Y651956D03*
X1927921Y-40764D03*
X1947921Y-45764D03*
X1942921D03*
X1937921D03*
X1932921D03*
X1927921D03*
X1922921D03*
X1917921D03*
X1912921D03*
X1907921D03*
X1902921D03*
X1927921Y-50764D03*
X1932921D03*
Y-40764D03*
X1937921D03*
X1942921D03*
X1947921D03*
X1907921Y-50764D03*
X1902921D03*
X1922921Y-40764D03*
X1917921D03*
X1912921D03*
X1907921D03*
X1902921D03*
X1922921Y-54764D03*
X1917921D03*
X1912921D03*
X1907921D03*
X1902921D03*
X1927921D03*
X1932921D03*
X1937921D03*
X1942921D03*
X1947921D03*
X1952921D03*
X1957921D03*
Y-50764D03*
X1952921D03*
X1947921D03*
X1942921D03*
X1937921D03*
X1922921D03*
X1917921D03*
X1912921D03*
X1957921Y-35764D03*
Y-58764D03*
X1952921Y-35764D03*
Y-58764D03*
X1947921Y-35764D03*
Y-58764D03*
X1942921Y-35764D03*
Y-58764D03*
X1937921Y-35764D03*
Y-58764D03*
X1932921Y-35764D03*
Y-58764D03*
X1927921Y-35764D03*
Y-58764D03*
X1922921Y-35764D03*
Y-58764D03*
X1917921Y-35764D03*
Y-58764D03*
X1912921Y-35764D03*
Y-58764D03*
X1907921Y-35764D03*
Y-58764D03*
X1902921Y-35764D03*
Y-58764D03*
X1938150Y70447D03*
X1937950Y73247D03*
X1940750Y73347D03*
X1929961Y73247D03*
X1935350D03*
X1932730Y73310D03*
X1942390Y76040D03*
X1943550Y73347D03*
X1946350Y73447D03*
X1945020Y76060D03*
X1954271Y80449D03*
X1936706Y75987D03*
X1939470Y76000D03*
X1930150Y70447D03*
X1932950D03*
X1935550D03*
X1940950Y70547D03*
X1943750D03*
X1960106Y638753D03*
X1955106D03*
X1950106D03*
X1945121Y647556D03*
Y643156D03*
X1945106Y638753D03*
X1940121Y647556D03*
Y643156D03*
X1940106Y638753D03*
X1935121Y647556D03*
Y643156D03*
X1935106Y638753D03*
X1930106D03*
X1925106D03*
X1920121Y647556D03*
X1910121Y643156D03*
X1910106Y638753D03*
X1905121Y647556D03*
Y643156D03*
X1905106Y638753D03*
X1900121Y647556D03*
X1900106Y638753D03*
X1900121Y643156D03*
X1920106Y638753D03*
X1915121Y647556D03*
X1920121Y643156D03*
X1910121Y647556D03*
X1915106Y638753D03*
X1915121Y643156D03*
X1960121Y656356D03*
Y660756D03*
X1955121Y656356D03*
Y660756D03*
X1950121Y651956D03*
Y656356D03*
Y660756D03*
X1945121Y651956D03*
Y656356D03*
Y660756D03*
X1940121Y651956D03*
Y656356D03*
Y660756D03*
X1935121Y651956D03*
Y656356D03*
Y660756D03*
X1930121Y651956D03*
Y656356D03*
Y660756D03*
X1925121Y651956D03*
Y656356D03*
Y660756D03*
X1920121Y651956D03*
Y656356D03*
X1905121Y651956D03*
Y656356D03*
Y660756D03*
X1900121D03*
Y656356D03*
Y651956D03*
X1915121D03*
Y656356D03*
Y660756D03*
X1920121D03*
X1910121D03*
Y656356D03*
Y651956D03*
X1967921Y-45764D03*
X1962921D03*
Y-40764D03*
X1967921D03*
Y-54764D03*
X1962921D03*
X1967921Y-50764D03*
X1962921D03*
X1967921Y-35764D03*
Y-58764D03*
X1962921Y-35764D03*
Y-58764D03*
X1970121Y647556D03*
Y643156D03*
X1970106Y638753D03*
X1965121Y647556D03*
Y643156D03*
X1965106Y638753D03*
X1970121Y651956D03*
Y656356D03*
Y660756D03*
X1965121Y651956D03*
Y656356D03*
Y660756D03*
G54D20*
X476672Y220096D03*
X483432Y216196D03*
Y231797D03*
X480052Y225947D03*
X487932Y383896D03*
X491312Y393647D03*
X494692Y399496D03*
X484552Y389747D03*
G54D11*
G01X38645Y172740D02*
X44291Y178386D01*
G01D02*
X49937Y184032D01*
G01X38645D02*
X44291Y178386D01*
G01D02*
X49937Y172740D01*
G01X-1969Y178386D02*
X3677Y184032D01*
G01X-7615D02*
X-1969Y178386D01*
G01D02*
X3677Y172740D01*
G01X12582D02*
X18228Y178386D01*
G01D02*
X23874Y184032D01*
G01X12582D02*
X18228Y178386D01*
G01D02*
X23874Y172740D01*
G01X116200Y70387D02*
X116500Y70087D01*
Y53300D01*
X113100Y49900D01*
Y23765D01*
X106595Y17260D01*
X106000D01*
G01X130324Y244033D02*
X133000Y241357D01*
Y214709D01*
X130324Y212033D01*
G01X122542Y214019D02*
X120930Y215631D01*
Y226620D01*
X115620Y231930D01*
Y240345D01*
X121950Y246675D01*
G01X130324Y308033D02*
X133500Y304857D01*
Y279209D01*
X130324Y276033D01*
G01D02*
X133600Y272757D01*
Y247309D01*
X130324Y244033D01*
G01X122493Y310633D02*
X116600Y304740D01*
Y301100D01*
X114000Y298500D01*
Y294500D01*
X115500Y293000D01*
X118063D01*
X121563Y289500D01*
Y279508D01*
X122400Y278671D01*
G01X121950Y246675D02*
X122203D01*
G01X121950D02*
X123030Y247755D01*
Y262389D01*
X117908Y267511D01*
Y274179D01*
X122400Y278671D01*
G01X130585Y372085D02*
Y371772D01*
X133600Y368757D01*
Y343309D01*
X130443Y340152D01*
X130205D01*
G01X129700D02*
X130205D01*
G01D02*
Y336496D01*
X134000Y332701D01*
Y314400D01*
X130324Y310724D01*
Y308033D01*
G01X122361Y342649D02*
Y340360D01*
X117878Y335877D01*
Y327522D01*
X120680Y324720D01*
Y312446D01*
X122493Y310633D01*
G01X430749Y-124922D02*
G02I-12000J0D01*
G01X425599D02*
G02I-6850J0D01*
G01X434749D02*
X402749D01*
G01X434749Y-140922D02*
Y-220922D01*
G01D02*
X1729349D01*
G01X434749Y-176422D02*
X1729349D01*
G01X418749Y-140922D02*
Y-108922D01*
G01X434749Y-140922D02*
X1729349D01*
G01X685100Y43000D02*
X687000D01*
X688391Y41609D01*
X701079D01*
X703370Y43900D01*
X714000D01*
G01X700000Y233700D02*
X699100Y234600D01*
Y235100D01*
G01D02*
X696340Y237860D01*
Y250790D01*
X689960Y257170D01*
Y260500D01*
G01X941849Y-140922D02*
Y-220922D01*
G01X1079349Y-140922D02*
Y-220922D01*
G01X1194349Y-140922D02*
Y-220922D01*
G01X1378207Y394568D02*
Y396693D01*
X1375300Y399600D01*
X1367100D01*
X1363680Y396180D01*
X1336500D01*
X1333190Y399490D01*
X1331770D01*
G01X1339600Y515800D02*
X1341758D01*
X1344586Y512972D01*
X1354073D01*
X1361950Y520849D01*
X1372436D01*
X1373345Y519940D01*
G01X1361849Y-140922D02*
Y-220922D01*
G01X1371500Y101000D02*
X1370040D01*
G01X1359360D02*
X1352614D01*
X1349114Y104500D01*
X1345000D01*
G01X1370040Y101000D02*
X1367600Y103440D01*
X1361800D01*
X1359360Y101000D01*
G01X1369407Y396668D02*
X1368733Y395994D01*
Y393197D01*
X1369461Y392469D01*
X1375800D01*
X1377800Y390469D01*
Y387885D01*
X1379735Y385950D01*
X1385950D01*
X1388300Y383600D01*
X1393213D01*
X1393843Y384230D01*
X1394370D01*
G01X1531849Y-140922D02*
Y-220922D01*
G01X1637500Y529400D02*
X1640643D01*
X1644737Y525306D01*
X1663034D01*
X1665684Y522656D01*
X1688248D01*
X1696485Y530893D01*
X1716257D01*
X1730759Y545395D01*
Y548162D01*
G01X1687606Y500938D02*
X1684462D01*
X1681650Y503750D01*
Y510673D01*
G01X1729349Y-140922D02*
Y-220922D01*
G01X1757349Y-124922D02*
G02I-12000J0D01*
G01X1752199D02*
G02I-6850J0D01*
G01X1745349Y-140922D02*
Y-108922D01*
G01X1761349Y-124922D02*
X1729349D01*
G01X1868670Y42765D02*
X1868770Y42865D01*
Y64058D01*
X1864578Y68250D01*
X1853523D01*
X1846667Y75106D01*
X-18000Y247400D03*
X-15000D03*
X-18000Y262700D03*
X-15000D03*
X-16700Y497400D03*
X-17200Y510800D03*
X-17302Y506798D03*
X-16186Y519304D03*
X-16766Y500106D03*
X-14971Y540000D03*
X-17500Y574000D03*
X22499Y-19381D03*
X19924Y-18875D03*
X25060Y16214D03*
X42520Y-16896D03*
X41677Y-14390D03*
X16400Y24744D03*
X40530Y20220D03*
X43960Y20572D03*
X37739Y19501D03*
X23728Y18731D03*
X1863Y59426D03*
X1572Y38307D03*
X3600Y36200D03*
X16625Y56211D03*
X3100Y65900D03*
X35650Y91150D03*
X34000Y93350D03*
X1826Y56447D03*
X44200Y139400D03*
X44300Y144800D03*
X44200Y130700D03*
Y116800D03*
X44100Y97800D03*
X44200Y111500D03*
X44300Y102700D03*
Y125600D03*
X44600Y154100D03*
X7995Y285385D03*
X-6712Y515731D03*
X2160Y479000D03*
X-6650Y487800D03*
X5100Y478330D03*
X22491Y500618D03*
X-5680Y524570D03*
X14700Y517000D03*
X-4100Y554400D03*
X-12600Y578900D03*
X-4300Y558400D03*
X1400Y556500D03*
X-1200D03*
X1439Y546583D03*
Y553783D03*
X1539Y550183D03*
Y586183D03*
X1439Y582583D03*
X-900Y592500D03*
X1600D03*
X-4500Y594000D03*
X1439Y589783D03*
X71172Y-18486D03*
X74386Y-18439D03*
X60035Y7508D03*
X106000Y17260D03*
X88777Y-10586D03*
X82300Y-16600D03*
X64200Y17389D03*
X61446Y18238D03*
X53382Y-1173D03*
X71050Y89600D03*
X48700Y90700D03*
Y95500D03*
X61300Y89800D03*
X86600Y94000D03*
X63737Y130602D03*
X48900Y132600D03*
X68592D03*
X63858Y97620D03*
X62422Y109413D03*
X48900Y123500D03*
X62524Y123395D03*
X68584Y123900D03*
X68654Y118680D03*
X48800Y118900D03*
X48700Y109600D03*
X48600Y104900D03*
X63582Y116409D03*
X62502Y105100D03*
X60300Y151500D03*
X70800Y151400D03*
X77790Y121030D03*
X98420Y112198D03*
X48800Y137600D03*
X63878Y144800D03*
X68632Y137800D03*
X63888Y140064D03*
X87151Y184872D03*
X61800Y191600D03*
X92086Y324258D03*
X88600Y302997D03*
X82500Y341400D03*
X65800Y338900D03*
X54400Y340300D03*
X79400Y325400D03*
X79600Y335200D03*
X49200Y340650D03*
X59452Y338800D03*
X82150Y335800D03*
X66900Y322000D03*
X104600Y316602D03*
X103200Y335190D03*
X88840Y324740D03*
X84866Y294213D03*
X58600Y302700D03*
X72600Y310800D03*
X93712Y380507D03*
X66350Y347950D03*
X87900Y347500D03*
X88000Y343900D03*
X51900Y351000D03*
X55616Y368998D03*
X90518Y388828D03*
X54900Y389400D03*
X60934Y362307D03*
X57395Y366795D03*
X61914Y368731D03*
X57800Y376100D03*
X62600Y375100D03*
X97472Y380934D03*
X55500Y521800D03*
X53000Y524300D03*
Y521800D03*
X58000D03*
X55500Y519300D03*
X52992Y516846D03*
X58000Y524300D03*
X57936Y519212D03*
X53900Y505450D03*
X57100D03*
X60300D03*
X55500Y524300D03*
X53000Y519300D03*
X53900Y502250D03*
X60300D03*
X57100D03*
X86100Y505200D03*
X59731Y480066D03*
X89497Y479201D03*
X94998Y481612D03*
X106392Y527413D03*
X92326Y480398D03*
X105392Y566000D03*
X102236Y614167D03*
X91150Y618250D03*
X93800Y618111D03*
X91952Y620900D03*
X106192Y604600D03*
X116200Y70387D03*
X130313Y65699D03*
X123620D03*
X147045D03*
X136806Y68550D03*
X141880Y68340D03*
X132959Y87714D03*
X126580Y71500D03*
X123620Y92757D03*
X126666Y87714D03*
X147045Y92757D03*
X141880Y70949D03*
Y87514D03*
X136780Y89900D03*
X141880Y90114D03*
X136780Y71199D03*
Y87300D03*
X132959Y71500D03*
X130313Y92757D03*
X160431Y65699D03*
X153738D03*
X167124D03*
X157084Y71900D03*
X153738Y92757D03*
X157084Y87714D03*
X150391Y71900D03*
Y87714D03*
X169770Y71500D03*
X167124Y92757D03*
X169770Y87714D03*
X163391Y71500D03*
X160431Y92757D03*
X163477Y87714D03*
X112664Y128795D03*
X120533Y109535D03*
X109622Y128879D03*
X122542Y214019D03*
X130324Y212033D03*
X141263Y215216D03*
X137763Y217716D03*
X141263D03*
X137763Y215216D03*
X162788Y200650D03*
X162800Y195600D03*
X150000Y199850D03*
Y194850D03*
X117080Y225330D03*
X130324Y244033D03*
X122203Y246675D03*
X130324Y276033D03*
X117063Y257016D03*
X122400Y278671D03*
X141263Y234216D03*
X141200Y229600D03*
X141211Y225615D03*
X141300Y221700D03*
X139763Y231700D03*
Y227600D03*
Y223700D03*
X139582Y219800D03*
X141263Y249716D03*
Y247216D03*
X137763D03*
Y249716D03*
X141300Y253700D03*
X139631Y251900D03*
X137763Y279216D03*
X141263Y266216D03*
X139763Y255700D03*
Y259600D03*
X139800Y263700D03*
X141313Y257533D03*
X141263Y279216D03*
X141200Y261600D03*
X137300Y337200D03*
X130324Y308033D03*
X129700Y340152D03*
X122493Y310633D03*
X117063Y321016D03*
X141263Y311216D03*
X137763D03*
X141263Y281716D03*
X139730Y284200D03*
X139763Y288200D03*
Y292000D03*
Y296000D03*
X141200Y286100D03*
X141261Y290076D03*
X141300Y294000D03*
X141263Y298216D03*
X137763Y281716D03*
X141211Y325515D03*
X141263Y330216D03*
X139763Y327800D03*
X141300Y317500D03*
Y321500D03*
X139582Y315800D03*
X139763Y319400D03*
X141263Y313716D03*
X137763D03*
X139763Y323600D03*
X130585Y372085D03*
X117063Y385016D03*
X153392Y404000D03*
X122361Y342649D03*
X117063Y353016D03*
X141289Y349488D03*
X141300Y353300D03*
X141200Y357200D03*
X137763Y345716D03*
X141263D03*
Y343216D03*
X137763D03*
X141263Y362216D03*
X139582Y347800D03*
X139763Y351400D03*
Y355200D03*
Y359500D03*
X141300Y381800D03*
X139763Y384000D03*
X141263Y394216D03*
Y390416D03*
X141261Y385876D03*
X139736Y392300D03*
X137763Y375216D03*
X141263D03*
Y377716D03*
X137763D03*
X139631Y379900D03*
X139900Y388000D03*
X153392Y407500D03*
X132959Y513114D03*
X163477D03*
X160431Y518157D03*
X130313D03*
X136780Y512700D03*
X141880Y515514D03*
X136780Y515300D03*
X141880Y512914D03*
X169770Y513114D03*
X167124Y518157D03*
X150391Y513114D03*
X147045Y518157D03*
X126666Y513114D03*
X123620Y518157D03*
X157084Y513114D03*
X153738Y518157D03*
X130313Y528899D03*
X160431D03*
X163391Y534700D03*
X132959D03*
X136780Y534399D03*
X141880Y531540D03*
X136806Y531750D03*
X141880Y534149D03*
X167124Y528899D03*
X169770Y534700D03*
X147045Y528899D03*
X150391Y535100D03*
X123620Y528899D03*
X126580Y534700D03*
X153738Y528899D03*
X157084Y535100D03*
X190549Y65699D03*
X183856D03*
X203935D03*
X197242D03*
X173617Y68550D03*
X210428D03*
X178691Y68340D03*
X173591Y89900D03*
X210402D03*
X178691Y70949D03*
Y87514D03*
X173591Y71199D03*
Y87300D03*
X210402Y71199D03*
Y87300D03*
X178691Y90114D03*
X193895Y71900D03*
X190549Y92757D03*
X193895Y87714D03*
X187202Y71900D03*
X183856Y92757D03*
X187202Y87714D03*
X206581Y71500D03*
X203935Y92757D03*
X206581Y87714D03*
X200202Y71500D03*
X197242Y92757D03*
X200288Y87714D03*
X227360Y65699D03*
X220667D03*
X215502Y68340D03*
X230706Y71900D03*
X227360Y92757D03*
X230706Y87714D03*
X224013Y71900D03*
X220667Y92761D03*
X224013Y87714D03*
X215502Y70949D03*
Y87514D03*
Y90114D03*
X206800Y246500D03*
X203947Y280933D03*
X177689Y404109D03*
X180799Y404049D03*
X174609Y404009D03*
X195233Y348402D03*
X173591Y515300D03*
X200288Y513114D03*
X197242Y518157D03*
X230706Y513114D03*
X227360Y518157D03*
X206581Y513114D03*
X203935Y518157D03*
X187202Y513114D03*
X183856Y518157D03*
X193895Y513114D03*
X190549Y518157D03*
X215502Y515514D03*
X178691D03*
X210402Y512700D03*
X173591D03*
X215502Y512914D03*
X178691D03*
X210402Y515300D03*
X224013Y513114D03*
X220667Y518161D03*
X173617Y531750D03*
X224013Y535100D03*
X197242Y528899D03*
X200202Y534700D03*
X227360Y528899D03*
X230706Y535100D03*
X203935Y528899D03*
X206581Y534700D03*
X183856Y528899D03*
X187202Y535100D03*
X190549Y528899D03*
X193895Y535100D03*
X210402Y534399D03*
X215502Y534149D03*
X178691D03*
X210428Y531750D03*
X220667Y528899D03*
X215502Y531540D03*
X178691D03*
X173591Y534399D03*
X240746Y65699D03*
X264171D03*
X234053D03*
X257478D03*
X247239Y68550D03*
X270864Y65699D03*
X243392Y71500D03*
X240746Y92757D03*
X243392Y87714D03*
X267517Y71900D03*
X264171Y92757D03*
X267517Y87714D03*
X237013Y71500D03*
X234053Y92757D03*
X237099Y87714D03*
X260824Y71900D03*
X257478Y92757D03*
X260824Y87714D03*
X247213Y89900D03*
X252313Y70949D03*
Y87514D03*
X247213Y71199D03*
Y87300D03*
X252313Y90114D03*
X270864Y92757D03*
X284050Y68550D03*
X289124Y68340D03*
X277557Y65699D03*
X284024Y89900D03*
X289124Y70949D03*
Y87514D03*
X284024Y71199D03*
Y87300D03*
X289124Y90114D03*
X280203Y71500D03*
X277557Y92757D03*
X280203Y87714D03*
X273824Y71500D03*
X273910Y87714D03*
X252313Y68340D03*
X277999Y218860D03*
X281379Y216909D03*
X284759Y218860D03*
X264092Y242260D03*
X271239D03*
X267859Y248109D03*
X264179Y261760D03*
X271239D03*
Y253960D03*
X288139Y228610D03*
X277999Y226660D03*
X288139Y220809D03*
X264179Y246160D03*
X271239D03*
Y250060D03*
X264179Y257860D03*
X271239D03*
X267859Y255909D03*
X271239Y277360D03*
X267392Y276000D03*
X267359Y279310D03*
X267859Y271509D03*
X264179Y273460D03*
X284759Y230559D03*
X277999Y222760D03*
X281379Y224709D03*
X284759Y222760D03*
X281379Y228610D03*
X288139Y224709D03*
Y279310D03*
X274619D03*
X281379D03*
X239778Y274478D03*
X271239Y339760D03*
X264179Y331960D03*
X271239D03*
Y320260D03*
Y324160D03*
X270939Y316160D03*
X267359Y318309D03*
X267859Y326110D03*
X267392Y322000D03*
X270892Y304660D03*
Y311960D03*
Y300760D03*
Y308560D03*
Y292959D03*
Y289060D03*
X271239Y281260D03*
X270892Y285500D03*
Y296860D03*
X267359Y283209D03*
X281379Y302709D03*
X288139D03*
X291519Y304660D03*
X281379Y306609D03*
Y310509D03*
X288139Y306609D03*
Y310509D03*
X284759Y304660D03*
X281379Y287109D03*
X288139Y291009D03*
X284759Y289060D03*
Y281260D03*
X291519Y289060D03*
Y281260D03*
Y296860D03*
X288139Y298809D03*
X274619Y306609D03*
Y310509D03*
X277999Y304660D03*
X274619Y302709D03*
Y298809D03*
Y294909D03*
X277999Y289060D03*
Y281260D03*
X274619Y283209D03*
Y287109D03*
Y291009D03*
X277999Y296860D03*
X288139Y283209D03*
Y287109D03*
X281379Y298809D03*
Y294909D03*
X288139D03*
X284759Y296860D03*
X281379Y291009D03*
Y283209D03*
X291519Y312460D03*
X284759D03*
X277999D03*
X274619Y314409D03*
X281379D03*
X288139D03*
X274619Y318309D03*
X264179Y335860D03*
X267859Y337809D03*
X271239Y335860D03*
X284759Y374860D03*
X271239Y347560D03*
X264179D03*
X277999Y374860D03*
X288139Y369010D03*
X281379Y380709D03*
Y369010D03*
X267859Y345609D03*
X281379Y372909D03*
X288139Y376809D03*
X277999Y370959D03*
X271239Y343660D03*
Y351460D03*
X264179D03*
X284759Y378760D03*
Y367060D03*
X277999Y378760D03*
X288139Y372909D03*
X247213Y515300D03*
X273910Y513114D03*
X270864Y518157D03*
X280203Y513114D03*
X277557Y518157D03*
X289124Y515514D03*
X252313D03*
X284024Y512700D03*
X247213D03*
X289124Y512914D03*
X252313D03*
X284024Y515300D03*
X260824Y513114D03*
X257478Y518157D03*
X237099Y513114D03*
X234053Y518157D03*
X267517Y513114D03*
X264171Y518157D03*
X243392Y513114D03*
X240746Y518157D03*
X270864Y528899D03*
X273824Y534700D03*
X277557Y528899D03*
X280203Y534700D03*
X289124Y531540D03*
X252313D03*
X247213Y534399D03*
X289124Y534149D03*
X252313D03*
X284050Y531750D03*
X257478Y528899D03*
X260824Y535100D03*
X234053Y528899D03*
X237013Y534700D03*
X264171Y528899D03*
X267517Y535100D03*
X240746Y528899D03*
X243392Y534700D03*
X247239Y531750D03*
X284024Y534399D03*
X314368Y-7108D03*
X324407Y-9901D03*
X327754Y-1743D03*
X321061Y-7108D03*
X341140D03*
X337793Y-4536D03*
X344486Y-9786D03*
Y-4536D03*
X351179Y-9901D03*
X354525Y-1742D03*
X354526Y-7108D03*
X311021Y-4536D03*
X347833Y-1743D03*
X300982Y65699D03*
X294289D03*
X304328Y71900D03*
X300982Y92757D03*
X304328Y87714D03*
X297635Y71900D03*
X294289Y92757D03*
X297635Y87714D03*
X308418Y216909D03*
X294899D03*
X301659D03*
X298279Y214960D03*
X305039D03*
X301659Y213009D03*
X298279Y222760D03*
X305039D03*
X328698Y236409D03*
Y244209D03*
X321938Y240309D03*
X348978Y236409D03*
X355737D03*
X342218D03*
X335458Y240309D03*
X345598Y234460D03*
X352357Y242260D03*
X308418Y220809D03*
X294899D03*
X301659Y224709D03*
X328698Y248109D03*
Y240309D03*
X301659Y220809D03*
X325318Y238360D03*
Y246160D03*
X321938Y244209D03*
X332078Y238360D03*
Y246160D03*
X301659Y279310D03*
X308418D03*
X294899D03*
X335458Y244209D03*
X348978Y267609D03*
X345598Y277360D03*
X348978Y279310D03*
Y275409D03*
Y271509D03*
X352357Y265660D03*
X355737Y263709D03*
X342218Y240309D03*
X352357Y234460D03*
X348978Y240309D03*
X355737D03*
Y228610D03*
X342218D03*
X308418Y306609D03*
X301659Y310509D03*
Y306609D03*
X311798Y304660D03*
X305039D03*
X321938Y306609D03*
X325318Y304660D03*
Y308560D03*
X298279Y304660D03*
X294899Y302709D03*
X308418D03*
X301659D03*
X315178D03*
X321938D03*
X294899Y310509D03*
Y306609D03*
X318558Y304660D03*
Y308560D03*
X321938Y291009D03*
X318558Y296860D03*
X315178Y294909D03*
X321938D03*
X301659D03*
X325318Y285160D03*
Y289060D03*
Y296860D03*
X298279D03*
Y289060D03*
Y281260D03*
X308418Y298809D03*
X301659D03*
X308418Y283209D03*
X305039Y281260D03*
Y289060D03*
X308418Y291009D03*
Y287109D03*
X311798Y281260D03*
Y289060D03*
X308418Y294909D03*
X311798Y296860D03*
X305039D03*
X315178Y287109D03*
X318558Y285160D03*
X321938Y287109D03*
X301659Y283209D03*
Y287109D03*
Y291009D03*
X294899Y298809D03*
Y294909D03*
Y291009D03*
Y283209D03*
Y287109D03*
X315178Y298809D03*
X321938D03*
X318558Y289060D03*
X315178Y291009D03*
X332078Y308560D03*
Y304660D03*
X328698Y302709D03*
Y306609D03*
Y287109D03*
Y291009D03*
Y294909D03*
Y298809D03*
X332078Y296860D03*
Y285160D03*
Y289060D03*
X315178Y306609D03*
X308418Y310509D03*
X311798Y312460D03*
X305039D03*
X298279D03*
X294899Y314409D03*
X308418D03*
X301659D03*
X335458Y298809D03*
X348978Y287109D03*
X345598Y285160D03*
Y281260D03*
X348978Y283209D03*
Y298809D03*
Y291009D03*
X345598Y289060D03*
Y292959D03*
Y296860D03*
X348978Y294909D03*
X345598Y300760D03*
X348978Y302709D03*
Y306609D03*
X345598Y304660D03*
Y308560D03*
X348978Y310509D03*
X342218Y302709D03*
Y306609D03*
Y291009D03*
Y287109D03*
Y294909D03*
Y298809D03*
X338838Y308560D03*
X335458Y302709D03*
X338838Y304660D03*
X335458Y306609D03*
Y287109D03*
X338838Y289060D03*
Y285160D03*
X335458Y291009D03*
X338838Y296860D03*
X335458Y294909D03*
X348978Y314409D03*
X345598Y312460D03*
X348978Y322209D03*
X355737Y333909D03*
X345598Y316360D03*
X348978Y318309D03*
Y330009D03*
X352357Y331960D03*
X348978Y326110D03*
X332078Y351460D03*
X321938Y357309D03*
X335458D03*
X325318Y351460D03*
X301659Y380709D03*
X328698Y361209D03*
X305039Y374860D03*
X294899Y380709D03*
X308418D03*
X298279Y374860D03*
X342218Y369010D03*
Y357309D03*
X345598Y363160D03*
Y351460D03*
X355737Y357309D03*
Y369010D03*
X352357Y351460D03*
X301659Y376809D03*
X348978Y361209D03*
X355737D03*
X332078Y359260D03*
X321938Y353409D03*
X335458D03*
X325318Y359260D03*
X328698Y357309D03*
Y349509D03*
X301659Y372909D03*
Y384609D03*
X328698Y353409D03*
X305039Y382660D03*
X294899Y376809D03*
X308418D03*
X298279Y382660D03*
X342218Y361209D03*
X345598Y355360D03*
X352357D03*
X297635Y513114D03*
X294289Y518157D03*
X304328Y513114D03*
X300982Y518157D03*
X294289Y528899D03*
X297635Y535100D03*
X300982Y528899D03*
X304328Y535100D03*
X324407Y609864D03*
X341140Y607292D03*
X337793Y609864D03*
X344486Y604614D03*
X351179Y604499D03*
X354526Y607292D03*
X334447Y612457D03*
X311021Y609864D03*
X314368Y607292D03*
X324407Y604499D03*
X321061Y607292D03*
X344486Y609864D03*
X374401Y-11346D03*
X394682Y17157D03*
X365311Y17042D03*
X404722Y-9901D03*
X394682Y11792D03*
X394683Y-2200D03*
X408068Y-7108D03*
X414761Y-1743D03*
X398029Y-9901D03*
X361218Y9114D03*
X362662Y17014D03*
X361218Y-9786D03*
X364565Y9114D03*
Y-1858D03*
Y-9786D03*
X414761Y-7108D03*
X361218Y-1858D03*
X396296Y236409D03*
X359117Y230559D03*
X379397Y234460D03*
X386157Y230559D03*
X407706Y224709D03*
X392916Y230559D03*
X399676D03*
X389537Y236409D03*
X362497D03*
X369257D03*
X365877Y230559D03*
X372637D03*
X359117Y242260D03*
X357057Y277360D03*
X368127Y264300D03*
X364747Y266300D03*
X361492Y268100D03*
X357092Y270700D03*
X359648Y269777D03*
X357057Y273460D03*
X379397Y230559D03*
X389537Y228610D03*
X392916Y234460D03*
X386157D03*
X359117D03*
X362497Y240309D03*
X376017Y236409D03*
X407706Y228610D03*
X382777Y236409D03*
X399676Y234460D03*
X382777Y228610D03*
X362497D03*
X369257D03*
X365877Y234460D03*
X372637D03*
X376017Y228610D03*
X357057Y281260D03*
Y296860D03*
Y285160D03*
Y292959D03*
Y300760D03*
Y308560D03*
Y304660D03*
Y289060D03*
Y312460D03*
X364747Y331509D03*
X361367Y329560D03*
X357987Y327609D03*
X371507Y335409D03*
X362497Y337809D03*
X369257Y341709D03*
X368127Y333460D03*
X365877Y339760D03*
X374887Y337360D03*
X381647Y341260D03*
X378267Y339309D03*
X359117Y335860D03*
X357057Y320260D03*
Y324160D03*
Y316360D03*
X403056Y369010D03*
X399676Y363160D03*
X382777Y369010D03*
X365877Y363160D03*
X372637D03*
X362497Y369010D03*
X369257D03*
X376017D03*
X389537D03*
X392916Y363160D03*
X386157D03*
X359117D03*
X379397D03*
X369257Y361209D03*
X372637Y343660D03*
X386157Y367060D03*
X403056Y372909D03*
X392916Y367060D03*
X382777Y361209D03*
X399676Y367060D03*
X389537Y361209D03*
X365877Y367060D03*
X372637D03*
X362497Y361209D03*
X379397Y367060D03*
X396296Y361209D03*
X359117Y355360D03*
X376017Y361209D03*
X394682Y588392D03*
X361518Y585714D03*
X364265D03*
X394682Y607292D03*
X414761Y612657D03*
X394682D03*
X408068Y607292D03*
X414761D03*
X361218Y612242D03*
X361964Y593642D03*
X364565Y612242D03*
X365311Y593642D03*
X364565Y604614D03*
X404722Y604499D03*
X398029D03*
X361218Y604614D03*
X421454Y-1817D03*
X448226Y11100D03*
X444880Y-9786D03*
X431494Y-9901D03*
X438187Y-9786D03*
X424801D03*
X444880Y-4536D03*
X451573Y65699D03*
Y92757D03*
X458266Y65699D03*
X474998D03*
X464758Y68550D03*
X469832Y68340D03*
X478344Y87714D03*
X464732Y89900D03*
X469832Y70949D03*
Y87514D03*
X464732Y71199D03*
Y87300D03*
X469832Y90114D03*
X460912Y71500D03*
X458266Y92757D03*
X460912Y87714D03*
X454533Y71500D03*
X454619Y87714D03*
X478344Y71900D03*
X474998Y92757D03*
X439493Y218147D03*
X459773D03*
X436113Y220096D03*
Y227896D03*
X446253Y222047D03*
Y225947D03*
X432733Y222047D03*
Y225947D03*
X442873Y220096D03*
Y227896D03*
X453013Y225947D03*
X439493Y229847D03*
Y222047D03*
Y225947D03*
X452865Y270081D03*
X439764Y263699D03*
X449288Y266435D03*
X444752Y264188D03*
X463153Y220096D03*
Y227896D03*
X473292Y222047D03*
Y225947D03*
X459773Y229847D03*
Y222047D03*
X456393Y220096D03*
X466533Y225947D03*
X453013Y222047D03*
X436113Y247396D03*
X446253Y249347D03*
X442873Y251296D03*
X439493Y249347D03*
X442873Y247396D03*
X439493Y245447D03*
X444408Y267305D03*
X440500Y266500D03*
X446253Y253247D03*
X447148Y278841D03*
X449848D03*
X450800Y275600D03*
X476672Y227896D03*
X459773Y225947D03*
X456393Y227896D03*
X466533Y222047D03*
Y261047D03*
X463153Y262996D03*
X477792Y276646D03*
X453400Y275600D03*
X473292Y261047D03*
X469913Y259096D03*
X474413Y274696D03*
X469913Y278596D03*
X466066Y292452D03*
X466100Y300021D03*
X442020Y339220D03*
X438240Y339380D03*
X449500Y309800D03*
X451648Y308341D03*
X447000Y309800D03*
X464000Y294500D03*
X454148Y310341D03*
Y307841D03*
X477792Y311747D03*
X469913Y309797D03*
Y282496D03*
X474413Y329296D03*
X468783Y332897D03*
X474413Y333196D03*
Y325396D03*
X477792Y323446D03*
X469913Y313696D03*
Y317596D03*
X467653Y379996D03*
Y387796D03*
X447373Y383896D03*
X460893D03*
X474413D03*
X450753Y389747D03*
X440613Y383896D03*
X454133D03*
X443993Y389747D03*
X448503Y344597D03*
X438363Y346546D03*
X424844D03*
X434983Y348497D03*
X428224D03*
X431604Y346546D03*
X447373Y387796D03*
X467653Y383896D03*
X447373Y379996D03*
X467653Y391696D03*
X447373D03*
X471033Y389747D03*
Y381947D03*
X460893Y387796D03*
X474413D03*
X464273Y389747D03*
Y381947D03*
X450753D03*
X440613Y387796D03*
X454133D03*
X443993Y381947D03*
X464732Y512700D03*
X469832Y512914D03*
X464732Y515300D03*
X478344Y513114D03*
X474998Y518157D03*
X454619Y513114D03*
X451573Y518157D03*
X460912Y513114D03*
X458266Y518157D03*
X469832Y515514D03*
X447735Y588394D03*
X469832Y534149D03*
X464758Y531750D03*
X474998Y528899D03*
X478344Y535100D03*
X451573Y528899D03*
X454533Y534700D03*
X458266Y528899D03*
X460912Y534700D03*
X464732Y534399D03*
X469832Y531540D03*
X447766Y612659D03*
X453250Y623320D03*
X456910D03*
X444880Y609864D03*
X438187Y604614D03*
X424801D03*
X444880D03*
X431494Y604499D03*
X481691Y65699D03*
X495077D03*
X488384D03*
X511809D03*
X501570Y68550D03*
X506644Y68340D03*
X497723Y71500D03*
X495077Y92757D03*
X497723Y87714D03*
X491344Y71500D03*
X488384Y92757D03*
X491430Y87714D03*
X511809Y92757D03*
X501544Y89900D03*
X506644Y70949D03*
Y87514D03*
X501544Y71199D03*
Y87300D03*
X506644Y90114D03*
X485037Y71900D03*
X481691Y92757D03*
X485037Y87714D03*
X518502Y65699D03*
X531888D03*
X525195D03*
X538381Y68550D03*
X538355Y89900D03*
Y71199D03*
Y87300D03*
X521848Y71900D03*
X518502Y92757D03*
X521848Y87714D03*
X515155Y71900D03*
Y87714D03*
X534534Y71500D03*
X531888Y92757D03*
X534534Y87714D03*
X528155Y71500D03*
X525195Y92757D03*
X528241Y87714D03*
X480052Y218147D03*
X521731Y216196D03*
X491312Y272747D03*
X483432Y220096D03*
X480052Y222047D03*
X498072Y280547D03*
X504832Y276647D03*
X483432Y227896D03*
X480052Y229847D03*
X494692Y223996D03*
X504832Y225947D03*
X511592Y222047D03*
X498072Y249347D03*
X508212Y274696D03*
X504832Y268847D03*
X501452Y278596D03*
X514972Y220096D03*
X531871Y241547D03*
Y249347D03*
Y237647D03*
X514972Y274696D03*
X518352Y257147D03*
X528491Y270796D03*
Y278596D03*
X535251Y255196D03*
X531871Y264947D03*
X511592Y303947D03*
X518352Y311747D03*
X528491Y305896D03*
X511592Y292245D03*
Y300047D03*
Y288347D03*
X508212Y340996D03*
X498072Y339047D03*
X504832Y327347D03*
X508212Y321496D03*
X514972Y305896D03*
Y309797D03*
X528491Y301996D03*
Y309797D03*
X525111Y311747D03*
Y307847D03*
Y303947D03*
X521731Y305896D03*
Y309797D03*
X518352Y307847D03*
X514972Y313696D03*
X528491D03*
X521731D03*
X514972Y340996D03*
X518352Y331247D03*
X521731Y321496D03*
X525111Y339047D03*
X535251Y333196D03*
Y325396D03*
X518352Y303947D03*
X481172Y383896D03*
X508212Y344896D03*
Y348796D03*
X511592Y346847D03*
Y350747D03*
Y342947D03*
X504832Y362447D03*
X494692Y368296D03*
Y352696D03*
X508212Y356596D03*
X504832Y350747D03*
X511592Y374146D03*
X501452Y383896D03*
X498072Y389747D03*
X494692Y376096D03*
X508212Y379996D03*
X521731Y368296D03*
X518352Y366347D03*
X514972Y348796D03*
Y344896D03*
Y352696D03*
X518352Y358547D03*
X521731Y344896D03*
X538631Y370247D03*
X525111Y350747D03*
X514972Y399496D03*
X538631Y381947D03*
X531871Y385847D03*
X528491Y391696D03*
X525111Y397546D03*
X487932Y387796D03*
Y391696D03*
Y379996D03*
X491312Y401447D03*
X481172Y387796D03*
X494692Y395597D03*
X484552Y381947D03*
X531871Y405347D03*
X538355Y515300D03*
X501544Y512700D03*
X506644Y512914D03*
X501544Y515300D03*
X528241Y513114D03*
X525195Y518157D03*
X534534Y513114D03*
X531888Y518157D03*
X515155Y513114D03*
X511809Y518157D03*
X491430Y513114D03*
X488384Y518157D03*
X521848Y513114D03*
X518502Y518157D03*
X497723Y513114D03*
X495077Y518157D03*
X485037Y513114D03*
X481691Y518157D03*
X506644Y515514D03*
X538355Y512700D03*
X538381Y531750D03*
X538355Y534399D03*
X501544D03*
X506644Y534149D03*
X501570Y531750D03*
X525195Y528899D03*
X528155Y534700D03*
X531888Y528899D03*
X534534Y534700D03*
X511809Y528899D03*
X515155Y535100D03*
X488384Y528899D03*
X491344Y534700D03*
X518502Y528899D03*
X521848Y535100D03*
X495077Y528899D03*
X497723Y534700D03*
X481691Y528899D03*
X485037Y535100D03*
X506644Y531540D03*
X602163Y9157D03*
X555313Y65699D03*
X548620D03*
X568699D03*
X562006D03*
X543455Y68340D03*
X565266Y87374D03*
X543455Y70949D03*
Y87514D03*
Y90114D03*
X558659Y71900D03*
X555313Y92757D03*
X558659Y87714D03*
X551966Y71900D03*
X548620Y92757D03*
X551966Y87714D03*
X571345Y71500D03*
X568699Y92757D03*
X571345Y87714D03*
X564966Y71500D03*
X562006Y92757D03*
X592124Y65699D03*
X585431D03*
X575192Y68550D03*
X580266Y68340D03*
X595470Y71900D03*
X592124Y92757D03*
X595470Y87714D03*
X588777Y71900D03*
X585431Y92757D03*
X588777Y87714D03*
X575166Y89900D03*
X580266Y70949D03*
Y87514D03*
X575166Y71199D03*
Y87300D03*
X580266Y90114D03*
X558911Y218147D03*
X552151Y237647D03*
X570400Y243500D03*
X555531Y231797D03*
X548771Y227896D03*
X552151Y245447D03*
X548771Y251296D03*
X542011Y223996D03*
X545391Y237647D03*
X572930Y232750D03*
Y228130D03*
X548771Y270796D03*
Y262996D03*
X545391Y276646D03*
X542011Y270796D03*
X580360Y234590D03*
Y230060D03*
X548771Y290296D03*
Y294196D03*
Y337096D03*
Y329296D03*
X562591Y348796D03*
X542011Y364396D03*
Y372197D03*
Y352696D03*
X545391Y342947D03*
X562006Y518157D03*
X595470Y513114D03*
X592124Y518157D03*
X571345Y513114D03*
X568699Y518157D03*
X551966Y513114D03*
X548620Y518157D03*
X558659Y513114D03*
X555313Y518157D03*
X580266Y515514D03*
X543455D03*
X575166Y512700D03*
X580266Y512914D03*
X543455D03*
X575166Y515300D03*
X588777Y513114D03*
X585431Y518157D03*
X565266Y512774D03*
X562006Y528899D03*
X564966Y534700D03*
X592124Y528899D03*
X595470Y535100D03*
X568699Y528899D03*
X571345Y534700D03*
X548620Y528899D03*
X551966Y535100D03*
X555313Y528899D03*
X558659Y535100D03*
X580266Y531540D03*
X543455D03*
X575166Y534399D03*
X543455Y534149D03*
X575192Y531750D03*
X585431Y528899D03*
X588777Y535100D03*
X580266Y534149D03*
X602163Y612657D03*
X663699Y3861D03*
X645430Y31067D03*
X656600Y31500D03*
X663300Y10000D03*
X647400Y-6900D03*
X605510Y27899D03*
Y9157D03*
X647000Y-9500D03*
X605510Y-1743D03*
Y-9901D03*
Y16999D03*
X647600Y84200D03*
X605510Y92599D03*
Y73857D03*
Y36057D03*
Y46957D03*
Y84757D03*
Y65699D03*
Y54799D03*
X618800Y100100D03*
X616115Y108339D03*
X620054Y114096D03*
X622200Y112200D03*
X616167Y118627D03*
X628673Y142718D03*
X632173Y142018D03*
X644055Y144493D03*
X642673Y139811D03*
X639173Y140618D03*
X654555Y142193D03*
X651055Y142893D03*
X647555Y143643D03*
X658055Y141493D03*
X635673Y141318D03*
X617400Y115800D03*
X605028Y119000D03*
X604977Y110200D03*
X660600Y170000D03*
Y175000D03*
X652500Y273600D03*
X647487Y280308D03*
X643591Y266983D03*
X643500Y274868D03*
X642855Y269660D03*
X633410Y269610D03*
Y274610D03*
X628950Y293550D03*
X649600Y391200D03*
X615300Y457900D03*
X624600Y419400D03*
X626737Y421000D03*
X619800Y416200D03*
X624300Y422100D03*
X627000Y423436D03*
X622900Y424200D03*
X619680Y422600D03*
X625200Y425400D03*
X621800Y421100D03*
X619700Y419500D03*
X620400Y463990D03*
X629600Y425100D03*
X622100Y417900D03*
X607012Y465997D03*
X623660Y466746D03*
X623400Y476300D03*
X656100Y486900D03*
X639197Y490367D03*
X658900Y509300D03*
X646200Y499700D03*
X648025Y501575D03*
X618800Y474500D03*
X619390Y469450D03*
X631741Y615759D03*
X644500Y594400D03*
X648180Y590702D03*
X646760Y592992D03*
X627705Y611973D03*
X629977Y613024D03*
X713824Y-18333D03*
X665942Y4716D03*
X692500Y15300D03*
X666100Y10000D03*
X712796Y-16011D03*
X701120Y19619D03*
X698470Y19669D03*
X665396Y23000D03*
X714300Y-1900D03*
X685100Y43000D03*
X670227Y34277D03*
X714000Y43900D03*
X697100Y90600D03*
X724888Y188930D03*
X709182Y203948D03*
X709200Y201300D03*
X711800Y203100D03*
X706600Y201300D03*
X715727Y218267D03*
X706500Y207800D03*
X706561Y211417D03*
Y204217D03*
X689960Y260500D03*
X720450Y249950D03*
X710900Y231660D03*
X700000Y233700D03*
X709700Y275500D03*
X709600Y278100D03*
X679300Y261700D03*
X709949Y272647D03*
X706800Y278100D03*
X723400Y250000D03*
X686470Y282220D03*
X706800Y281900D03*
X713970Y310860D03*
X711900Y327700D03*
X683490Y282110D03*
X690048Y284053D03*
Y281053D03*
X710272Y281911D03*
X683417Y364972D03*
X677563Y365496D03*
X674300Y489500D03*
X677800Y485600D03*
X680300Y485700D03*
X676600Y501300D03*
X671500D03*
X674000Y501200D03*
X720300Y485800D03*
X723792Y489148D03*
X721301Y488200D03*
X701500Y505500D03*
X710643Y505496D03*
X703800Y507100D03*
X716100Y525200D03*
X675080Y485570D03*
X711704Y525483D03*
X685200Y530500D03*
X716100Y527700D03*
X713600D03*
Y530200D03*
Y532700D03*
X716100D03*
Y530200D03*
X725000Y533700D03*
X713500Y618000D03*
X711500Y616274D03*
X755000Y17255D03*
X731210Y-15134D03*
X754600Y300D03*
X751900Y400D03*
X760100Y17255D03*
X756176Y-4300D03*
X751600Y41000D03*
X755500Y55200D03*
X733740Y95230D03*
X730923Y75315D03*
X731910Y92790D03*
X733671Y75412D03*
X753100Y92111D03*
X779921Y65699D03*
X773228D03*
X786414Y68550D03*
X782567Y71500D03*
X779921Y92757D03*
X782567Y87714D03*
X776188Y71500D03*
X773228Y92757D03*
X776274Y87714D03*
X786388Y89900D03*
Y71199D03*
Y87300D03*
X727776Y188811D03*
X779932Y212033D03*
X770300Y204930D03*
X787371Y215216D03*
Y217716D03*
X737837Y222364D03*
Y224964D03*
X740300Y228100D03*
X742937Y221174D03*
Y223774D03*
X740437Y224964D03*
Y222364D03*
X766732Y225189D03*
X779932Y244033D03*
X766632Y222589D03*
X779400Y276200D03*
X766532Y254652D03*
X766632Y257252D03*
X726328Y249979D03*
X787371Y247216D03*
Y249716D03*
Y279216D03*
X739500Y247500D03*
X749126Y220843D03*
X742897Y226773D03*
X739400Y253400D03*
X767310Y286530D03*
X779100Y307900D03*
X767000Y318500D03*
X779932Y340033D03*
X766732Y321189D03*
X787371Y281716D03*
Y311216D03*
Y313716D03*
X764980Y287980D03*
X779882Y372033D03*
X767477Y350708D03*
X766732Y353189D03*
X766643Y382724D03*
X787371Y343216D03*
Y345716D03*
X787321Y374916D03*
Y377316D03*
X767155Y385550D03*
X746130Y430130D03*
X739933Y447401D03*
X746151Y433077D03*
X728373Y488356D03*
X731339Y489319D03*
X756000Y525950D03*
X729000Y511500D03*
X731600Y511600D03*
X786388Y515300D03*
Y512700D03*
X769500Y510100D03*
X779921Y518157D03*
X782567Y513114D03*
X773228Y518157D03*
X776274Y513114D03*
X738648Y492050D03*
X736000Y537700D03*
Y535200D03*
X733500Y537700D03*
Y535200D03*
X728000Y533750D03*
X755000Y566000D03*
X786414Y531750D03*
X786388Y534399D03*
X769500Y536983D03*
X779921Y528899D03*
X776188Y534700D03*
X769500Y585700D03*
Y547900D03*
Y574700D03*
X782567Y534700D03*
X773228Y528899D03*
X733032Y604000D03*
X769500Y612583D03*
X739307Y598850D03*
X755800Y604600D03*
X753300Y593600D03*
X810039Y65699D03*
X803346D03*
X796653D03*
X816732D03*
X791488Y68340D03*
X812999Y71500D03*
X810039Y92757D03*
X813085Y87714D03*
X806692Y71900D03*
X803346Y92757D03*
X806692Y87714D03*
X799999Y71900D03*
X796653Y92757D03*
X799999Y87714D03*
X816732Y92757D03*
X791488Y70949D03*
Y87514D03*
Y90114D03*
X846850Y65699D03*
X823225Y68550D03*
X828299Y68340D03*
X840157Y65699D03*
X833464D03*
X843503Y71900D03*
X840157Y92757D03*
X843503Y87714D03*
X836810Y71900D03*
X833464Y92757D03*
X836810Y87714D03*
X846850Y92757D03*
X819378Y71500D03*
Y87714D03*
X823199Y89900D03*
X828299Y70949D03*
Y87514D03*
X823199Y71199D03*
Y87300D03*
X828299Y90114D03*
X799300Y195600D03*
Y199100D03*
X813700Y195600D03*
X790871Y215216D03*
Y217716D03*
X799620Y186547D03*
X798337Y181216D03*
X813700Y198900D03*
X804470Y186814D03*
X789500Y231800D03*
X790900Y234000D03*
Y229700D03*
X790846Y225774D03*
X790882Y221723D03*
X790871Y247216D03*
Y249716D03*
X789471Y227742D03*
X789576Y223737D03*
X789554Y219723D03*
X790900Y253900D03*
X789432Y252000D03*
X790871Y266216D03*
X789432Y255800D03*
X790867Y257724D03*
X789432Y259800D03*
X789500Y263900D03*
X790885Y261711D03*
X790871Y279216D03*
Y311216D03*
X789432Y284200D03*
Y288300D03*
Y292400D03*
X789400Y296200D03*
X790871Y298216D03*
X790937Y294270D03*
X790900Y290300D03*
Y286200D03*
X790871Y281716D03*
Y313716D03*
X789432Y319900D03*
Y323900D03*
X790900Y322000D03*
Y326000D03*
X790871Y330216D03*
X789500Y328000D03*
X789478Y315671D03*
X790800Y317700D03*
X824000Y402863D03*
X827800D03*
X832300D03*
X789432Y348100D03*
Y352100D03*
X789597Y356105D03*
X789500Y360200D03*
X790900Y358200D03*
X790835Y354048D03*
X790867Y350024D03*
X790871Y345716D03*
Y343216D03*
Y362216D03*
X790821Y374916D03*
X790900Y389300D03*
X789500Y391300D03*
X790900Y393400D03*
Y381100D03*
X789582Y383200D03*
X790900Y385300D03*
X789500Y387300D03*
X790821Y377316D03*
X789282Y379200D03*
X797000Y404700D03*
X797200Y409830D03*
X800610Y415000D03*
X798500Y412600D03*
X799999Y513114D03*
X791488Y512914D03*
Y515514D03*
X803346Y518157D03*
X806692Y513114D03*
X796653Y518157D03*
X846850D03*
X813085Y513114D03*
X810039Y518157D03*
X823199Y512700D03*
Y515300D03*
X819378Y513114D03*
X816732Y518157D03*
X828299Y515514D03*
Y512914D03*
X836810Y513114D03*
X833464Y518157D03*
X843503Y513114D03*
X840157Y518157D03*
X796653Y528899D03*
X791488Y534149D03*
Y531540D03*
X806692Y535100D03*
X803346Y528899D03*
X799999Y535100D03*
X846850Y528899D03*
X812999Y534700D03*
X823225Y531750D03*
X816732Y528899D03*
X819378Y534700D03*
X828299Y534149D03*
X836810Y535100D03*
X840157Y528899D03*
X843503Y535100D03*
X810039Y528899D03*
X823199Y534399D03*
X828299Y531540D03*
X833464Y528899D03*
X870275Y65699D03*
X860036Y68550D03*
X865110Y68340D03*
X853543Y65699D03*
X876968D03*
X856189Y71500D03*
X853543Y92757D03*
X856189Y87714D03*
X876968Y92757D03*
X849810Y71500D03*
X849896Y87714D03*
X873621Y71900D03*
X870275Y92761D03*
X873621Y87714D03*
X860010Y89900D03*
X865110Y70949D03*
Y87514D03*
X860010Y71199D03*
Y87300D03*
X865110Y90114D03*
X880314Y71900D03*
Y87714D03*
X893000Y71500D03*
X890354Y92757D03*
X893000Y87714D03*
X886621Y71500D03*
X883661Y92757D03*
X886707Y87714D03*
X910432Y71900D03*
X907086Y92757D03*
X910432Y87714D03*
X896821Y89900D03*
X901921Y70949D03*
Y87514D03*
X896821Y71199D03*
Y87300D03*
X901921Y90114D03*
X890354Y65699D03*
X883661D03*
X907086D03*
X896847Y68550D03*
X901921Y68340D03*
X882008Y321100D03*
X849896Y513114D03*
X870275Y518161D03*
X873621Y513114D03*
X860010Y515300D03*
X865110Y512914D03*
X860010Y512700D03*
X865110Y515514D03*
X853543Y518157D03*
X856189Y513114D03*
X876968Y518157D03*
X910432Y513114D03*
X896821Y515300D03*
X901921Y512914D03*
X896821Y512700D03*
X901921Y515514D03*
X880314Y513114D03*
X890354Y518157D03*
X893000Y513114D03*
X883661Y518157D03*
X907086D03*
X886707Y513114D03*
X849810Y534700D03*
X873621Y535100D03*
X860036Y531750D03*
X865110Y534149D03*
Y531540D03*
X856189Y534700D03*
X853543Y528899D03*
X876968D03*
X907086D03*
X896847Y531750D03*
X896821Y534399D03*
X901921Y531540D03*
X880314Y535100D03*
X893000Y534700D03*
X890354Y528899D03*
X886621Y534700D03*
X883661Y528899D03*
X870275D03*
X860010Y534399D03*
X910432Y535100D03*
X901921Y534149D03*
X960629Y-4536D03*
X963976Y-7108D03*
X970669D03*
X917125Y71900D03*
X913779Y92757D03*
X917125Y87714D03*
X933632Y89900D03*
Y71199D03*
Y87300D03*
X929811Y71500D03*
X927165Y92757D03*
X913779Y65699D03*
X933658Y68550D03*
X927165Y65699D03*
X920472D03*
X929811Y87714D03*
X923432Y71500D03*
X920472Y92757D03*
X923518Y87714D03*
X938732Y68340D03*
X950590Y65699D03*
X943897D03*
X947243Y87714D03*
X938732Y70949D03*
Y87514D03*
Y90114D03*
X953936Y71900D03*
X950590Y92757D03*
X953936Y87714D03*
X947243Y71900D03*
X943897Y92757D03*
X930987Y216909D03*
X958026D03*
X944507D03*
X951267Y213009D03*
Y216909D03*
X927607Y218860D03*
X934367D03*
X947887Y214960D03*
X954647D03*
X930987Y228610D03*
X937747D03*
X927607Y222760D03*
X913700Y242260D03*
X920847D03*
Y250060D03*
X927607Y226660D03*
X917467Y248109D03*
X934367Y222760D03*
X917467Y271509D03*
X913787Y257860D03*
X920847Y261760D03*
Y253960D03*
X947887Y222760D03*
X954647D03*
X951267Y220809D03*
X971546Y240309D03*
Y244209D03*
X937747Y224709D03*
X934367Y230559D03*
X913787Y246160D03*
X920847D03*
X937747Y220809D03*
X930987Y224709D03*
X937747Y279310D03*
X917000Y276000D03*
X920847Y277360D03*
X924227Y279310D03*
X913787Y273460D03*
X920847Y257860D03*
X913787Y261760D03*
X917467Y255909D03*
X916967Y279310D03*
X930987D03*
X958026Y220809D03*
X944507D03*
X951267Y224709D03*
X944507Y279310D03*
X958026D03*
X951267D03*
X913787Y335860D03*
X920847Y331960D03*
Y339760D03*
X937747Y287109D03*
X920500Y304660D03*
Y300760D03*
X930987Y302709D03*
X924227D03*
X920500Y311960D03*
X927607Y304660D03*
X924227Y306609D03*
X930987D03*
Y310509D03*
X934367Y304660D03*
X924227Y310509D03*
X920500Y308560D03*
Y289060D03*
X934367Y296860D03*
X930987Y294909D03*
X920500Y296860D03*
Y292959D03*
X927607Y296860D03*
X924227Y298809D03*
X930987D03*
X924227Y283209D03*
X927607Y281260D03*
X920500Y285500D03*
X924227Y287109D03*
X920847Y281260D03*
X930987Y287109D03*
X934367Y289060D03*
Y281260D03*
X930987Y283209D03*
X924227Y291009D03*
X930987D03*
X927607Y289060D03*
X937747Y302709D03*
Y306609D03*
Y310509D03*
Y283209D03*
Y291009D03*
Y294909D03*
Y298809D03*
X920847Y335860D03*
X913787Y331960D03*
X917467Y337809D03*
X937747Y314409D03*
X924227D03*
X930987D03*
X934367Y312460D03*
X927607D03*
X920847Y324160D03*
X924227Y318309D03*
X920547Y316160D03*
X917167Y318309D03*
Y322209D03*
X917467Y326110D03*
X920847Y320260D03*
X971546Y294909D03*
X944507Y283209D03*
X964786Y291009D03*
X954647Y281260D03*
X958026Y283209D03*
X951267Y287109D03*
X958026D03*
X951267Y283209D03*
X961406Y281260D03*
Y296860D03*
X964786Y298809D03*
Y302709D03*
X971546D03*
X961406Y304660D03*
X958026Y302709D03*
X951267D03*
X968166Y308560D03*
X964786Y306609D03*
X968166Y304660D03*
X971546Y306609D03*
X951267Y310509D03*
X954647Y304660D03*
X958026Y306609D03*
Y310509D03*
X951267Y306609D03*
X944507Y302709D03*
Y306609D03*
Y310509D03*
X941127Y304660D03*
X947887D03*
X944507Y294909D03*
Y287109D03*
X971546Y298809D03*
X968166Y285160D03*
X964786Y287109D03*
X944507Y291009D03*
X941127Y281260D03*
Y289060D03*
Y296860D03*
X944507Y298809D03*
X947887Y289060D03*
Y296860D03*
Y281260D03*
X968166Y296860D03*
X964786Y294909D03*
X971546Y291009D03*
Y287109D03*
X968166Y289060D03*
X961406D03*
X958026Y298809D03*
X951267D03*
Y291009D03*
X958026D03*
X954647Y289060D03*
Y296860D03*
X958026Y294909D03*
X951267D03*
X944507Y314409D03*
X951267D03*
X958026D03*
X961406Y312460D03*
X954647D03*
X941127D03*
X947887D03*
X934367Y367060D03*
X913787Y351460D03*
X920847D03*
X927607Y370959D03*
X917467Y345609D03*
X937747Y372909D03*
X927607Y378760D03*
X934367D03*
X971546Y357309D03*
X947887Y382660D03*
X958026Y376809D03*
X944507D03*
X954647Y382660D03*
X951267Y372909D03*
X930987Y369010D03*
X937747D03*
X913787Y347560D03*
X920847Y343660D03*
Y347560D03*
X930987Y380709D03*
X927607Y374860D03*
X934367D03*
X937747Y376809D03*
X930987Y372909D03*
X971546Y353409D03*
X964786Y349509D03*
Y353409D03*
X961406Y355360D03*
Y347560D03*
Y351460D03*
X958026Y380709D03*
X954647Y374860D03*
X951267Y376809D03*
Y384609D03*
Y380709D03*
X947887Y374860D03*
X944507Y380709D03*
X933632Y515300D03*
Y512700D03*
X927165Y518157D03*
X929811Y513114D03*
X920472Y518157D03*
X923518Y513114D03*
X913779Y518157D03*
X917125Y513114D03*
X938732Y512914D03*
Y515514D03*
X943897Y518157D03*
X947243Y513114D03*
X953936D03*
X950590Y518157D03*
X933658Y531750D03*
X929811Y534700D03*
X927165Y528899D03*
X923432Y534700D03*
X920472Y528899D03*
X917125Y535100D03*
X913779Y528899D03*
X938732Y534149D03*
Y531540D03*
X947243Y535100D03*
X950590Y528899D03*
X953936Y535100D03*
X933632Y534399D03*
X943897Y528899D03*
X963976Y607292D03*
X970669D03*
X960629Y609864D03*
X1027202Y-11005D03*
X1026700Y1700D03*
X990748Y-7108D03*
X987401Y-4536D03*
X994094Y-9786D03*
Y-4536D03*
X997441Y-1743D03*
X1000787Y-9901D03*
X1004133Y-1742D03*
X1004134Y-7108D03*
X1010826Y9114D03*
Y-1858D03*
X1012270Y17014D03*
X1010826Y-9786D03*
X1014173Y9114D03*
Y-1858D03*
X1014919Y17042D03*
X1014173Y-9786D03*
X974015Y-9901D03*
X977362Y-1743D03*
X978306Y236409D03*
Y240309D03*
Y244209D03*
X974926Y246160D03*
X985066Y240309D03*
X981686Y246160D03*
X1018865Y228610D03*
X1012105Y236409D03*
X1018865D03*
X1015485Y230559D03*
X1022245D03*
X991826Y236409D03*
Y228610D03*
X1029005Y230559D03*
X998586Y236409D03*
X1001965Y242260D03*
X1005345Y236409D03*
X1008725Y230559D03*
Y242260D03*
X1025625Y236409D03*
X1032385D03*
X1022245Y234460D03*
X991826Y240309D03*
X995206Y234460D03*
X1008725D03*
X1032385Y228610D03*
X978306Y248109D03*
X974926Y238360D03*
X985066Y244209D03*
X981686Y238360D03*
X995206Y277360D03*
X998586Y267609D03*
Y271509D03*
Y275409D03*
Y279310D03*
X1017735Y264300D03*
X1014355Y266300D03*
X1005345Y263709D03*
X1001965Y265660D03*
X1009256Y269777D03*
X1006665Y277360D03*
X1006700Y270700D03*
X1006665Y273460D03*
X1011100Y268100D03*
X1012105Y228610D03*
X1015485Y234460D03*
X1001965D03*
X998586Y240309D03*
X1025625Y228610D03*
X1005345Y240309D03*
Y228610D03*
X1012105Y240309D03*
X1029005Y234460D03*
X995206Y296860D03*
X985066Y294909D03*
Y287109D03*
X988446Y285160D03*
X991826Y287109D03*
X995206Y281260D03*
X978306Y298809D03*
Y287109D03*
X981686Y285160D03*
X978306Y294909D03*
X981686Y296860D03*
Y289060D03*
X978306Y291009D03*
X998586Y302709D03*
Y306609D03*
Y310509D03*
Y287109D03*
Y294909D03*
Y291009D03*
Y298809D03*
Y283209D03*
X985066Y302709D03*
X978306D03*
X988446Y304660D03*
Y308560D03*
X985066Y306609D03*
X995206Y304660D03*
Y308560D03*
X991826Y306609D03*
X978306D03*
X981686Y308560D03*
Y304660D03*
X974926D03*
Y308560D03*
X995206Y300760D03*
X991826Y302709D03*
X974926Y285160D03*
Y296860D03*
Y289060D03*
X995206Y292959D03*
X988446Y296860D03*
X991826Y294909D03*
X995206Y289060D03*
X988446D03*
X991826Y291009D03*
X985066D03*
X995206Y285160D03*
X985066Y298809D03*
X991826D03*
X998586Y314409D03*
X995206Y312460D03*
X998586Y318309D03*
Y322209D03*
Y326110D03*
Y330009D03*
X995206Y316360D03*
X1006665Y300760D03*
Y304660D03*
Y308560D03*
Y285160D03*
Y296860D03*
Y289060D03*
Y281260D03*
Y292959D03*
X1008725Y335860D03*
X1005345Y333909D03*
X1001965Y331960D03*
X1007595Y327609D03*
X1021115Y335409D03*
X1018865Y341709D03*
X1017735Y333460D03*
X1015485Y339760D03*
X1024495Y337360D03*
X1012105Y337809D03*
X1006665Y312460D03*
X1014355Y331509D03*
X1010975Y329560D03*
X1027875Y339309D03*
X1031255Y341260D03*
X1006665Y324160D03*
Y316360D03*
Y320260D03*
X978306Y361209D03*
X974926Y351460D03*
X981686D03*
X1015485Y367060D03*
X1022245D03*
X1012105Y361209D03*
X1018865D03*
X991826D03*
X998586D03*
X1029005Y367060D03*
X995206Y355360D03*
X1001965D03*
X1005345Y361209D03*
X1008725Y355360D03*
X1025625Y361209D03*
X1032385D03*
X985066Y357309D03*
X1018865Y369010D03*
X995206Y363160D03*
X1032385Y369010D03*
X978306Y353409D03*
Y349509D03*
Y357309D03*
X974926Y359260D03*
X981686D03*
X1022245Y343660D03*
X1025625Y369010D03*
X1015485Y363160D03*
X1022245D03*
X1012105Y369010D03*
X991826D03*
Y357309D03*
X995206Y351460D03*
X1005345Y357309D03*
Y369010D03*
X1008725Y363160D03*
X1029005D03*
X1001965Y351460D03*
X985066Y353409D03*
X1011126Y585714D03*
X1013873D03*
X990748Y607292D03*
X987401Y609864D03*
X994094D03*
X1000787Y604499D03*
X1004134Y607292D03*
X984055Y612457D03*
X1011572Y593642D03*
X1010826Y604614D03*
X1014173Y612242D03*
X1014919Y593642D03*
X974015Y609864D03*
Y604499D03*
X994094Y604614D03*
X1010826Y612242D03*
X1014173Y604614D03*
X1044290Y11792D03*
X1045525Y15357D03*
X1071062Y-1817D03*
X1094488Y-4536D03*
Y-9786D03*
X1081102Y-9901D03*
X1064369Y-7108D03*
X1054330Y-9901D03*
X1044291Y-2200D03*
X1087795Y-9786D03*
X1074409D03*
X1057676Y-7108D03*
X1064369Y-1743D03*
X1047637Y-9901D03*
X1089101Y218147D03*
X1092481Y220096D03*
Y227896D03*
X1089101Y229847D03*
X1085721Y220096D03*
X1095861Y225947D03*
X1082341D03*
X1095700Y265900D03*
X1045904Y236409D03*
X1035765Y230559D03*
X1057314Y228610D03*
X1042524Y230559D03*
X1049284D03*
X1042524Y234460D03*
X1035765D03*
X1049284D03*
X1039145Y236409D03*
X1089101Y222047D03*
Y225947D03*
X1092481Y247396D03*
X1089101Y245447D03*
X1085721Y247396D03*
X1089101Y249347D03*
X1092481Y251296D03*
X1095861Y249347D03*
X1085721Y227896D03*
X1095861Y222047D03*
X1082341D03*
X1089100Y264500D03*
X1092300Y267200D03*
X1095700Y268790D03*
X1089000Y267000D03*
X1095861Y253247D03*
X1092100Y264500D03*
X1039145Y228610D03*
X1057314Y224709D03*
X1035765Y367060D03*
X1093601Y381947D03*
X1090221Y387796D03*
X1045904Y361209D03*
X1052664Y372909D03*
X1042524Y367060D03*
X1049284D03*
X1039145Y361209D03*
X1034635Y343209D03*
X1038015Y345160D03*
X1041395Y347109D03*
X1048154D03*
X1044774Y345160D03*
X1051534D03*
X1093601Y389747D03*
X1090221Y383896D03*
X1039145Y369010D03*
X1042524Y363160D03*
X1035765D03*
X1052664Y369010D03*
X1049284Y363160D03*
X1044290Y588392D03*
X1064369Y612657D03*
X1044291Y612658D03*
X1057676Y607292D03*
X1047637Y604499D03*
X1094488Y604614D03*
X1081102Y604499D03*
X1054330D03*
X1074409Y593642D03*
X1087795Y604614D03*
X1074409D03*
X1094488Y609864D03*
X1064369Y607292D03*
X1097834Y11100D03*
X1107874Y65699D03*
X1101181D03*
X1114366Y68550D03*
X1119440Y68340D03*
X1110520Y71500D03*
X1107874Y92757D03*
X1110520Y87714D03*
X1104227D03*
X1114340Y89900D03*
X1119440Y70949D03*
Y87514D03*
X1114340Y71199D03*
Y87300D03*
X1119440Y90114D03*
X1131299Y65699D03*
X1124606D03*
X1144685D03*
X1137992D03*
X1151178Y68550D03*
X1156252Y68340D03*
X1134645Y71900D03*
X1131299Y92757D03*
X1134645Y87714D03*
X1127952Y71900D03*
X1124606Y92757D03*
X1127952Y87714D03*
X1147331Y71500D03*
X1144685Y92757D03*
X1147331Y87714D03*
X1140952Y71500D03*
X1137992Y92757D03*
X1141038Y87714D03*
X1151152Y89900D03*
X1156252Y70949D03*
Y87514D03*
X1151152Y71199D03*
Y87300D03*
X1156252Y90114D03*
X1101181Y92757D03*
X1104141Y71500D03*
X1109381Y218147D03*
X1133040Y216196D03*
X1129660Y218147D03*
X1106001Y220096D03*
X1116141Y225947D03*
X1102621Y222047D03*
Y225947D03*
X1112761Y220096D03*
Y227896D03*
X1109381Y229847D03*
X1107600Y271900D03*
X1126280Y220096D03*
X1133040Y231797D03*
X1122900Y222047D03*
Y225947D03*
X1133040Y220096D03*
X1129660Y229847D03*
X1147680Y261047D03*
X1144300Y259096D03*
X1157820Y274696D03*
X1154440Y268847D03*
X1140920Y272747D03*
X1154440Y276647D03*
X1106001Y227896D03*
X1116141Y222047D03*
X1109381D03*
Y225947D03*
X1116141Y268847D03*
X1112761Y262996D03*
X1116141Y261047D03*
X1126280Y227896D03*
X1133040D03*
X1129660Y225947D03*
Y222047D03*
X1144300Y223996D03*
X1154440Y225947D03*
X1147680Y245447D03*
Y249347D03*
X1151060Y278596D03*
X1116096Y295809D03*
X1113900Y297800D03*
X1119521Y309797D03*
Y313696D03*
Y317596D03*
X1127400Y311747D03*
X1144300Y317596D03*
X1130780Y329296D03*
X1103741Y387796D03*
X1100361Y381947D03*
X1113881Y389747D03*
X1110501Y383896D03*
X1117261Y379996D03*
X1096981Y391696D03*
X1117261Y383896D03*
Y387796D03*
X1124021Y383896D03*
X1120641Y389747D03*
X1144300Y399496D03*
X1130780Y383896D03*
Y387796D03*
X1140920Y393647D03*
X1137540Y379996D03*
Y383896D03*
Y387796D03*
X1140920Y401447D03*
X1103741Y383896D03*
X1113881Y381947D03*
X1110501Y387796D03*
X1096981Y383896D03*
X1117261Y391696D03*
X1096981Y379996D03*
Y387796D03*
X1124021D03*
X1120641Y381947D03*
X1134160Y389747D03*
X1144300Y395597D03*
X1137540Y391696D03*
X1134160Y381947D03*
X1100361Y389747D03*
X1110520Y513114D03*
X1104227D03*
X1119440Y515514D03*
X1151152Y515300D03*
X1156252Y512914D03*
X1151152Y512700D03*
X1156252Y515514D03*
X1127952Y513114D03*
X1144685Y518157D03*
X1147331Y513114D03*
X1137992Y518157D03*
X1141038Y513114D03*
X1114340Y512700D03*
X1119440Y512914D03*
X1114340Y515300D03*
X1124606Y518157D03*
X1101181D03*
X1131299D03*
X1107874D03*
X1134645Y513114D03*
X1107874Y528899D03*
X1101181D03*
X1097343Y588394D03*
X1156252Y534149D03*
X1151152Y534399D03*
X1156252Y531540D03*
X1147331Y534700D03*
X1144685Y528899D03*
X1140952Y534700D03*
X1137992Y528899D03*
X1119440Y534149D03*
X1114366Y531750D03*
X1127952Y535100D03*
X1104141Y534700D03*
X1131299Y528899D03*
X1110520Y534700D03*
X1119440Y531540D03*
X1151178Y531750D03*
X1124606Y528899D03*
X1114340Y534399D03*
X1134645Y535100D03*
X1168110Y65699D03*
X1161417D03*
X1174803D03*
X1171456Y71900D03*
X1168110Y92757D03*
X1171456Y87714D03*
X1164763Y71900D03*
X1161417Y92757D03*
X1164763Y87714D03*
X1177763Y71500D03*
X1174803Y92757D03*
X1177849Y87714D03*
X1181496Y92757D03*
X1184142Y71500D03*
Y87714D03*
X1208267Y71900D03*
X1204921Y92757D03*
X1208267Y87714D03*
X1201574Y71900D03*
X1198228Y92757D03*
X1201574Y87714D03*
X1218307Y92757D03*
X1214574Y71500D03*
X1211614Y92757D03*
X1214874Y87374D03*
X1187963Y89900D03*
X1193063Y70949D03*
Y87514D03*
X1187963Y71199D03*
Y87300D03*
X1181496Y65699D03*
X1204921D03*
X1198228D03*
X1218307D03*
X1211614D03*
X1187989Y68550D03*
X1193063Y68340D03*
Y90114D03*
X1208519Y218147D03*
X1171339Y216196D03*
X1209033Y183907D03*
X1181479Y218147D03*
X1191619Y208397D03*
X1178099Y223996D03*
X1191619D03*
X1164580Y274696D03*
X1167960Y222047D03*
X1164580Y220096D03*
X1167960Y233746D03*
X1161200Y222047D03*
X1167960Y257147D03*
X1181479Y249347D03*
Y237647D03*
Y241547D03*
X1184859Y223996D03*
X1201759Y237647D03*
X1198379Y227896D03*
X1205139Y231797D03*
X1201759Y245447D03*
X1194999Y237647D03*
X1198379Y251296D03*
X1184859Y255196D03*
X1174719Y272747D03*
X1159390Y262460D03*
X1171339Y255196D03*
X1161200Y300047D03*
Y303947D03*
X1198379Y290296D03*
Y294196D03*
X1164580Y391696D03*
X1184859Y379996D03*
X1188239Y350747D03*
X1191619Y356596D03*
X1184859Y372197D03*
X1181479Y366347D03*
Y362447D03*
X1188239D03*
Y358547D03*
Y354647D03*
X1184859Y376096D03*
X1171339Y391696D03*
X1178099Y376096D03*
X1171339Y395596D03*
X1174719Y389747D03*
X1171339Y383896D03*
X1161200Y389747D03*
X1164580Y395597D03*
X1178099Y387796D03*
X1181479Y378047D03*
X1188239Y374146D03*
X1184859Y368296D03*
Y364396D03*
X1181479Y358547D03*
X1184859Y360496D03*
X1181479Y381947D03*
X1164580Y387796D03*
X1174719Y385847D03*
X1178099Y383896D03*
Y379996D03*
X1167960Y393647D03*
X1171339Y387796D03*
X1161417Y518157D03*
X1174803D03*
X1177849Y513114D03*
X1168110Y518157D03*
X1171456Y513114D03*
X1181496Y518157D03*
X1184142Y513114D03*
X1204921Y518157D03*
X1208267Y513114D03*
X1198228Y518157D03*
X1201574Y513114D03*
X1211614Y518157D03*
X1214874Y512774D03*
X1187963Y515300D03*
X1193063Y512914D03*
X1187963Y512700D03*
X1193063Y515514D03*
X1218307Y518157D03*
X1164763Y513114D03*
Y535100D03*
X1177763Y534700D03*
X1174803Y528899D03*
X1171456Y535100D03*
X1168110Y528899D03*
X1184142Y534700D03*
X1181496Y528899D03*
X1208267Y535100D03*
X1204921Y528899D03*
X1201574Y535100D03*
X1198228Y528899D03*
X1218307D03*
X1214574Y534700D03*
X1211614Y528899D03*
X1187989Y531750D03*
X1193063Y534149D03*
X1187963Y534399D03*
X1193063Y531540D03*
X1161417Y528899D03*
X1251771Y9157D03*
X1241732Y65699D03*
X1267959Y47245D03*
X1268111Y58040D03*
X1241732Y92757D03*
X1245078Y71900D03*
Y87714D03*
X1238385Y71900D03*
Y87714D03*
X1220953Y71500D03*
Y87714D03*
X1235039Y92757D03*
X1224774Y89900D03*
X1229874Y70949D03*
Y87514D03*
X1224774Y71199D03*
Y87300D03*
X1235039Y65699D03*
X1224800Y68550D03*
X1229874Y68340D03*
Y90114D03*
X1257800Y110900D03*
X1263798Y133493D03*
X1272100Y141603D03*
X1255400Y108000D03*
X1261800Y154973D03*
X1260737Y133877D03*
X1257800Y120800D03*
X1233902Y173337D03*
X1246655Y176395D03*
X1244410Y173150D03*
X1246910D03*
X1242800Y175200D03*
X1241712Y187710D03*
X1229780Y181980D03*
Y178980D03*
X1232780Y181980D03*
X1226914Y184708D03*
X1232780Y178980D03*
X1226780D03*
Y181980D03*
X1277978Y491571D03*
X1262843Y497553D03*
X1266162Y496404D03*
X1269006Y496016D03*
X1241732Y518157D03*
X1245078Y513114D03*
X1238385D03*
X1278573Y519596D03*
X1220953Y513114D03*
X1235039Y518157D03*
X1224774Y515300D03*
X1229874Y512914D03*
X1224774Y512700D03*
X1229874Y515514D03*
X1274576Y510235D03*
X1271300Y510600D03*
X1255120Y510158D03*
Y518000D03*
Y574834D03*
X1277200Y539100D03*
X1277137Y547393D03*
X1279318Y545212D03*
X1245078Y535100D03*
X1241732Y528899D03*
X1238385Y535100D03*
X1251771Y574857D03*
X1235039Y528899D03*
X1224800Y531750D03*
X1229874Y534149D03*
X1224774Y534399D03*
X1229874Y531540D03*
X1255120Y537034D03*
Y555144D03*
X1220953Y534700D03*
X1270400Y593600D03*
X1255120D03*
X1303774Y-18842D03*
X1292692Y1008D03*
X1299369Y-15680D03*
X1282252Y-14747D03*
X1284859Y-14524D03*
X1296908Y36900D03*
X1295581Y94320D03*
X1298422Y74000D03*
X1301219Y89141D03*
X1309700Y83300D03*
X1317195Y87098D03*
X1304685Y78827D03*
X1336850Y76450D03*
X1317300Y84600D03*
X1327500Y68000D03*
X1327467Y70786D03*
X1327500Y65300D03*
X1325100Y145000D03*
X1327900Y142918D03*
X1287790Y156575D03*
X1310098Y150040D03*
X1323026Y133323D03*
X1326026D03*
X1320500Y145000D03*
X1315180Y169950D03*
X1315130Y164870D03*
X1295500Y159970D03*
X1299907Y159808D03*
X1310061Y165235D03*
X1305171Y164767D03*
X1338224Y209051D03*
X1334724D03*
X1300300Y169900D03*
X1283720Y223870D03*
X1288800Y233900D03*
X1336900Y232118D03*
X1325900D03*
X1314900D03*
X1342400D03*
X1331400D03*
X1320400D03*
X1315100Y237645D03*
X1325900Y237900D03*
X1342400D03*
X1331400D03*
X1320289Y237671D03*
X1323734Y279663D03*
X1330171Y276035D03*
X1336448Y271755D03*
X1340248D03*
X1333680Y276035D03*
X1327243Y279663D03*
X1336900Y237900D03*
X1336240Y301243D03*
X1341740D03*
X1318751Y282730D03*
X1322260D03*
X1342570Y368220D03*
X1331770Y399490D03*
X1319320Y418900D03*
X1316820Y421400D03*
Y418900D03*
X1339600Y515800D03*
X1341050Y498275D03*
X1287770Y501897D03*
X1295090Y579360D03*
X1293290Y581160D03*
X1343100Y566300D03*
X1340700D03*
X1338000D03*
X1340526Y563337D03*
X1343026D03*
X1338026D03*
X1333026D03*
X1335526D03*
Y566237D03*
X1327956Y545655D03*
X1324707Y545493D03*
X1333026Y566237D03*
X1296295Y615596D03*
X1301384Y618119D03*
X1380300Y2944D03*
X1382151Y-5545D03*
X1381642Y25898D03*
X1400616Y13795D03*
X1380219Y5581D03*
X1351908Y40402D03*
X1362448Y43413D03*
X1376989Y46971D03*
X1359500Y83000D03*
X1355500D03*
X1362674Y46058D03*
X1348945Y40264D03*
X1358500Y74500D03*
X1379110Y45033D03*
X1363500Y77400D03*
X1345000Y104500D03*
X1371500Y101000D03*
X1399400Y126400D03*
X1344462Y209272D03*
X1359500Y209200D03*
X1356926Y209100D03*
X1362000Y209300D03*
X1353569Y208960D03*
X1348569D03*
X1358900Y232118D03*
X1347900D03*
X1353400D03*
X1380900D03*
X1369900D03*
X1397400D03*
X1386400D03*
X1375400D03*
X1364400D03*
X1397400Y237900D03*
X1375400D03*
X1364400D03*
X1353400D03*
X1377522Y265600D03*
X1366312Y265525D03*
X1352468Y265695D03*
X1343668Y268095D03*
X1381031Y265600D03*
X1347468Y268095D03*
X1356268Y265695D03*
X1362803Y265525D03*
X1391900Y237900D03*
X1380900D03*
X1369900D03*
X1358900D03*
X1347900D03*
X1391900Y232118D03*
X1386400Y237900D03*
X1347892Y299741D03*
X1369320Y301219D03*
X1358514Y300815D03*
X1392135Y302051D03*
X1380601Y301465D03*
X1353672Y299605D03*
X1397635Y302051D03*
X1386101Y301465D03*
X1374820Y301219D03*
X1364014Y300815D03*
X1403037Y302046D03*
X1394370Y384230D03*
X1378207Y394568D03*
X1369407Y396668D03*
X1388900Y387800D03*
X1390100Y452500D03*
Y457500D03*
X1395100Y447500D03*
X1383263Y493673D03*
X1344761Y498282D03*
X1373345Y519940D03*
X1360741Y486523D03*
X1381041Y482575D03*
X1362841Y492823D03*
X1380741Y487489D03*
X1383241Y498595D03*
X1362880Y497556D03*
X1360863Y481673D03*
X1387986Y574960D03*
X1390595Y549328D03*
X1361600Y559400D03*
X1355548Y559959D03*
X1361926Y584037D03*
Y586537D03*
X1359100Y586200D03*
X1357400Y588400D03*
X1360100D03*
X1344613Y556376D03*
Y561376D03*
Y558876D03*
X1347700Y554100D03*
X1344613Y553876D03*
X1358439Y559959D03*
X1382032Y560143D03*
X1376070Y559760D03*
X1382200Y562700D03*
X1379000Y561500D03*
X1364426Y586637D03*
Y584137D03*
X1382500Y579100D03*
X1360500Y570900D03*
Y574700D03*
X1360261Y578873D03*
X1360247Y567390D03*
X1360261Y562373D03*
Y581373D03*
X1362000Y576700D03*
Y572800D03*
X1362100Y569100D03*
X1362000Y565600D03*
X1375961Y569473D03*
X1376000Y565700D03*
X1375961Y562273D03*
X1363761Y581373D03*
X1383074Y581963D03*
X1385000Y602700D03*
X1386921Y620689D03*
X1390851D03*
X1357726Y591037D03*
X1360226D03*
X1363761Y612573D03*
X1360261D03*
X1360200Y597800D03*
X1361600Y599900D03*
X1361500Y595700D03*
X1360100Y610100D03*
X1360200Y606300D03*
Y602000D03*
X1361900Y608200D03*
X1361500Y604200D03*
X1360261Y593573D03*
X1363761Y610073D03*
X1410600Y9100D03*
X1464150Y235550D03*
X1454056Y266169D03*
X1454000Y259700D03*
X1419220Y301983D03*
X1408537Y302046D03*
X1413720Y301983D03*
X1446700Y387900D03*
X1458300Y442675D03*
X1439000Y423000D03*
X1439813Y409422D03*
X1439651Y412466D03*
X1442830Y406472D03*
X1443252Y409029D03*
X1407884Y512751D03*
X1452188Y487223D03*
X1449568Y487276D03*
X1458935Y512470D03*
X1438390Y527175D03*
X1436396Y477691D03*
X1413041Y477423D03*
X1412941Y489523D03*
X1436441Y489323D03*
X1412741Y494223D03*
X1436541Y494423D03*
X1436600Y482900D03*
X1413193Y482532D03*
X1436358Y525142D03*
X1410486Y529792D03*
X1439861Y540497D03*
X1436160Y561200D03*
X1441409Y561117D03*
X1447022Y546578D03*
X1449922Y546664D03*
X1418402Y562624D03*
X1438799Y542785D03*
X1439123Y545294D03*
X1451533Y527867D03*
X1413600Y531300D03*
X1432560Y561160D03*
X1419600Y531500D03*
X1453533Y532667D03*
X1415582Y562904D03*
X1439822Y537382D03*
X1506300Y-6600D03*
X1498800Y-12676D03*
X1477100Y2400D03*
X1514400Y3500D03*
X1520100D03*
X1516900D03*
X1527600D03*
X1476761Y152725D03*
X1489053Y103325D03*
X1524284Y112773D03*
X1526728Y124168D03*
X1490178Y112315D03*
X1488800Y145000D03*
X1496150Y148115D03*
X1514425Y134180D03*
X1493069Y152834D03*
X1514425Y137980D03*
X1520150Y127600D03*
X1500703Y158233D03*
X1507524Y218600D03*
X1510800Y193330D03*
X1497237Y217281D03*
X1513900Y218000D03*
X1478611Y209695D03*
X1478089Y182650D03*
X1511100Y186275D03*
X1487716Y218650D03*
X1510638Y166240D03*
X1492469Y179387D03*
X1494939Y159500D03*
X1516872Y208863D03*
X1504706Y164871D03*
X1527657Y278700D03*
X1477397Y256657D03*
X1491438Y221137D03*
X1523580Y237960D03*
X1509800Y244676D03*
X1499472Y250370D03*
X1504772Y259229D03*
X1479700Y224801D03*
X1475004Y246287D03*
X1512790Y240099D03*
X1516613Y240656D03*
X1520413Y239498D03*
X1482400Y248000D03*
X1525650Y248700D03*
X1502165Y251200D03*
X1526936Y307015D03*
X1484100Y330115D03*
X1510851Y340113D03*
X1513796Y330680D03*
X1497997Y338546D03*
X1527537Y330048D03*
X1526900Y292866D03*
X1493268Y293943D03*
X1501550Y293750D03*
X1472500Y334800D03*
X1523935Y318901D03*
X1495810Y341200D03*
X1512182Y293317D03*
X1507200Y356000D03*
X1489475Y387654D03*
X1514265Y355542D03*
X1520429Y354379D03*
X1525561Y350253D03*
X1511000Y350627D03*
X1478607Y359082D03*
X1478612Y361670D03*
X1507154Y353100D03*
X1524746Y356717D03*
Y354217D03*
X1522476Y361907D03*
X1507200Y358700D03*
X1514925Y358844D03*
X1489838Y350011D03*
X1483740Y359550D03*
X1483664Y362914D03*
X1489915Y352637D03*
X1499225Y391034D03*
X1488479Y362967D03*
Y360367D03*
Y357767D03*
X1517367Y349964D03*
X1515500Y448250D03*
X1520675Y463826D03*
X1493375Y443546D03*
X1489475Y414694D03*
X1493375D03*
Y421454D03*
X1489475D03*
X1487525Y460446D03*
X1524575Y463826D03*
X1518675Y451425D03*
X1516775Y457066D03*
X1524575Y407624D03*
X1509200Y410450D03*
X1485250Y408017D03*
X1491425Y446926D03*
X1524950Y429350D03*
X1505462Y434630D03*
X1524950Y413600D03*
X1497273Y407610D03*
X1516775Y463826D03*
X1487525Y440166D03*
X1491425D03*
X1489475Y443546D03*
X1487500Y424600D03*
X1491400D03*
X1467290Y428013D03*
X1469900D03*
X1491425Y460446D03*
X1485030Y463690D03*
X1489475Y463826D03*
X1515389Y451400D03*
X1521800D03*
X1518650Y448250D03*
X1491425Y480726D03*
X1495325Y473966D03*
X1499225Y467206D03*
X1470643Y495299D03*
X1482958Y486118D03*
X1476800Y507300D03*
X1490929Y507104D03*
X1506060Y508180D03*
X1501490Y504988D03*
X1505743Y516117D03*
X1511215Y507781D03*
X1512400Y519020D03*
X1493930Y522800D03*
X1488410Y517810D03*
X1497267Y505323D03*
X1483804Y509928D03*
X1501175Y477346D03*
X1493375D03*
X1497275Y470586D03*
X1495325Y467206D03*
X1493375Y470586D03*
X1499225Y473966D03*
X1497275Y477346D03*
X1489475D03*
X1491425Y467206D03*
X1511126Y503038D03*
X1500655Y516122D03*
X1488293Y508000D03*
X1481975Y507975D03*
X1508626Y503038D03*
X1506985Y510645D03*
X1510005Y518155D03*
X1498277Y508239D03*
X1490100Y520000D03*
X1485693Y508000D03*
X1479375Y507975D03*
X1507405Y518155D03*
X1498055Y516122D03*
X1509585Y510645D03*
X1500877Y508239D03*
X1492700Y520000D03*
X1489380Y546030D03*
X1478700Y533700D03*
X1467839Y618964D03*
X1470356Y618000D03*
X1505679Y620111D03*
X1472932Y619131D03*
X1508550Y619810D03*
X1584000Y-16100D03*
X1580398Y5400D03*
X1549600Y-10800D03*
X1557981Y141470D03*
X1572395Y110754D03*
X1541434Y139871D03*
X1553500Y121000D03*
X1555676Y123283D03*
X1530101Y132671D03*
X1566486Y181270D03*
X1566858Y175192D03*
X1568488Y164058D03*
X1571501Y180031D03*
X1557787Y192236D03*
X1561925Y192675D03*
X1535000Y207200D03*
X1535425Y188016D03*
X1549693Y196707D03*
X1548178Y190880D03*
X1545910Y199977D03*
X1546000Y197400D03*
X1543100Y184128D03*
X1562150Y160700D03*
X1571876Y255800D03*
X1570318Y238116D03*
X1572700Y239400D03*
X1531935Y224160D03*
X1537972Y236000D03*
X1541325Y245090D03*
X1547375Y245850D03*
X1577486Y307621D03*
X1587800Y308200D03*
X1581090Y338795D03*
X1569211Y331542D03*
Y334142D03*
X1566910Y315117D03*
X1583500Y303120D03*
Y300560D03*
X1573950Y338050D03*
X1530500Y287700D03*
X1533914Y286073D03*
X1564427Y311083D03*
X1554775Y295328D03*
X1560024Y329200D03*
X1551404Y309376D03*
X1534400Y296029D03*
X1564411Y315210D03*
X1559500Y290300D03*
X1552900Y281700D03*
X1540175Y387654D03*
X1565525Y397794D03*
X1563575Y387654D03*
X1551875Y401174D03*
X1563575Y380894D03*
X1567475Y401174D03*
X1576074Y359600D03*
X1582600Y389300D03*
X1571450Y359650D03*
X1565525Y391034D03*
X1570289Y384368D03*
X1586500Y354900D03*
X1589100Y358400D03*
X1569425Y397794D03*
X1587683Y397414D03*
X1571375Y387654D03*
X1529829Y362655D03*
X1530425Y391034D03*
X1533589Y366361D03*
X1557725Y377514D03*
X1559675Y401174D03*
X1542125Y397794D03*
X1558950Y363050D03*
X1547975Y394414D03*
Y387654D03*
X1536275D03*
Y394414D03*
X1560500Y350000D03*
X1543528Y352446D03*
X1546182Y355446D03*
X1586500Y358400D03*
X1587684Y362653D03*
X1587032Y350996D03*
X1565525Y453686D03*
X1536275Y463826D03*
X1557725Y460446D03*
X1563575Y450306D03*
X1580370Y462090D03*
X1584200Y462610D03*
X1587559Y423835D03*
X1588870Y440546D03*
X1587573Y445300D03*
X1587000Y411976D03*
X1584233Y427947D03*
X1585560Y421324D03*
X1581939Y426594D03*
X1532375Y463826D03*
Y407934D03*
X1538225Y460446D03*
X1559675Y407934D03*
X1551875Y450306D03*
X1536275Y407934D03*
X1540175D03*
X1540700Y413600D03*
X1543850Y445100D03*
Y451400D03*
X1549926Y411312D03*
X1544150Y409900D03*
X1553825Y446926D03*
Y440166D03*
X1557725Y404554D03*
X1530425Y467206D03*
X1584970Y472370D03*
X1568400Y503300D03*
X1534039Y502906D03*
X1531580Y510790D03*
X1534020Y511930D03*
X1534325Y467206D03*
X1538225D03*
X1542125D03*
X1542475Y504400D03*
X1542425Y512200D03*
X1555424Y504609D03*
X1555832Y512288D03*
X1548300Y506600D03*
X1565389Y585721D03*
X1566520Y623382D03*
X1569495Y623365D03*
X1573500Y619500D03*
X1535565Y591658D03*
X1560747Y623576D03*
X1557575Y623559D03*
X1540477Y620308D03*
X1577000Y619500D03*
X1623900Y4600D03*
X1597504Y-17346D03*
X1601102Y-600D03*
X1648748Y6325D03*
X1638865Y11105D03*
X1629148Y6825D03*
X1619798Y10755D03*
X1643865Y11105D03*
X1634148Y6825D03*
X1624798Y10755D03*
X1651298Y39462D03*
X1641848D03*
X1632398Y39862D03*
X1606797Y64949D03*
X1608452Y62890D03*
X1622635Y39900D03*
X1646848Y39462D03*
X1637398Y39862D03*
X1627715Y39934D03*
X1632006Y94500D03*
X1593241Y134295D03*
X1648000Y100597D03*
X1598449Y120760D03*
X1598300Y116477D03*
X1630836Y197560D03*
X1593218Y191776D03*
X1595291Y166423D03*
X1598006Y192421D03*
X1611761Y216250D03*
X1651000Y178628D03*
X1642457Y186948D03*
X1637870Y195077D03*
X1644290Y196383D03*
X1629595Y217725D03*
X1627326Y182759D03*
X1615362Y213507D03*
X1615553Y184908D03*
X1608056Y184771D03*
X1647852Y197374D03*
X1635621Y208259D03*
X1637281Y254322D03*
X1636684Y279815D03*
X1627024Y253387D03*
X1627043Y256900D03*
X1637281Y260922D03*
X1643106Y233913D03*
X1601870Y270470D03*
X1626124Y225250D03*
X1609051Y243415D03*
X1626291Y273309D03*
X1597201Y238188D03*
X1621164Y223392D03*
X1620250Y254741D03*
X1621164Y225910D03*
X1620240Y257660D03*
X1617498Y273433D03*
X1598028Y256422D03*
X1600552Y261281D03*
X1636684Y277315D03*
X1606849Y241210D03*
X1622000Y279495D03*
X1592110Y322002D03*
X1590176Y331844D03*
X1590212Y315425D03*
X1636800Y287956D03*
X1636922Y302588D03*
X1636861Y305091D03*
X1619897Y338636D03*
Y341136D03*
X1602776Y331304D03*
X1625846Y286154D03*
X1638063Y326504D03*
X1636822Y294946D03*
X1636925Y297444D03*
X1636822Y292446D03*
X1636684Y283141D03*
X1620159Y332004D03*
X1625400Y327667D03*
X1608764Y322440D03*
X1603307Y393224D03*
X1590218Y350995D03*
X1638991Y352037D03*
X1630408Y357603D03*
X1630476Y360103D03*
X1629300Y385400D03*
X1630240Y365099D03*
X1643150Y348692D03*
X1643700Y351667D03*
X1630337Y362600D03*
X1621727Y395374D03*
X1609271Y348166D03*
X1608850Y343835D03*
X1613452Y387098D03*
X1610140Y358350D03*
X1610370Y361890D03*
X1607412Y360895D03*
X1602215Y363981D03*
X1621800Y386300D03*
Y381500D03*
X1630800Y378500D03*
X1590154Y354762D03*
X1630750Y404800D03*
X1591446Y440472D03*
X1591350Y445300D03*
X1640000Y456900D03*
X1640100Y459700D03*
X1630200Y457175D03*
X1630150Y427663D03*
X1611642Y461877D03*
X1600400Y446100D03*
X1603000Y435500D03*
X1630276Y449517D03*
X1612183Y442623D03*
X1603050Y432523D03*
X1639750Y445477D03*
X1639500Y433200D03*
X1639774Y439486D03*
X1646451Y452590D03*
X1646469Y450090D03*
X1646525Y447590D03*
X1647200Y430450D03*
X1612825Y408974D03*
X1615061Y463157D03*
X1603000Y422971D03*
X1630200Y454675D03*
X1621226Y445026D03*
X1612256Y440088D03*
X1611935Y429515D03*
X1612250Y435500D03*
X1590037Y432515D03*
X1630159Y520608D03*
X1627622Y524928D03*
X1590580Y472370D03*
X1594280D03*
X1637500Y529400D03*
X1626518Y528029D03*
X1622040Y554827D03*
X1609829Y556599D03*
X1624293Y561747D03*
X1615030Y584260D03*
X1603060Y582920D03*
X1603120Y578020D03*
X1599170Y572780D03*
X1602000Y565700D03*
X1631975Y527700D03*
X1625094Y559200D03*
X1601825Y572325D03*
X1607533Y561644D03*
X1601825Y568325D03*
X1607533Y557644D03*
X1605994Y578500D03*
Y582500D03*
X1625094Y555200D03*
X1644856Y604930D03*
X1640921Y605334D03*
X1622330Y592325D03*
X1613721D03*
X1614700Y597000D03*
X1615862Y605507D03*
X1601489Y602812D03*
X1601270Y597200D03*
X1602150Y610720D03*
X1685948Y10725D03*
X1680033Y-16711D03*
X1688000Y3000D03*
X1676819Y-16779D03*
X1653748Y6325D03*
X1676428Y11381D03*
X1666979Y6236D03*
X1657369Y10258D03*
X1690948Y10725D03*
X1681428Y11381D03*
X1671979Y6236D03*
X1662373Y10154D03*
X1689155Y77991D03*
X1679648Y39462D03*
X1670198D03*
X1660748D03*
X1689098D03*
X1667000Y88000D03*
X1677573Y86930D03*
X1677649Y90301D03*
X1675062Y91219D03*
X1656298Y39462D03*
X1694098D03*
X1684648D03*
X1675198D03*
X1665748D03*
X1654685Y121790D03*
X1664135Y131239D03*
X1657835D03*
X1664500Y99000D03*
X1698927Y153139D03*
X1674019Y175990D03*
X1663566Y213009D03*
X1681352Y196092D03*
X1686183Y191250D03*
X1683484Y190908D03*
X1708350Y175050D03*
X1667356Y213096D03*
X1660440Y200789D03*
X1687550Y213751D03*
X1709900Y187300D03*
X1669849Y193067D03*
X1695734Y164676D03*
X1691439Y174354D03*
X1659643Y213505D03*
X1676924Y196731D03*
X1666345Y241987D03*
X1683729Y242346D03*
X1661186Y245352D03*
X1662000Y250008D03*
X1666329Y245139D03*
X1662956Y243582D03*
X1681760Y245500D03*
X1684509Y245631D03*
X1683615Y250493D03*
X1681116Y238614D03*
X1681632Y233665D03*
X1684300Y233579D03*
X1680769Y242605D03*
X1679100Y294500D03*
Y286593D03*
Y289500D03*
X1661243Y390364D03*
Y392943D03*
X1664829Y379194D03*
X1664905Y376695D03*
X1667809Y427809D03*
X1667729Y424621D03*
X1667946Y412987D03*
X1661470Y456251D03*
X1661522Y453751D03*
X1676304Y449794D03*
X1676287Y447244D03*
X1667588Y434149D03*
X1667649Y430849D03*
X1667462Y440735D03*
X1669962D03*
X1675744Y456200D03*
X1664762Y443735D03*
X1669816Y443953D03*
Y446453D03*
X1673064Y446022D03*
X1679145Y461950D03*
X1673068Y448522D03*
X1673074Y453185D03*
X1675120Y439731D03*
X1664762Y440735D03*
X1676041Y458884D03*
X1655790Y476593D03*
X1687741Y466988D03*
X1698354Y486873D03*
X1687443Y487203D03*
X1695658Y486945D03*
X1692443Y487259D03*
X1681650Y510673D03*
X1687606Y500938D03*
X1672265Y473600D03*
X1665047Y467257D03*
X1689943Y487203D03*
X1687500Y484000D03*
X1653960Y562930D03*
X1699600Y578100D03*
X1664113Y548380D03*
X1658466D03*
X1686036Y548251D03*
X1677300Y550200D03*
X1680007Y547917D03*
X1669121Y547923D03*
X1708140Y547538D03*
X1697839Y545759D03*
X1680000Y550544D03*
X1658754Y551000D03*
X1669600Y550544D03*
X1685000D03*
X1663754Y551000D03*
X1674600Y550544D03*
X1652669Y582350D03*
Y578350D03*
X1709950Y592900D03*
X1755500Y9076D03*
X1734875Y9238D03*
X1749085Y9177D03*
X1757998Y73637D03*
X1725474Y69250D03*
X1766240Y70500D03*
X1769250Y70350D03*
X1746491Y95650D03*
X1765015Y119100D03*
X1713596Y175795D03*
X1715837Y246178D03*
X1724181Y246159D03*
X1768700Y233644D03*
X1733900Y237300D03*
X1736400D03*
X1719080Y236152D03*
X1766077Y232681D03*
X1749462Y232955D03*
X1737150Y450850D03*
X1719317Y441947D03*
X1742900Y485000D03*
X1734000Y488100D03*
X1755000Y485000D03*
X1748600D03*
X1749396Y493969D03*
X1751868Y494045D03*
X1770325Y490255D03*
X1773500Y472100D03*
X1767300Y472700D03*
X1765325Y490255D03*
X1758500Y493800D03*
X1760900Y472800D03*
X1733830Y502650D03*
X1740400Y496300D03*
X1728700Y502600D03*
X1762715Y521085D03*
X1725694Y571814D03*
X1754000Y553500D03*
X1743500Y564500D03*
X1759500Y554500D03*
X1730759Y548162D03*
X1764300Y570900D03*
X1738216Y548239D03*
X1753807Y548183D03*
X1757478Y548192D03*
X1737958Y560500D03*
X1767529Y566200D03*
X1733368Y579868D03*
X1770600Y600800D03*
X1766400Y599400D03*
X1718037Y597184D03*
X1762062Y592055D03*
Y589555D03*
X1804800Y-1500D03*
X1823300Y21700D03*
X1795078Y11900D03*
X1790078Y11860D03*
X1804462Y8830D03*
X1799462D03*
X1815150Y26650D03*
X1813795Y12165D03*
X1808795D03*
X1829888Y10735D03*
X1827100Y81600D03*
X1798454Y82256D03*
X1826900Y40400D03*
X1808363Y40033D03*
X1803300Y39900D03*
X1817352Y36909D03*
X1812352Y36949D03*
X1797700Y36804D03*
X1792700Y36871D03*
X1777000Y115750D03*
X1813118Y127976D03*
X1807509Y128500D03*
X1778000Y120000D03*
X1780720Y153850D03*
X1824990Y103620D03*
X1815026Y121478D03*
X1810100Y114700D03*
X1784750Y124000D03*
X1807818Y124179D03*
X1833629Y170807D03*
X1821261Y170012D03*
X1834103Y176021D03*
X1834400Y216900D03*
X1830415Y196567D03*
X1784440Y232938D03*
X1826085Y236034D03*
X1822877Y235852D03*
X1793600Y235100D03*
X1793700Y232500D03*
X1806083Y232584D03*
X1803280Y232611D03*
X1779700Y472100D03*
X1784525Y491830D03*
X1789774Y476403D03*
X1801500Y471055D03*
X1795164Y476406D03*
X1789525Y491830D03*
X1801125D03*
X1796125D03*
X1817325Y481320D03*
X1806600Y471055D03*
X1812325Y481320D03*
X1806975Y491630D03*
X1824125Y491830D03*
X1819125D03*
X1811975Y491630D03*
X1803900Y491500D03*
X1789300Y520000D03*
X1836600Y521600D03*
X1833700Y497300D03*
X1786000Y522600D03*
X1813500Y526500D03*
X1792170Y583900D03*
X1792100Y566900D03*
X1816100Y576200D03*
X1809309Y555713D03*
X1786900Y552500D03*
X1810387Y571435D03*
X1810385Y568821D03*
X1813456Y583500D03*
X1793900Y550100D03*
X1793660Y560570D03*
X1792805Y574675D03*
X1816458Y587480D03*
X1793452Y586701D03*
X1788300Y585100D03*
X1791349Y589122D03*
X1791323Y594030D03*
X1787500Y600500D03*
X1794500Y612500D03*
X1845420Y13310D03*
X1841289Y21631D03*
X1843426Y9528D03*
X1841060Y35540D03*
X1849027Y34426D03*
X1883200Y76600D03*
X1878997Y37546D03*
X1868670Y42765D03*
X1896970Y73460D03*
X1895354Y75650D03*
X1877103Y60791D03*
X1854250Y138600D03*
X1854115Y131121D03*
X1864904Y114735D03*
X1872254Y138618D03*
X1839667Y151994D03*
X1837090Y149830D03*
X1843107Y97988D03*
X1857110Y113600D03*
X1890974Y105600D03*
X1898102Y107325D03*
X1897536Y120510D03*
Y114600D03*
X1874258Y103196D03*
X1862400Y124500D03*
X1861015Y130815D03*
X1878096Y152843D03*
X1881324Y153250D03*
X1886050Y151431D03*
X1848590Y141360D03*
X1857250Y138600D03*
X1853317Y108197D03*
X1857849Y148079D03*
X1854962Y133613D03*
X1848532Y144360D03*
X1864637Y201861D03*
X1868843Y207920D03*
X1839873Y159358D03*
X1836932Y170486D03*
X1854900Y175900D03*
X1877517Y217988D03*
X1875700Y184800D03*
X1883539Y199813D03*
X1883350Y202410D03*
X1877880Y203780D03*
X1863650Y189750D03*
X1863750Y163750D03*
X1883800Y179100D03*
X1857400Y175900D03*
X1862000Y177500D03*
X1886952Y213125D03*
X1884340Y217866D03*
X1864464Y198466D03*
X1878789Y213663D03*
X1884400Y183700D03*
X1883800Y210575D03*
X1854868Y184667D03*
X1847200Y202050D03*
X1858686Y180377D03*
X1864170Y211869D03*
X1884000Y188100D03*
X1865100Y174600D03*
X1850723Y219250D03*
X1843449Y244425D03*
X1896529Y235080D03*
X1884651Y234975D03*
X1882200Y234400D03*
X1882345Y231837D03*
X1892274Y235080D03*
X1875900Y453600D03*
X1868015Y452987D03*
X1837300Y472276D03*
X1837200Y525700D03*
X1842400Y516800D03*
X1841900Y498800D03*
X1852719Y487575D03*
Y492575D03*
X1873632Y500904D03*
X1837475Y573835D03*
X1837534Y579322D03*
X1875850Y567200D03*
X1852400Y554900D03*
X1869800Y557100D03*
X1878875Y565475D03*
X1897300Y548800D03*
X1882300Y565550D03*
X1873510Y541710D03*
X1840700Y563800D03*
X1848800Y551400D03*
X1848900Y548200D03*
X1844018Y586482D03*
X1847070Y537610D03*
X1918352Y89300D03*
X1923300Y94300D03*
X1918113Y93576D03*
X1927918Y126156D03*
X1918210Y96103D03*
X1940700Y136300D03*
X1927810Y123544D03*
X1919195Y134396D03*
X1926952Y156049D03*
X1952726Y102950D03*
X1914500Y113300D03*
X1944609Y149184D03*
X1944600Y151700D03*
X1923837Y118800D03*
X1937728Y99441D03*
X1911440Y128840D03*
X1934544Y127957D03*
X1946770Y98150D03*
X1929736Y128337D03*
X1919514Y131701D03*
X1943660Y98180D03*
X1918002Y98902D03*
X1934100Y193400D03*
X1927064Y207564D03*
X1918489Y212513D03*
X1930500Y209464D03*
X1943500Y209500D03*
X1917568Y201215D03*
X1939400Y198400D03*
X1918143Y219848D03*
X1925835Y233735D03*
X1926100Y231200D03*
X1944463Y228458D03*
X1910340Y220741D03*
X1944925Y226001D03*
X1899816Y235035D03*
X1942000Y440500D03*
X1945000Y474000D03*
X1947550Y485350D03*
X1956500Y507470D03*
X1939000Y476600D03*
X1959300Y518000D03*
X1948200Y474300D03*
X1900890Y477200D03*
X1914750Y544863D03*
X1951900Y534900D03*
X1898850Y545250D03*
X1926600Y559500D03*
X1923600Y565100D03*
X1923000Y568700D03*
X1922000Y543750D03*
X1958500Y535000D03*
X1923500Y579500D03*
X1939800Y546300D03*
X1948100Y538700D03*
X1923400Y583000D03*
X1923600Y575500D03*
X1918880Y586460D03*
X1932390Y590100D03*
X1938130Y601480D03*
X1937870Y594480D03*
X1914700Y594600D03*
X1964890Y534940D03*
X1963000Y573000D03*
X1972700Y549950D03*
G54D30*
G01X1551875Y450306D02*
Y454521D01*
X1550076Y456320D01*
Y457812D01*
X1551875Y459611D01*
Y461281D01*
X1550076Y463080D01*
Y464572D01*
X1551875Y466371D01*
Y468041D01*
X1550076Y469840D01*
Y471332D01*
X1551875Y473131D01*
Y474801D01*
X1553900Y476826D01*
Y478200D01*
X1555900Y480200D01*
Y481600D01*
X1557600Y483300D01*
Y484600D01*
X1559600Y486600D01*
Y490400D01*
G54D12*
X30500Y-42250D03*
Y-52250D03*
X12290Y264640D03*
X18450Y267010D03*
X22970Y244400D03*
X28720Y244450D03*
X17120Y244220D03*
X24200Y267060D03*
X50500Y-42250D03*
Y-52250D03*
X60500Y-42250D03*
Y-52250D03*
X457246Y-52301D03*
Y-42301D03*
X477246Y-52301D03*
Y-42301D03*
X487246Y-52301D03*
Y-42301D03*
X788984Y-52057D03*
Y-42057D03*
X808984Y-52057D03*
Y-42057D03*
X818984Y-52057D03*
Y-42057D03*
X1125583Y-52285D03*
Y-42285D03*
X1145583Y-52285D03*
Y-42285D03*
X1382258Y-52257D03*
Y-42257D03*
X1402258Y-52257D03*
Y-42257D03*
X1422258Y-52257D03*
Y-42257D03*
X1442258Y-52257D03*
Y-42257D03*
G54D21*
X1482000Y-5000D03*
G54D31*
G01X51700Y283200D02*
X50151Y281651D01*
G01X53425Y283198D02*
X54600Y284373D01*
G01X258392Y260363D02*
X260778D01*
X263281Y257860D01*
X264179D01*
G01X258392Y257863D02*
X260878D01*
X262778Y255963D01*
X265191D01*
X267088Y257860D01*
X271239D01*
G01X258392Y242659D02*
X259681D01*
X260080Y242260D01*
X264092D01*
G01X257892Y240159D02*
X264962D01*
X267063Y242260D01*
X271239D01*
G01X257892Y265363D02*
X260576D01*
X264179Y261760D01*
G01X257892Y262863D02*
X260530D01*
X263537Y259856D01*
X265259D01*
X267163Y261760D01*
X271239D01*
G01X258392Y247659D02*
X260181D01*
X261680Y246160D01*
X264179D01*
G01X258392Y245159D02*
X259982D01*
X260885Y244256D01*
X265183D01*
X267087Y246160D01*
X271239D01*
G01X259846Y251394D02*
X260034Y251206D01*
X260717D01*
X263438Y248485D01*
X264912D01*
X266861Y250434D01*
X268394D01*
G02X268943Y250333I1J-1538D01*
G03X270425Y250060I1482J3886D01*
G01X271239D01*
G01X259376Y254183D02*
X259463D01*
X259536Y254256D01*
X260584D01*
X263205Y251635D01*
X265224D01*
X267173Y253584D01*
X268593D01*
G03X269322Y253860I0J1101D01*
G02X269586Y253960I264J-299D01*
G01X271239D01*
G01X259846Y250334D02*
X259968Y250456D01*
X260406D01*
X263127Y247735D01*
X265223D01*
X267172Y249684D01*
X268394D01*
G02X268675Y249632I0J-787D01*
G02X268394Y248109I-281J-736D01*
G01X267859D01*
G01X259496Y255243D02*
X259733Y255006D01*
X260895D01*
X263516Y252385D01*
X264913D01*
X266862Y254334D01*
X268593D01*
G03X268825Y254422I0J350D01*
G03X268943Y254684I-232J262D01*
G01Y255559D01*
G03X268593Y255909I-350J0D01*
G01X267859D01*
G01X271239Y335860D02*
X267198D01*
X265251Y333913D01*
X264605D01*
X262977Y333915D01*
X262056Y334836D01*
X259291D01*
G01X264179Y335860D02*
X262703Y337336D01*
X259306D01*
G01X264179Y351460D02*
X259422D01*
G01X271239D02*
X267027D01*
X264941Y353546D01*
X263355D01*
X262901Y354000D01*
X259480D01*
G01X271239Y331960D02*
X268043D01*
X265685Y330983D01*
X264949Y330247D01*
X259124D01*
G01X264179Y331960D02*
X262023D01*
X261647Y332336D01*
X259233D01*
G01X264179Y347560D02*
X259334D01*
G01X271239D02*
X267069D01*
X265013Y349616D01*
X259334D01*
G01X271239Y343660D02*
X269361D01*
G03X268959Y343559I0J-851D01*
G02X267929Y343284I-1099J2050D01*
G01X267061D01*
G02X265687Y344458I798J2325D01*
G03X264834Y345235I-1508J-798D01*
G01X263427D01*
X262179Y343987D01*
X258824D01*
X258654Y343817D01*
G01X271239Y339760D02*
X269692Y339921D01*
X269092Y339983D01*
X268505Y340044D01*
G03X267944Y340134I-646J-2235D01*
G01X267815D01*
G02X266494Y340922I44J1575D01*
G03X264549Y342085I-2015J-1162D01*
G01X263186D01*
X262071Y340970D01*
X259198D01*
X259012Y341156D01*
G01X267859Y345609D02*
X269013Y344944D01*
X269092Y344649D01*
X269096Y344634D01*
G02X268604Y344221I-1238J975D01*
G02X267903Y344034I-746J1388D01*
G01X267204D01*
G02X266351Y344811I655J1575D01*
G03X264977Y345985I-2172J-1151D01*
G01X263116D01*
X261868Y344737D01*
X261092D01*
X260829Y345000D01*
X260092D01*
X259829Y344737D01*
X258794D01*
X258654Y344877D01*
G01X267859Y337809D02*
X269013Y338475D01*
X269092Y338770D01*
X269096Y338785D01*
G03X268296Y339323I-1237J-976D01*
G03X267918Y339384I-438J-1514D01*
G01X267789D01*
G02X265844Y340547I70J2325D01*
G03X264523Y341335I-1365J-787D01*
G01X263497D01*
X262382Y340220D01*
X261682D01*
X261282Y339820D01*
X260582D01*
X260182Y340220D01*
X259058D01*
X258934Y340096D01*
X258847D01*
G01X260840Y227852D02*
X261685D01*
X263174Y229341D01*
X267490D01*
X269083Y230934D01*
X274048D01*
X274049Y230935D01*
X274689D01*
G02X275277Y230841I-70J-2326D01*
G01X276129D01*
X276634Y231346D01*
G02X279364I1365J-787D01*
G01X279429Y231232D01*
X281379Y228610D01*
G01X260209Y225302D02*
X263498Y228591D01*
X267798D01*
X269391Y230184D01*
X274690D01*
G02X275984Y229397I-71J-1574D01*
G01X276396Y228985D01*
X278084D01*
G02X280014Y227823I-85J-2325D01*
G03X281335Y227035I1365J787D01*
G01X281430D01*
G03X282991Y227436I108J2818D01*
G01X283946Y228010D01*
G02X284688Y228234I812J-1350D01*
G01X284830D01*
G02X286124Y227447I-71J-1574D01*
G01X286189Y227334D01*
X288139Y224709D01*
G01X267448Y205756D02*
X268756Y207596D01*
X269092Y208117D01*
X269224Y208322D01*
G02X271188Y209485I2015J-1163D01*
G01X271298D01*
G03X272604Y210272I-59J1575D01*
G02X274534Y211434I2015J-1163D01*
G01X274663D01*
G03X275984Y213797I-44J1575D01*
G02X277929Y217285I2015J1163D01*
G01X278058D01*
G03X279236Y217884I-60J1575D01*
G01X279153Y218194D01*
X277999Y218860D01*
G01X268612Y203313D02*
X269403Y204104D01*
Y207040D01*
X269692Y207596D01*
X269874Y207946D01*
G02X271195Y208734I1365J-787D01*
G01X271290D01*
G03X273254Y209897I-51J2326D01*
G02X274560Y210684I1365J-788D01*
G01X274689D01*
G03X276634Y214172I-70J2325D01*
G02X277955Y216535I1365J788D01*
G01X278084D01*
G03X279873Y217480I-84J2325D01*
G01X280225Y217575D01*
X281379Y216909D01*
G01X261045Y232952D02*
X261436D01*
X261850Y232538D01*
X266187D01*
X268483Y234834D01*
X274663D01*
G03X275984Y235622I-44J1575D01*
G02X277929Y236785I2015J-1162D01*
G01X278069D01*
G02X280014Y235622I-70J-2325D01*
G03X281335Y234834I1365J787D01*
G01X281464D01*
G02X283394Y233672I-85J-2325D01*
G02X283534Y233385I-2016J-1161D01*
G01X284759Y230559D01*
G01X260898Y230402D02*
X261208D01*
X262594Y231788D01*
X266495D01*
X268791Y234084D01*
X274689D01*
G03X276634Y235247I-70J2325D01*
G02X278043Y236035I1365J-787D01*
G02X279364Y235247I-44J-1575D01*
G03X281309Y234084I2015J1162D01*
G01X281438D01*
G02X282744Y233297I-59J-1575D01*
G02X282939Y232733I-1365J-788D01*
G01X283209Y230093D01*
X283394Y229772D01*
G03X284688Y228985I1365J787D01*
G01X284903D01*
X288139Y228610D01*
G01X277999Y222760D02*
X279153Y222094D01*
X279236Y221784D01*
G02X278058Y221185I-1238J976D01*
G01X277929D01*
G03X275984Y220022I70J-2325D01*
G02X274663Y219234I-1365J787D01*
G01X273639D01*
X265994Y211589D01*
X265399D01*
X264608Y212380D01*
G01X264736Y209830D02*
X265747Y210841D01*
X266304D01*
X273947Y218484D01*
X274689D01*
G03X276634Y219647I-70J2325D01*
G02X277955Y220435I1365J-787D01*
G01X278084D01*
G02X279553Y219948I0J-2459D01*
G01X281013Y218860D01*
X284759D01*
G01X277999Y226660D02*
X277450Y227209D01*
X277448D01*
G03X275995Y226734I0J-2459D01*
G02X275808Y226609I-1362J1835D01*
G01X275807Y226610D01*
G02X274670Y226284I-1189J2000D01*
G01X270791D01*
X268842Y224335D01*
X263454D01*
X260409Y221287D01*
Y220579D01*
X259773Y219942D01*
X259065D01*
X258430Y219307D01*
Y219087D01*
X258368Y219025D01*
G01X288139Y220809D02*
X286985Y221475D01*
X286891Y221827D01*
G03X284829Y225085I-2131J933D01*
G01X284689D01*
G03X282744Y223922I70J-2325D01*
G01X282743D01*
G02X281380Y223134I-1363J786D01*
G01X281378D01*
G02X280014Y223922I0J1574D01*
G03X278000Y225085I-2014J-1162D01*
G01X277997D01*
G03X275984Y223922I0J-2324D01*
G02X274663Y223134I-1365J787D01*
G01X272580D01*
X267687Y218241D01*
X265703D01*
X265548Y218396D01*
X265461D01*
G01X281379Y224709D02*
X281542Y224872D01*
Y226066D01*
X281328Y226284D01*
G02X279364Y227447I51J2326D01*
G03X278070Y228234I-1365J-787D01*
G01X277928D01*
G03X275550Y227339I414J-4707D01*
G02X275424Y227255I-936J1268D01*
G02X274663Y227035I-804J1355D01*
G02X274660Y227034I-500J1494D01*
G01X270480D01*
X268531Y225085D01*
X263143D01*
X257898Y219837D01*
X257680D01*
X257618Y219775D01*
G01X265461Y217336D02*
X265548D01*
X265703Y217491D01*
X267998D01*
X272891Y222384D01*
X274673D01*
G03X276634Y223547I-54J2325D01*
G02X277998Y224335I1364J-786D01*
G01X278001D01*
G02X279364Y223547I-1J-1574D01*
G03X281377Y222384I2013J1161D01*
G01X281379D01*
G03X283394Y223547I2J2324D01*
G02X284711Y224334I1364J-788D01*
G02X284806I47J-1575D01*
G02X286223Y222178I-47J-1575D01*
G01X285913Y222094D01*
X284759Y222760D01*
G01X288139Y372909D02*
X286841Y369912D01*
X286774Y369797D01*
G02X284829Y368634I-2015J1162D01*
G01X284688D01*
G03X283394Y367847I71J-1574D01*
G02X281430Y366684I-2015J1163D01*
G01X281320D01*
G03X280014Y365897I59J-1575D01*
G02X278084Y364735I-2015J1163D01*
G01X277955D01*
G03X276634Y363947I44J-1575D01*
G02X274689Y362784I-2015J1162D01*
G01X264647D01*
X263666Y363765D01*
X263188D01*
X262499Y363076D01*
G01X281379Y369010D02*
X279430Y366387D01*
X279364Y366272D01*
G02X278058Y365485I-1365J788D01*
G01X277929D01*
G03X275984Y364322I70J-2325D01*
G02X274663Y363534I-1365J787D01*
G01X264955D01*
X263976Y364513D01*
X263613D01*
X262499Y365627D01*
G01X288139Y369010D02*
X286774Y365897D01*
G02X284844Y364735I-2015J1163D01*
G01X284715D01*
G03X283394Y363947I44J-1575D01*
G02X281449Y362784I-2015J1162D01*
G01X281320D01*
G03X280014Y361997I59J-1575D01*
G02X278084Y360835I-2015J1163D01*
G01X277955D01*
G03X276634Y360047I44J-1575D01*
G02X274689Y358884I-2015J1162D01*
G01X274041D01*
X273848Y358691D01*
X264096D01*
X263236Y357831D01*
G01X284759Y367060D02*
X282810Y364437D01*
X282744Y364322D01*
G02X281423Y363534I-1365J787D01*
G01X281294D01*
G03X279364Y362372I85J-2325D01*
G02X278058Y361585I-1365J788D01*
G01X277929D01*
G03X275984Y360422I70J-2325D01*
G02X274663Y359634I-1365J787D01*
G01X273733D01*
X273538Y359439D01*
X264206D01*
X263264Y360381D01*
G01X284759Y374860D02*
X285913Y375525D01*
X286223Y375441D01*
G02X284818Y373285I-1465J-581D01*
G01X284708D01*
G03X282744Y372122I51J-2326D01*
G02X281450Y371335I-1365J787D01*
G01X281309D01*
G03X279364Y370172I70J-2325D01*
G02X278070Y369385I-1365J787D01*
G01X277914D01*
G03X277895I-9J-2325D01*
G01Y369384D01*
G03X275984Y368222I104J-2324D01*
G02X274660Y367434I-1365J788D01*
G01X273183D01*
X272774Y367025D01*
X266829D01*
X264563Y369291D01*
X260372D01*
X258391Y371272D01*
X258392Y371490D01*
X258331Y371551D01*
G01X277999Y370959D02*
X275644Y370621D01*
X275234Y370583D01*
X274703Y370585D01*
X271204D01*
X269948Y371841D01*
X261648D01*
X255148Y378341D01*
Y378705D01*
X254089Y379764D01*
X253867D01*
X253805Y379826D01*
G01X288139Y376809D02*
X286985Y376144D01*
X286891Y375793D01*
G02X284810Y372534I-2132J-933D01*
G01X284715D01*
G03X283394Y371746I44J-1575D01*
G02X281464Y370584I-2015J1163D01*
G01X281308D01*
G03X280014Y369797I71J-1574D01*
G02X278069Y368634I-2015J1162D01*
G01X277928D01*
G03X276634Y367847I71J-1574D01*
G02X274669Y366684I-2015J1163D01*
G01X273494D01*
X273085Y366275D01*
X266518D01*
X264252Y368541D01*
X260061D01*
X257863Y370739D01*
X257643D01*
X257581Y370801D01*
G01X281379Y380709D02*
Y379172D01*
X279198Y376991D01*
X277097D01*
X275704Y378384D01*
X272491D01*
X272048Y377941D01*
X264722D01*
X262048Y380615D01*
Y385241D01*
X256248Y391041D01*
X254978D01*
G01X277999Y378760D02*
X276518D01*
X276144Y379134D01*
X272180D01*
X271735Y378689D01*
X265032D01*
X262796Y380925D01*
Y385551D01*
X256748Y391599D01*
Y392878D01*
G01X284759Y378760D02*
X282810Y376138D01*
X282744Y376022D01*
G02X281423Y375234I-1365J787D01*
G01X281294D01*
G03X279364Y374072I85J-2325D01*
G02X278058Y373285I-1365J788D01*
G01X277940D01*
G02X276634Y374072I59J1575D01*
G01X275304Y374484D01*
X273405D01*
X272948Y374941D01*
X262948D01*
X258241Y379648D01*
Y381848D01*
X257684Y382405D01*
X256400D01*
G01X277999Y374860D02*
X276679D01*
X276305Y375234D01*
X273716D01*
X273261Y375689D01*
X263258D01*
X258989Y379958D01*
Y382158D01*
X258104Y383043D01*
Y384308D01*
G01X281379Y372909D02*
X278611Y372536D01*
X277586D01*
X275644Y371712D01*
G02X275533Y371625I-1027J1196D01*
G02X274700Y371335I-914J1284D01*
G01X271515D01*
X270259Y372591D01*
X261959D01*
X255898Y378652D01*
Y379016D01*
X254618Y380296D01*
Y380516D01*
X254556Y380578D01*
G01X275061Y197103D02*
X275452Y197494D01*
Y199116D01*
X275913Y199919D01*
G02X278420Y201741I3688J-2439D01*
G03X279364Y202472I-421J1519D01*
G02X281328Y203635I2015J-1163D01*
G01X281423D01*
G03X282744Y204423I-44J1575D01*
G02X284674Y205585I2015J-1163D01*
G01X284830D01*
G03X286124Y206372I-71J1574D01*
G02X288069Y207535I2015J-1162D01*
G01X288210D01*
G03X289504Y208322I-71J1574D01*
G02X291468Y209485I2015J-1163D01*
G01X291578D01*
G03X292884Y210272I-59J1575D01*
G02X294814Y211434I2015J-1163D01*
G01X294943D01*
G03X296264Y212222I-44J1575D01*
G01X296330Y212338D01*
X298279Y214960D01*
G01X278366Y196801D02*
X279624Y198059D01*
Y201346D01*
X280014Y202097D01*
G02X281320Y202884I1365J-788D01*
G01X281430D01*
G03X283394Y204047I-51J2326D01*
G02X284688Y204834I1365J-787D01*
G01X284829D01*
G03X286774Y205997I-70J2325D01*
G02X288068Y206784I1365J-787D01*
G01X288224D01*
G03X290154Y207946I-85J2325D01*
G02X291475Y208734I1365J-787D01*
G01X291570D01*
G03X293534Y209897I-51J2326D01*
G02X294840Y210684I1365J-788D01*
G01X294969D01*
G03X296914Y211847I-70J2325D01*
G02X297320Y212309I1355J-781D01*
G02X298448Y213041I5343J-6998D01*
G03X299644Y214172I-1299J2571D01*
G03X298966Y216378I-1365J788D01*
G02X297159Y217752I2504J5168D01*
G02X296895Y219613I1120J1108D01*
G01X296982Y219764D01*
X298279Y222760D01*
G01X293841Y189941D02*
X295147D01*
X295898Y190692D01*
Y192029D01*
G01X295748Y188241D02*
Y189341D01*
X296648Y190241D01*
Y192029D01*
G01X270723Y199979D02*
X271441Y200697D01*
X271618Y200871D01*
X272604Y202472D01*
G02X274568Y203635I2015J-1163D01*
G01X274663D01*
G03X275984Y204423I-44J1575D01*
G02X277914Y205585I2015J-1163D01*
G01X278070D01*
G03X279364Y206372I-71J1574D01*
G02X281309Y207535I2015J-1162D01*
G01X281450D01*
G03X282744Y208322I-71J1574D01*
G02X284708Y209485I2015J-1163D01*
G01X284818D01*
G03X286124Y210272I-59J1575D01*
G02X288054Y211434I2015J-1163D01*
G01X288183D01*
G03X289504Y212222I-44J1575D01*
G02X291449Y213385I2015J-1162D01*
G01X291578D01*
G03X292884Y214172I-59J1575D01*
G01X292950Y214288D01*
X294899Y216909D01*
G01X271755Y197404D02*
X272828Y198477D01*
Y201351D01*
X273254Y202097D01*
G02X274560Y202884I1365J-788D01*
G01X274670D01*
G03X276634Y204047I-51J2326D01*
G02X277928Y204834I1365J-787D01*
G01X278069D01*
G03X280014Y205997I-70J2325D01*
G02X281308Y206784I1365J-787D01*
G01X281464D01*
G03X283394Y207946I-85J2325D01*
G02X284715Y208734I1365J-787D01*
G01X284810D01*
G03X286774Y209897I-51J2326D01*
G02X288080Y210684I1365J-788D01*
G01X288209D01*
G03X290154Y211847I-70J2325D01*
G02X291475Y212635I1365J-787D01*
G01X291604D01*
G03X293534Y213797I-85J2325D01*
G02X294840Y214584I1365J-788D01*
G01X294899D01*
G03X295616Y214998I0J828D01*
G01X296264Y216122D01*
X296283Y216156D01*
G03X296264Y217697I-1384J754D01*
G01X296198Y217810D01*
X294899Y220809D01*
G01X305039Y214960D02*
X306241Y212188D01*
G03X306403Y211847I2176J825D01*
G02X306614Y211060I-1365J-788D01*
G01X306615Y209152D01*
X306616Y209151D01*
Y207891D01*
X300410Y201685D01*
X298209D01*
G03X296264Y200522I70J-2325D01*
G02X294943Y199734I-1365J787D01*
G01X294814D01*
G03X292884Y198572I85J-2325D01*
G01X292048Y197123D01*
Y194341D01*
X291748Y194041D01*
X290726D01*
X290537Y193852D01*
G01X292291Y191998D02*
X292548Y192255D01*
Y193741D01*
X292798Y193991D01*
Y196921D01*
X293534Y198197D01*
G02X294840Y198984I1365J-788D01*
G01X294969D01*
G03X296914Y200147I-70J2325D01*
G02X298235Y200935I1365J-787D01*
G01X300721D01*
X307366Y207580D01*
X307365Y207581D01*
Y211060D01*
G03X307053Y212223I-2327J-1D01*
G02Y213797I1365J787D01*
G03Y216123I-2015J1163D01*
G02X306590Y218590I3278J1892D01*
G03X306526Y219377I-1552J270D01*
G01Y222543D01*
X306309Y222760D01*
X305039D01*
G01X280868Y193956D02*
Y194306D01*
X283178Y196616D01*
Y199772D01*
X283394Y200147D01*
G02X284715Y200935I1365J-787D01*
G01X284844D01*
G03X286774Y202097I-85J2325D01*
G02X288080Y202884I1365J-788D01*
G01X288190D01*
G03X290154Y204047I-51J2326D01*
G02X291448Y204834I1365J-787D01*
G01X291589D01*
G03X293534Y205997I-70J2325D01*
G02X294828Y206784I1365J-787D01*
G01X294984D01*
G03X296914Y207946I-85J2325D01*
G02X298235Y208734I1365J-787D01*
G01X298330D01*
G03X300294Y209897I-51J2326D01*
G02X300946Y210728I3238J-1870D01*
G01X301659Y213009D01*
G01X315592Y188900D02*
Y188987D01*
X315437Y189142D01*
Y194451D01*
X322466Y201480D01*
X323120Y202608D01*
Y205790D01*
X320698Y208212D01*
Y217300D01*
X320901Y217503D01*
Y219443D01*
X320550Y220060D01*
G02X320573Y221597I1388J748D01*
G03X320599Y223876I-2015J1163D01*
G01X320573Y223922D01*
X320550Y223960D01*
G02X320573Y225497I1388J748D01*
G03X320599Y227776I-2015J1163D01*
G01X320573Y227822D01*
G02X321881Y230185I1365J788D01*
G01X322025D01*
G03X323953Y231347I-87J2324D01*
G02X325277Y232135I1365J-788D01*
G01X325390D01*
G03X327333Y233297I-72J2325D01*
G03X327614Y233873I-3968J2292D01*
G01X328698Y236409D01*
G01X301659Y224709D02*
Y223378D01*
X301403Y223122D01*
G03X301589Y218484I256J-2312D01*
G01X301718D01*
G02X303043Y216156I-59J-1575D01*
G01X303024Y216122D01*
X302999Y216080D01*
G03X303024Y213797I2040J-1119D01*
G02X303043Y212256I-1365J-787D01*
G01X303024Y212222D01*
X302999Y212180D01*
G03X303024Y209897I2040J-1119D01*
G02X301703Y207534I-1365J-788D01*
G01X301574D01*
G03X299644Y206372I85J-2325D01*
G02X298338Y205585I-1365J788D01*
G01X298209D01*
G03X296264Y204422I70J-2325D01*
G02X294943Y203634I-1365J787D01*
G01X294814D01*
G03X292884Y202472I85J-2325D01*
G02X291578Y201685I-1365J788D01*
G01X291449D01*
G03X289504Y200522I70J-2325D01*
G02X288183Y199734I-1365J787D01*
G01X288054D01*
G03X286124Y198572I85J-2325D01*
G03X285970Y197997I997J-575D01*
G01Y194838D01*
X285815Y194683D01*
G01X328698Y248109D02*
Y246778D01*
X328442Y246522D01*
G03X328628Y241884I256J-2312D01*
G01X328757D01*
G02X330082Y239556I-59J-1575D01*
G01X330063Y239522D01*
X330038Y239480D01*
G03X330063Y237197I2040J-1119D01*
G02X330082Y235656I-1365J-787D01*
G01X330063Y235622D01*
X330038Y235580D01*
G03X330063Y233297I2040J-1119D01*
G02X328769Y230935I-1365J-788D01*
G01X328628D01*
G03X326683Y229772I70J-2325D01*
G02X325389Y228985I-1365J787D01*
G01X325233D01*
G03X323303Y225497I85J-2325D01*
G02X323322Y223956I-1365J-787D01*
G01X323303Y223922D01*
X323298Y223914D01*
X323294Y223908D01*
X323289Y223898D01*
X323278Y223880D01*
G03X323303Y221597I2040J-1119D01*
G02X323253Y219893I-1405J-812D01*
G01X322990Y219630D01*
Y209119D01*
X325788Y206321D01*
Y200651D01*
X320268Y195131D01*
Y193079D01*
X320132Y192943D01*
G01X301659Y216909D02*
X300361Y213912D01*
X300294Y213797D01*
G03Y212223I1365J-787D01*
G02X300268Y211360I-1049J-400D01*
G02X300236Y211297I-716J324D01*
G01X299644Y210272D01*
G02X298338Y209485I-1365J788D01*
G01X298228D01*
G03X296264Y208322I51J-2326D01*
G02X294970Y207535I-1365J787D01*
G01X294829D01*
G03X292884Y206372I70J-2325D01*
G02X291590Y205585I-1365J787D01*
G01X291434D01*
G03X289504Y204423I85J-2325D01*
G02X288183Y203635I-1365J787D01*
G01X288088D01*
G03X286124Y202472I51J-2326D01*
G02X284818Y201685I-1365J788D01*
G01X284705D01*
G03X282743Y200522I53J-2325D01*
G01X282428Y199973D01*
Y196928D01*
X280311Y194811D01*
X280203D01*
G01X328698Y240309D02*
X328691Y240294D01*
G02X327333Y237196I-14719J4605D01*
G03X327172Y236017I1365J-787D01*
G02X326918Y234154I-3808J-430D01*
G02X326683Y233672I-3553J1434D01*
G02X325377Y232885I-1365J788D01*
G01X325267D01*
G03X323303Y231722I51J-2326D01*
G02X322009Y230935I-1365J787D01*
G01X321868D01*
G03X319923Y227447I70J-2325D01*
G01X319942Y227413D01*
G02X319923Y225872I-1384J-754D01*
G03X319898Y223589I2015J-1164D01*
G01X319923Y223547D01*
X319942Y223513D01*
G02X319923Y221972I-1384J-754D01*
G03X319894Y219696I2015J-1164D01*
G01X320151Y219244D01*
Y217814D01*
X319948Y217611D01*
Y207901D01*
X322370Y205479D01*
Y202810D01*
X321866Y201941D01*
X314687Y194762D01*
Y189142D01*
X314532Y188987D01*
Y188900D01*
G01X286875Y194683D02*
X286720Y194838D01*
Y197996D01*
G02X286774Y198197I401J0D01*
G02X288080Y198984I1365J-788D01*
G01X288209D01*
G03X290154Y200147I-70J2325D01*
G02X291475Y200935I1365J-787D01*
G01X291604D01*
G03X293534Y202097I-85J2325D01*
G02X294840Y202884I1365J-788D01*
G01X294969D01*
G03X296914Y204047I-70J2325D01*
G02X298235Y204835I1365J-787D01*
G01X298364D01*
G03X300294Y205997I-85J2325D01*
G02X301600Y206784I1365J-788D01*
G01X301729D01*
G03X303674Y210272I-70J2325D01*
G02X303655Y211813I1365J787D01*
G01X303674Y211847D01*
X303699Y211889D01*
G03X303674Y214172I-2040J1119D01*
G02X303655Y215713I1365J787D01*
G01X303674Y215747D01*
X303699Y215789D01*
G03X301744Y219234I-2040J1120D01*
G01X301615D01*
G02X301431Y222368I44J1575D01*
G01X301659Y222140D01*
Y220809D01*
G01X321192Y192965D02*
X321018Y193139D01*
Y194820D01*
X326538Y200340D01*
Y206632D01*
X323740Y209430D01*
Y219319D01*
X323832Y219411D01*
G03X323953Y221972I-1933J1375D01*
G02X323934Y223513I1365J787D01*
G01X323933Y223514D01*
X323935Y223517D01*
X323978Y223589D01*
G03X323953Y225872I-2040J1119D01*
G02X325247Y228234I1365J788D01*
G01X325388D01*
G03X327333Y229397I-70J2325D01*
G02X328627Y230184I1365J-787D01*
G01X328783D01*
G03X330713Y233672I-85J2325D01*
G02X330694Y235213I1365J787D01*
G01X330713Y235247D01*
X330738Y235289D01*
G03X330713Y237572I-2040J1119D01*
G02X330694Y239113I1365J787D01*
G01X330713Y239147D01*
X330738Y239189D01*
G03X328783Y242634I-2040J1120D01*
G01X328654D01*
G02X328470Y245768I44J1575D01*
G01X328698Y245540D01*
Y244209D01*
G01X325318Y238360D02*
X324007D01*
X323715Y238068D01*
Y237574D01*
X323937Y237352D01*
Y236812D01*
G02X323836Y236482I-599J3D01*
G03X323319Y235650I12648J-8436D01*
G01X323303Y235622D01*
G02X321982Y234834I-1359J776D01*
G01X321853D01*
G03X319923Y233672I85J-2325D01*
G02X318617Y232885I-1365J788D01*
G01X318507D01*
G03X316518Y229439I51J-2326D01*
G01X316543Y229397D01*
G02Y227823I-1365J-787D01*
G03Y225497I2015J-1163D01*
G02X316562Y223956I-1365J-787D01*
G01X316543Y223922D01*
X316518Y223880D01*
G03X316543Y221597I2040J-1119D01*
G02X316562Y220056I-1365J-787D01*
G01X316543Y220022D01*
G03Y217698I2015J-1162D01*
G01X316873Y217073D01*
Y207626D01*
X317338Y207161D01*
Y203651D01*
X310178Y196491D01*
Y194851D01*
X309592Y194265D01*
G01X311868Y193991D02*
X310926Y194933D01*
Y196181D01*
X318086Y203341D01*
Y207474D01*
X317623Y207937D01*
Y217383D01*
X317193Y218073D01*
G02Y219647I1365J787D01*
G01X317218Y219689D01*
G03X317193Y221972I-2040J1119D01*
G02X317174Y223513I1365J787D01*
G01X317193Y223547D01*
X317218Y223589D01*
G03X317193Y225872I-2040J1119D01*
G02X317174Y227413I1365J787D01*
G01X317193Y227447D01*
G03X317218Y229730I-2015J1164D01*
G01X317193Y229772D01*
G02X318514Y232134I1365J787D01*
G01X318609D01*
G03X320573Y233297I-51J2326D01*
G02X321879Y234084I1365J-788D01*
G01X322008D01*
G03X323953Y235246I-68J2323D01*
G02X325892Y236892I3267J-1884D01*
G03X326568Y239318I-574J1467D01*
G03X324714Y240804I-3490J-2454D01*
G02X323743Y242279I604J1455D01*
G01Y243071D01*
X324338Y243666D01*
Y244501D01*
X323743Y245096D01*
Y248256D01*
X323948Y248461D01*
X324818D01*
X325318Y247961D01*
Y246160D01*
G01X304218Y193611D02*
X305068Y194461D01*
Y195702D01*
X311748Y202382D01*
Y203401D01*
X311308Y203841D01*
Y205901D01*
X312579Y207172D01*
Y209259D01*
X313163Y210272D01*
G03X313182Y211813I-1365J787D01*
G01X313163Y211847D01*
X313138Y211889D01*
G02X313163Y214172I2040J1119D01*
G03X313182Y215713I-1365J787D01*
G01X313163Y215747D01*
X313138Y215789D01*
G02X313163Y218072I2040J1119D01*
G03X313182Y219613I-1365J787D01*
G01X313163Y219647D01*
X313138Y219689D01*
G02X313163Y221972I2040J1119D01*
G03X313182Y223513I-1365J787D01*
G01X313163Y223547D01*
X313138Y223589D01*
G02X313163Y225872I2040J1119D01*
G03X313182Y227413I-1365J787D01*
G01X313163Y227447D01*
G02X313138Y229730I2015J1164D01*
G01X313163Y229772D01*
G03Y231346I-1365J787D01*
G02X315093Y234834I2015J1163D01*
G01X315222D01*
G03X316543Y235622I-44J1575D01*
G02X318488Y236785I2015J-1162D01*
G01X318617D01*
G03X319923Y237572I-59J1575D01*
G02X320173Y237925I2015J-1162D01*
G01X321938Y240309D01*
G01X306768Y193511D02*
X305824Y194455D01*
Y195388D01*
X314498Y204062D01*
Y206181D01*
X313329Y207350D01*
Y209058D01*
X313813Y209897D01*
G03X313838Y212180I-2015J1164D01*
G01X313813Y212222D01*
X313794Y212256D01*
G02X313813Y213797I1384J754D01*
G03X313838Y216080I-2015J1164D01*
G01X313813Y216122D01*
X313794Y216156D01*
G02X313813Y217697I1384J754D01*
G03X313838Y219980I-2015J1164D01*
G01X313813Y220022D01*
X313794Y220056D01*
G02X313813Y221597I1384J754D01*
G03X313838Y223880I-2015J1164D01*
G01X313813Y223922D01*
X313794Y223956D01*
G02X313813Y225497I1384J754D01*
G03Y227823I-2015J1163D01*
G02Y229397I1365J787D01*
G01X313838Y229439D01*
G03X313813Y231722I-2040J1119D01*
G01X313794Y231756D01*
G02X315119Y234084I1384J753D01*
G01X315248D01*
G03X317193Y235247I-70J2325D01*
G02X318514Y236035I1365J-787D01*
G01X318643D01*
G03X320573Y237197I-85J2325D01*
G02X321097Y237742I1365J-788D01*
G01X322265Y238510D01*
X323125Y239189D01*
X323314Y239517D01*
G03X323303Y241097I-1397J780D01*
G01X323237Y241210D01*
X323090Y241550D01*
Y241558D01*
X321938Y242710D01*
Y244209D01*
G01X298279Y374860D02*
X296330Y377481D01*
X296264Y377597D01*
G02X296239Y379880I2015J1164D01*
G01X296264Y379922D01*
X296283Y379956D01*
G03X294958Y382284I-1384J753D01*
G01X294829D01*
G02X292884Y383447I70J2325D01*
G03X291563Y384235I-1365J-787D01*
G01X291434D01*
G02X289504Y385397I85J2325D01*
G03X288198Y386184I-1365J-788D01*
G01X288069D01*
G02X286124Y387347I70J2325D01*
G03X284803Y388135I-1365J-787D01*
G01X284674D01*
G02X282744Y389297I85J2325D01*
G03X281438Y390084I-1365J-788D01*
G01X281328D01*
G02X279364Y391247I51J2326D01*
G03X278070Y392034I-1365J-787D01*
G01X277929D01*
G02X275984Y393197I70J2325D01*
G03X274690Y393984I-1365J-787D01*
G01X274534D01*
G02X272604Y395146I85J2325D01*
G03X271244Y395932I-1360J-784D01*
G01X270203D01*
X268778Y397357D01*
Y398991D01*
X261053Y406716D01*
X259857D01*
X259808Y406667D01*
G01X298279Y382660D02*
X295045Y383034D01*
X294855D01*
G02X293534Y383822I44J1575D01*
G03X291589Y384985I-2015J-1162D01*
G01X291460D01*
G02X290154Y385772I59J1575D01*
G03X288224Y386934I-2015J-1163D01*
G01X288095D01*
G02X286774Y387722I44J1575D01*
G03X284829Y388885I-2015J-1162D01*
G01X284700D01*
G02X283394Y389672I59J1575D01*
G03X281430Y390835I-2015J-1163D01*
G01X281335D01*
G02X280014Y391623I44J1575D01*
G03X278084Y392785I-2015J-1163D01*
G01X277928D01*
G02X276634Y393572I71J1574D01*
G03X274689Y394735I-2015J-1162D01*
G01X274548D01*
G02X273254Y395522I71J1574D01*
G03X271290Y396685I-2015J-1163D01*
G01X270508D01*
X269526Y397667D01*
Y399301D01*
X261660Y407167D01*
Y408422D01*
G01X308418Y376809D02*
Y378140D01*
X308161Y378397D01*
G02X306403Y381873I256J2312D01*
G03Y383447I-1364J787D01*
G01X306368Y383507D01*
G02X306403Y385773I2050J1102D01*
G03Y387347I-1364J787D01*
G02X306368Y387407I843J532D01*
G02X306403Y389673I2050J1102D01*
G03X305087Y392034I-1364J787D01*
G01X304954D01*
G02X303024Y393196I85J2325D01*
G03X301718Y393983I-1365J-788D01*
G01X301608D01*
G02X299644Y395146I51J2326D01*
G03X298350Y395933I-1365J-787D01*
G01X298209D01*
G02X296264Y397096I70J2325D01*
G03X294970Y397883I-1365J-787D01*
G01X294814D01*
G02X292884Y399045I85J2325D01*
G01X292573Y399583D01*
X289627Y402529D01*
X287430D01*
X285238Y404721D01*
Y407401D01*
X280308Y412331D01*
X279088D01*
X279063Y412356D01*
G01X308418Y380709D02*
Y379378D01*
X308191Y379151D01*
G02X307054Y381496I227J1558D01*
G03X307089Y383762I-2015J1164D01*
G01X307054Y383822D01*
G02Y385396I1364J787D01*
G03X307089Y387662I-2015J1164D01*
G01X307054Y387722D01*
G02Y389296I1364J787D01*
G03X305109Y392785I-2015J1163D01*
G01X305039D01*
G03X304980Y392784I0J-1741D01*
G02X303674Y393571I59J1575D01*
G03X301710Y394734I-2015J-1163D01*
G01X301615D01*
G02X300294Y395522I44J1575D01*
G03X298364Y396684I-2015J-1163D01*
G01X298208D01*
G02X296914Y397471I71J1574D01*
G03X294969Y398634I-2015J-1162D01*
G01X294828D01*
G02X293534Y399421I71J1574D01*
G01X293174Y400044D01*
X289939Y403279D01*
X287738D01*
X285986Y405031D01*
Y407711D01*
X280841Y412856D01*
Y414135D01*
G01X294899Y376809D02*
Y378140D01*
X294642Y378397D01*
G02X292884Y379547I257J2312D01*
G03X291563Y380335I-1365J-787D01*
G01X291434D01*
G02X289504Y381497I85J2325D01*
G03X288198Y382284I-1365J-788D01*
G01X288069D01*
G02X286124Y383447I70J2325D01*
G03X284803Y384235I-1365J-787D01*
G01X284674D01*
G02X282744Y385397I85J2325D01*
G03X281438Y386184I-1365J-788D01*
G01X281309D01*
G02X279364Y387347I70J2325D01*
G03X278043Y388135I-1365J-787D01*
G01X277914D01*
G02X275984Y389297I85J2325D01*
G03X274663Y390085I-1365J-787D01*
G01X274534D01*
G02X272604Y391247I85J2325D01*
G03X271310Y392034I-1365J-787D01*
G01X271169D01*
G02X269224Y393197I70J2325D01*
G01X268803Y393927D01*
X268509Y394221D01*
X267647D01*
X262288Y399581D01*
X261108D01*
X257180Y403509D01*
X255750D01*
G01X294899Y380709D02*
Y379378D01*
X294671Y379150D01*
G02X293534Y379922I228J1559D01*
G03X291589Y381085I-2015J-1162D01*
G01X291460D01*
G02X290154Y381872I59J1575D01*
G03X288224Y383034I-2015J-1163D01*
G01X288095D01*
G02X286774Y383822I44J1575D01*
G03X284829Y384985I-2015J-1162D01*
G01X284700D01*
G02X283394Y385772I59J1575D01*
G03X281464Y386934I-2015J-1163D01*
G01X281335D01*
G02X280014Y387722I44J1575D01*
G03X278069Y388885I-2015J-1162D01*
G01X277955D01*
G02X276634Y389673I44J1575D01*
G03X274704Y390835I-2015J-1163D01*
G01X274575D01*
G02X273254Y391623I44J1575D01*
G03X271324Y392785I-2015J-1163D01*
G01X271168D01*
G02X269874Y393572I71J1574D01*
G01X269872Y393571D01*
X269402Y394386D01*
X268819Y394969D01*
X267957D01*
X262598Y400329D01*
X261418D01*
X257553Y404194D01*
Y405313D01*
G01X305039Y374860D02*
X303740Y377859D01*
X303674Y377972D01*
G02X303655Y379513I1365J787D01*
G01X303674Y379547D01*
X303699Y379589D01*
G03X303674Y381872I-2040J1119D01*
G02X303662Y383427I1289J787D01*
G01X303699Y383489D01*
G03X303986Y384611I-2040J1119D01*
G01Y385013D01*
G03X303701Y386015I-1904J0D01*
G02X303235Y387517I2667J1651D01*
G01Y388509D01*
G03X301718Y390084I-1576J0D01*
G03X301611Y390086I-107J-2851D01*
G01X301574D01*
G02X299644Y391247I0J2185D01*
G03X298350Y392034I-1365J-787D01*
G01X298209D01*
G02X296264Y393197I70J2325D01*
G03X294970Y393984I-1365J-787D01*
G01X294814D01*
G02X292884Y395146I85J2325D01*
G03X291563Y395934I-1365J-787D01*
G01X291468D01*
G02X289504Y397097I51J2326D01*
G03X288198Y397884I-1365J-788D01*
G01X288085D01*
G02X288075I-5J2326D01*
G02X286123Y399047I63J2325D01*
G01X285804Y399600D01*
X275243Y410161D01*
X274044D01*
G01X305039Y382660D02*
Y384536D01*
G03X304661Y385996I-2247J197D01*
G02X304343Y386552I3552J2400D01*
G02X303986Y388131I3313J1579D01*
G01Y388509D01*
G03X301744Y390834I-2327J0D01*
G03X301635Y390836I-109J-2994D01*
G01X301615D01*
G02X300294Y391622I0J1503D01*
G03X298349Y392785I-2015J-1162D01*
G01X298208D01*
G02X296914Y393572I71J1574D01*
G03X294969Y394735I-2015J-1162D01*
G01X294828D01*
G02X293534Y395522I71J1574D01*
G03X291570Y396685I-2015J-1163D01*
G01X291460D01*
G02X290154Y397472I59J1575D01*
G03X288224Y398634I-2015J-1163D01*
G01X288095D01*
G02X286774Y399421I44J1576D01*
G01X286409Y400053D01*
X275946Y410516D01*
Y411866D01*
X275722Y412090D01*
G01X269619Y405641D02*
X269680Y405580D01*
Y405360D01*
X271048Y403992D01*
Y401824D01*
X272984Y399888D01*
X273254Y399422D01*
G03X274562Y398634I1365J787D01*
G01X274704D01*
G02X276634Y397472I-85J-2325D01*
G03X277940Y396685I1365J788D01*
G01X278050D01*
G02X280014Y395522I-51J-2326D01*
G03X281308Y394735I1365J787D01*
G01X281449D01*
G02X283394Y393572I-70J-2325D01*
G03X284688Y392785I1365J787D01*
G01X284844D01*
G02X286774Y391623I-85J-2325D01*
G03X288095Y390835I1365J787D01*
G01X288190D01*
G02X290154Y389672I-51J-2326D01*
G03X291460Y388885I1365J788D01*
G01X291589D01*
G02X293534Y387722I-70J-2325D01*
G03X294855Y386934I1365J787D01*
G01X294984D01*
G02X296914Y385772I-85J-2325D01*
G03X298220Y384985I1365J788D01*
G01X298349D01*
G02X300294Y381497I-70J-2325D01*
G03X300275Y379956I1365J-787D01*
G01X300294Y379922D01*
X300319Y379880D01*
G02X300294Y377597I-2040J-1119D01*
G03X301431Y375250I1365J-788D01*
G01X301659Y375478D01*
Y376809D01*
G01Y384609D02*
G03X300192Y386650I-3679J-1097D01*
G02X299644Y387347I2143J2249D01*
G03X298323Y388135I-1365J-787D01*
G01X298194D01*
G02X296264Y389297I85J2325D01*
G03X294958Y390084I-1365J-788D01*
G01X294848D01*
G02X292884Y391247I51J2326D01*
G03X291590Y392034I-1365J-787D01*
G01X291449D01*
G02X289504Y393197I70J2325D01*
G03X288210Y393984I-1365J-787D01*
G01X288054D01*
G02X286124Y395146I85J2325D01*
G03X284803Y395934I-1365J-787D01*
G01X284708D01*
G02X282744Y397097I51J2326D01*
G03X281438Y397884I-1365J-788D01*
G01X281309D01*
G02X279363Y399047I69J2325D01*
G01X278316Y400864D01*
X266878Y412354D01*
X266658D01*
X266596Y412416D01*
G01X301659Y372909D02*
Y374240D01*
X301402Y374497D01*
G02X299644Y377972I257J2312D01*
G03X299663Y379513I-1365J787D01*
G01X299644Y379547D01*
X299619Y379589D01*
G02X299644Y381872I2040J1119D01*
G03X298323Y384235I-1365J788D01*
G01X298194D01*
G02X296264Y385397I85J2325D01*
G03X294958Y386184I-1365J-788D01*
G01X294829D01*
G02X292884Y387347I70J2325D01*
G03X291563Y388135I-1365J-787D01*
G01X291434D01*
G02X289504Y389297I85J2325D01*
G03X288198Y390084I-1365J-788D01*
G01X288088D01*
G02X286124Y391247I51J2326D01*
G03X284830Y392034I-1365J-787D01*
G01X284689D01*
G02X282744Y393197I70J2325D01*
G03X281450Y393984I-1365J-787D01*
G01X281294D01*
G02X279364Y395146I85J2325D01*
G03X278043Y395934I-1365J-787D01*
G01X277948D01*
G02X275984Y397097I51J2326D01*
G03X274678Y397884I-1365J-788D01*
G01X274549D01*
G02X272604Y399047I70J2325D01*
G01X272384Y399427D01*
X270298Y401513D01*
Y403681D01*
X269151Y404828D01*
X268931D01*
X268869Y404890D01*
G01X301659Y380709D02*
Y382040D01*
G02X302413Y383225I1447J-88D01*
G03X302325Y386038I-752J1384D01*
G02X301617Y386615I797J1701D01*
G03X301054Y387054I-1082J-808D01*
G02X300700Y387258I603J1456D01*
G02X300294Y387722I960J1250D01*
G03X298349Y388885I-2015J-1162D01*
G01X298220D01*
G02X296914Y389672I59J1575D01*
G03X294950Y390835I-2015J-1163D01*
G01X294855D01*
G02X293534Y391623I44J1575D01*
G03X291604Y392785I-2015J-1163D01*
G01X291448D01*
G02X290154Y393572I71J1574D01*
G03X288209Y394735I-2015J-1162D01*
G01X288068D01*
G02X286774Y395522I71J1574D01*
G03X284810Y396685I-2015J-1163D01*
G01X284700D01*
G02X283394Y397472I59J1575D01*
G03X281464Y398634I-2015J-1163D01*
G01X281322D01*
G02X280014Y399422I57J1575D01*
G01X278914Y401329D01*
X267407Y412886D01*
X267408Y413104D01*
X267347Y413165D01*
G01X328698Y349509D02*
Y350840D01*
X328441Y351097D01*
G02X326683Y354572I257J2312D01*
G03X326702Y356113I-1365J787D01*
G01X326683Y356147D01*
X326658Y356189D01*
G02X326683Y358472I2040J1119D01*
G03X326702Y360013I-1365J787D01*
G01X326683Y360047D01*
X326658Y360089D01*
G02X326683Y362372I2040J1119D01*
G03X325362Y364735I-1365J788D01*
G01X325233D01*
G02X323303Y368223I85J2325D01*
G03Y369797I-1365J787D01*
G01X323278Y369839D01*
G02X323303Y372122I2040J1119D01*
G01X323322Y372156D01*
G03X323303Y373697I-1384J754D01*
G02X323278Y375980I2015J1164D01*
G01X323303Y376022D01*
X323322Y376056D01*
G03X323303Y377597I-1384J754D01*
G02X323278Y379880I2015J1164D01*
G01X323303Y379922D01*
G03X323408Y380141I-1364J789D01*
G03X323197Y381669I-1485J573D01*
G01X322596Y382471D01*
Y393450D01*
X318418Y397628D01*
Y404195D01*
X318263Y404350D01*
Y404437D01*
G01X325318Y351460D02*
X323369Y354081D01*
X323303Y354197D01*
G02X323278Y356480I2015J1164D01*
G01X323303Y356522D01*
X323322Y356556D01*
G03X323303Y358097I-1384J754D01*
G02X323278Y360380I2015J1164D01*
G01X323303Y360422D01*
X323322Y360456D01*
G03X321997Y362784I-1384J753D01*
G01X321868D01*
G02X319923Y366272I70J2325D01*
G03X319942Y367813I-1365J787D01*
G01X319923Y367847D01*
G02X319898Y370130I2015J1164D01*
G01X319923Y370172D01*
G03Y371746I-1365J787D01*
G02Y374072I2015J1163D01*
G03X319942Y375613I-1365J787D01*
G01X319923Y375647D01*
X319898Y375689D01*
G02X319923Y377972I2040J1119D01*
G03X319942Y379513I-1365J787D01*
G01X319923Y379547D01*
X319898Y379589D01*
G02X319923Y381872I2040J1119D01*
G03Y383446I-1365J787D01*
G02Y385772I2015J1163D01*
G03X319942Y387313I-1365J787D01*
G01X319923Y387347D01*
X319898Y387389D01*
G02X319923Y389672I2040J1119D01*
G01X319926Y389676D01*
G03X318583Y392034I-1343J797D01*
G01X318488D01*
G02X316543Y393197I70J2325D01*
G01X316217Y393762D01*
X314094Y395885D01*
Y400943D01*
X313099Y401938D01*
G01X325318Y359260D02*
X324019Y362259D01*
X323953Y362372D01*
G03X322023Y363534I-2015J-1163D01*
G01X321894D01*
G02X320573Y365897I44J1575D01*
G03Y368223I-2015J1163D01*
G02Y369797I1365J787D01*
G01X320598Y369839D01*
G03X320573Y372122I-2040J1119D01*
G01X320554Y372156D01*
G02X320573Y373697I1384J754D01*
G03X320598Y375980I-2015J1164D01*
G01X320573Y376022D01*
X320554Y376056D01*
G02X320573Y377597I1384J754D01*
G03X320598Y379880I-2015J1164D01*
G01X320573Y379922D01*
X320554Y379956D01*
G02X320573Y381497I1384J754D01*
G01X320598Y381539D01*
G03X320573Y383822I-2040J1119D01*
G01X320554Y383856D01*
G02X320573Y385397I1384J754D01*
G03X320598Y387680I-2015J1164D01*
G01X320573Y387722D01*
X320554Y387756D01*
G02X320573Y389297I1384J754D01*
G01X320579Y389306D01*
G03X318650Y392785I-1929J1205D01*
G01X318487D01*
G02X317193Y393572I71J1574D01*
G01X317191Y393571D01*
X316816Y394221D01*
X314842Y396195D01*
Y400988D01*
X315668Y401814D01*
G01X321938Y353409D02*
Y354740D01*
X321681Y354997D01*
G02X319923Y358472I257J2312D01*
G03X318602Y360835I-1365J788D01*
G01X318473D01*
G02X316518Y364280I85J2325D01*
G01X316543Y364322D01*
X316562Y364356D01*
G03X316543Y365897I-1384J754D01*
G02Y368223I2015J1163D01*
G03Y369797I-1365J787D01*
G01X316518Y369839D01*
G02X316543Y372122I2040J1119D01*
G01X316562Y372156D01*
G03X316543Y373697I-1384J754D01*
G02X316518Y375980I2015J1164D01*
G01X316543Y376022D01*
X316562Y376056D01*
G03X316543Y377597I-1384J754D01*
G02X316518Y379880I2015J1164D01*
G01X316543Y379922D01*
X316562Y379956D01*
G03X316543Y381497I-1384J754D01*
G02X316518Y383780I2015J1164D01*
G01X316543Y383822D01*
X316562Y383856D01*
G03X316543Y385397I-1384J754D01*
G02X316518Y387680I2015J1164D01*
G01X316543Y387722D01*
X316562Y387756D01*
G03X315237Y390084I-1384J753D01*
G01X313605D01*
X309494Y394195D01*
Y398034D01*
X307971Y399557D01*
G01X321938Y357309D02*
Y355978D01*
X321710Y355750D01*
G02X320573Y358097I228J1559D01*
G03X318628Y361585I-2015J1163D01*
G01X318499D01*
G02X317174Y363913I59J1575D01*
G01X317193Y363947D01*
X317218Y363989D01*
G03X317193Y366272I-2040J1119D01*
G02X317174Y367813I1365J787D01*
G01X317193Y367847D01*
G03X317218Y370130I-2015J1164D01*
G01X317193Y370172D01*
G02Y371746I1365J787D01*
G03Y374072I-2015J1163D01*
G02X317174Y375613I1365J787D01*
G01X317193Y375647D01*
X317218Y375689D01*
G03X317193Y377972I-2040J1119D01*
G02X317174Y379513I1365J787D01*
G01X317193Y379547D01*
X317218Y379589D01*
G03X317193Y381872I-2040J1119D01*
G02X317174Y383413I1365J787D01*
G01X317193Y383447D01*
X317218Y383489D01*
G03X317193Y385772I-2040J1119D01*
G02X317174Y387313I1365J787D01*
G01X317193Y387347D01*
X317218Y387389D01*
G03X315250Y390835I-2040J1120D01*
G01X313917D01*
X310245Y394507D01*
Y400093D01*
X310549Y400397D01*
G01X319323Y404437D02*
Y404350D01*
X319168Y404195D01*
Y397939D01*
X323346Y393761D01*
Y382721D01*
X323798Y382119D01*
G02X324108Y379871I-1875J-1404D01*
G02X323953Y379547I-2184J846D01*
G01X323934Y379513D01*
G03X323953Y377972I1384J-754D01*
G02X323978Y375689I-2015J-1164D01*
G01X323953Y375647D01*
X323934Y375613D01*
G03X323953Y374072I1384J-754D01*
G02Y371746I-2015J-1163D01*
G03Y370172I1365J-787D01*
G01X323978Y370130D01*
G02X323953Y367847I-2040J-1119D01*
G01X323934Y367813D01*
G03X325259Y365485I1384J-753D01*
G01X325388D01*
G02X327333Y361997I-70J-2325D01*
G03X327314Y360456I1365J-787D01*
G01X327333Y360422D01*
X327358Y360380D01*
G02X327333Y358097I-2040J-1119D01*
G03X327314Y356556I1365J-787D01*
G01X327333Y356522D01*
X327358Y356480D01*
G02X327333Y354197I-2040J-1119D01*
G03X328470Y351850I1365J-788D01*
G01X328698Y352078D01*
Y353409D01*
G01Y361209D02*
X328705Y361224D01*
G02X330063Y364322I14719J-4605D01*
G01X330080Y364352D01*
X330082Y364356D01*
G03X328757Y366684I-1384J753D01*
G01X328647D01*
G02X326658Y370130I51J2326D01*
G01X326683Y370172D01*
G03Y371746I-1365J787D01*
G02Y374072I2015J1163D01*
G03X326702Y375613I-1365J787D01*
G01X326683Y375647D01*
X326658Y375689D01*
G02X326682Y377971I2040J1120D01*
G01X326942Y378422D01*
Y393725D01*
X322501Y398165D01*
X322103Y398969D01*
G02X322172Y401146I2070J1024D01*
G01X322381Y401508D01*
Y407345D01*
X322226Y407500D01*
Y407587D01*
G01X328698Y357309D02*
X328705Y357324D01*
G02X330063Y360422I14719J-4605D01*
G03X330224Y361601I-1365J787D01*
G02X330713Y363946I3808J429D01*
G01X330722Y363961D01*
X330724Y363965D01*
X330726Y363968D01*
X330732Y363978D01*
X330736Y363985D01*
X330738Y363989D01*
G03X328749Y367435I-2040J1120D01*
G01X328654D01*
G02X327333Y369797I44J1575D01*
G01X327358Y369839D01*
G03X327333Y372122I-2040J1119D01*
G01X327314Y372156D01*
G02X327333Y373697I1384J754D01*
G03X327358Y375980I-2015J1164D01*
G01X327333Y376022D01*
G02Y377596I1365J787D01*
G01X327692Y378218D01*
Y394036D01*
X323119Y398609D01*
X322776Y399302D01*
G02X322822Y400771I1397J691D01*
G01X323131Y401307D01*
Y407345D01*
X323286Y407500D01*
Y407587D01*
G01X345298Y200336D02*
Y201319D01*
X344023Y202594D01*
Y203672D01*
X344233Y204047D01*
G03X344258Y206330I-2015J1164D01*
G01X344233Y206372D01*
G02Y207946I1365J787D01*
G03Y210272I-2015J1163D01*
G02X344214Y211813I1365J787D01*
G01X344233Y211847D01*
X344258Y211889D01*
G03X344233Y214172I-2040J1119D01*
G02X344214Y215713I1365J787D01*
G01X344233Y215747D01*
X344258Y215789D01*
G03X344233Y218072I-2040J1119D01*
G02X344214Y219613I1365J787D01*
G01X344233Y219647D01*
X344258Y219689D01*
G03X344233Y221972I-2040J1119D01*
G02X344214Y223513I1365J787D01*
G01X344233Y223547D01*
X344258Y223589D01*
G03X344233Y225872I-2040J1119D01*
G02X344214Y227413I1365J787D01*
G01X344233Y227447D01*
G03X344258Y229730I-2015J1164D01*
G01X344233Y229772D01*
G02Y231346I1365J787D01*
G01X344398Y231632D01*
X345888Y232803D01*
X346427Y233120D01*
G03X346963Y233672I-828J1341D01*
G01X347029Y233788D01*
G03X347192Y234404I-1083J616D01*
G01Y235801D01*
X347800Y236409D01*
X348978D01*
G01Y240309D02*
Y239413D01*
X350892Y237499D01*
Y235500D01*
X349892Y234500D01*
X349028D01*
X348555Y234027D01*
G03X347403Y232463I423J-1518D01*
G01X347347Y231591D01*
X347132Y230066D01*
X346938Y229730D01*
G03X346963Y227447I2040J-1119D01*
G01X346982Y227413D01*
G02X346963Y225872I-1384J-754D01*
G03X346938Y223589I2015J-1164D01*
G01X346963Y223547D01*
X346982Y223513D01*
G02X346963Y221972I-1384J-754D01*
G03X346938Y219689I2015J-1164D01*
G01X346963Y219647D01*
X346982Y219613D01*
G02X346963Y218072I-1384J-754D01*
G03X346938Y215789I2015J-1164D01*
G01X346963Y215747D01*
X346982Y215713D01*
G02X346963Y214172I-1384J-754D01*
G03X346938Y211889I2015J-1164D01*
G01X346963Y211847D01*
X346982Y211813D01*
G02X346963Y210272I-1384J-754D01*
G03Y207946I2015J-1163D01*
G02Y206372I-1365J-787D01*
G01X346938Y206330D01*
G03X346963Y204047I2040J-1119D01*
G01X347298Y203468D01*
Y201105D01*
G01X352357Y234460D02*
X350405Y231832D01*
X350342Y231722D01*
G02X349800Y231166I-1364J787D01*
G01X348813Y230516D01*
X347775Y229678D01*
X347613Y229397D01*
G03Y227823I1365J-787D01*
G02Y225497I-2015J-1163D01*
G03X347594Y223956I1365J-787D01*
G01X347613Y223922D01*
X347638Y223880D01*
G02X347613Y221597I-2040J-1119D01*
G03X347594Y220056I1365J-787D01*
G01X347613Y220022D01*
X347638Y219980D01*
G02X347613Y217697I-2040J-1119D01*
G03X347594Y216156I1365J-787D01*
G01X347613Y216122D01*
X347638Y216080D01*
G02X347613Y213797I-2040J-1119D01*
G03X347594Y212256I1365J-787D01*
G01X347613Y212222D01*
X347638Y212180D01*
G02X347613Y209897I-2040J-1119D01*
G03X347594Y208356I1365J-787D01*
G01X347613Y208322D01*
G02X347638Y206039I-2015J-1164D01*
G01X347613Y205997D01*
G03Y204423I1365J-787D01*
G01X349298Y201759D01*
Y200994D01*
G01X345598Y234460D02*
X345558Y234454D01*
X343770Y232048D01*
X343583Y231722D01*
G03X343558Y229439I2015J-1164D01*
G01X343583Y229397D01*
G02Y227823I-1365J-787D01*
G03Y225497I2015J-1163D01*
G02X343602Y223956I-1365J-787D01*
G01X343583Y223922D01*
X343558Y223880D01*
G03X343583Y221597I2040J-1119D01*
G02X343602Y220056I-1365J-787D01*
G01X343583Y220022D01*
X343558Y219980D01*
G03X343583Y217697I2040J-1119D01*
G02X343602Y216156I-1365J-787D01*
G01X343583Y216122D01*
X343558Y216080D01*
G03X343583Y213797I2040J-1119D01*
G02X343602Y212256I-1365J-787D01*
G01X343583Y212222D01*
X343558Y212180D01*
G03X343583Y209897I2040J-1119D01*
G02X343602Y208356I-1365J-787D01*
G01X343583Y208322D01*
G03X343558Y206039I2015J-1164D01*
G01X343583Y205997D01*
G02Y204422I-1365J-787D01*
G01X343273Y203868D01*
Y200681D01*
G01X342218Y240309D02*
X340919Y237310D01*
X340203Y236071D01*
G03Y235247I714J-412D01*
G01X340222Y235213D01*
G02X340203Y233672I-1384J-754D01*
G03Y231346I2015J-1163D01*
G02X340409Y230685I-1365J-788D01*
G01X340413Y230681D01*
Y230520D01*
G02X340223Y229807I-1576J38D01*
G01X339592Y228712D01*
Y226900D01*
X337785Y225093D01*
Y224700D01*
G02X337473Y223548I-2327J12D01*
G03Y221974I1365J-787D01*
G02Y219648I-2015J-1163D01*
G03Y218074I1365J-787D01*
G02Y215748I-2015J-1163D01*
G03Y214174I1365J-787D01*
G02Y211848I-2015J-1163D01*
G03X337262Y211047I1365J-788D01*
G01Y202330D01*
X338503Y201089D01*
Y193842D01*
X337273Y192612D01*
Y190678D01*
G01X342218Y228610D02*
X340919Y225611D01*
X340853Y225497D01*
G03X340834Y223956I1365J-787D01*
G01X340853Y223922D01*
X340878Y223880D01*
G02X340853Y221597I-2040J-1119D01*
G03X340834Y220056I1365J-787D01*
G01X340853Y220022D01*
X340878Y219980D01*
G02X340853Y217697I-2040J-1119D01*
G03X340834Y216156I1365J-787D01*
G01X340853Y216122D01*
X340878Y216080D01*
G02X340853Y213797I-2040J-1119D01*
G03X340834Y212256I1365J-787D01*
G01X340853Y212222D01*
X340878Y212180D01*
G02X340853Y209897I-2040J-1119D01*
G03X340834Y208356I1365J-787D01*
G01X340853Y208322D01*
G02X340878Y206039I-2015J-1164D01*
G01X340853Y205997D01*
G03Y204423I1365J-787D01*
G01X341273Y203694D01*
Y200481D01*
G01X342218Y236409D02*
X340919Y233410D01*
X340853Y233297D01*
G03X340834Y231756I1365J-787D01*
G01X340922Y231599D01*
G02X340907Y229488I-1865J-1042D01*
G01X340453Y228703D01*
Y226461D01*
X339891Y225899D01*
Y224730D01*
G03X340178Y223589I2327J-21D01*
G01X340203Y223547D01*
X340222Y223513D01*
G02X340203Y221972I-1384J-754D01*
G03X340178Y219689I2015J-1164D01*
G01X340203Y219647D01*
X340222Y219613D01*
G02X340203Y218072I-1384J-754D01*
G03X340178Y215789I2015J-1164D01*
G01X340203Y215747D01*
X340222Y215713D01*
G02X340203Y214172I-1384J-754D01*
G03X340178Y211889I2015J-1164D01*
G01X340203Y211847D01*
X340222Y211813D01*
G02X340203Y210272I-1384J-754D01*
G03Y207946I2015J-1163D01*
G02Y206372I-1365J-787D01*
G03Y204048I2015J-1162D01*
G01X340423Y203666D01*
Y202376D01*
X339746Y201699D01*
Y192830D01*
X339273Y192357D01*
Y191212D01*
G01X359117Y242260D02*
X360417Y239260D01*
X360482Y239148D01*
G02Y237574I-1365J-787D01*
G03Y235248I2015J-1163D01*
G02Y233674I-1365J-787D01*
G03Y231348I2015J-1163D01*
G02Y229774I-1365J-787D01*
G03Y227448I2015J-1163D01*
G02Y225874I-1365J-787D01*
G03Y223548I2015J-1163D01*
G02Y221974I-1365J-787D01*
G03Y219648I2015J-1163D01*
G02Y218074I-1365J-787D01*
G03Y215748I2015J-1163D01*
G02Y214174I-1365J-787D01*
G03Y211848I2015J-1163D01*
G02Y210274I-1365J-787D01*
G03X359818Y207795I4295J-2479D01*
G01Y201661D01*
X363298Y198181D01*
Y196375D01*
G01X365298Y196325D02*
Y198114D01*
X360913Y202499D01*
Y209080D01*
G02X361132Y209898I1638J0D01*
G03Y212224I-2015J1163D01*
G02Y213798I1365J787D01*
G03Y216124I-2015J1163D01*
G02Y217698I1365J787D01*
G03Y220024I-2015J1163D01*
G02Y221598I1365J787D01*
G03Y223924I-2015J1163D01*
G02Y225498I1365J787D01*
G03Y227824I-2015J1163D01*
G02Y229398I1365J787D01*
G03Y231724I-2015J1163D01*
G02Y233298I1365J787D01*
G03Y235624I-2015J1163D01*
G02Y237198I1365J787D01*
G01X361197Y237310D01*
X362497Y240309D01*
G01X359117Y230559D02*
X357817Y227560D01*
X357752Y227448D01*
G03Y225874I1365J-787D01*
G02Y223548I-2015J-1163D01*
G03Y221974I1365J-787D01*
G02Y219648I-2015J-1163D01*
G03Y218074I1365J-787D01*
G02Y215748I-2015J-1163D01*
G03Y214174I1365J-787D01*
G02Y211848I-2017J-1163D01*
G03Y210274I1365J-787D01*
G02X358403Y207844I-4211J-2430D01*
G01Y200687D01*
X361298Y197792D01*
Y191275D01*
G01X359298Y191225D02*
Y192441D01*
X359598Y192741D01*
Y197391D01*
X357363Y199626D01*
Y208923D01*
G03X357102Y209898I-1952J0D01*
G02Y212224I2015J1163D01*
G03Y213798I-1364J787D01*
G02Y216124I2015J1163D01*
G03Y217698I-1365J787D01*
G02Y220024I2015J1163D01*
G03Y221598I-1365J787D01*
G02Y223924I2015J1163D01*
G03Y225498I-1365J787D01*
G02Y227824I2015J1163D01*
G03X357311Y228546I-1365J786D01*
G02X357420Y229289I3579J-146D01*
G03X357552Y230379I-2197J819D01*
G02X357752Y231348I1565J182D01*
G01X358068Y231881D01*
X359117Y234460D01*
G01X355737Y228610D02*
X354938Y226475D01*
X354372Y225497D01*
G03X354353Y223956I1365J-787D01*
G01X354372Y223922D01*
X354397Y223880D01*
G02X354372Y221597I-2040J-1119D01*
G03X354353Y220056I1365J-787D01*
G01X354372Y220022D01*
X354397Y219980D01*
G02X354372Y217697I-2040J-1119D01*
G03X354353Y216156I1365J-787D01*
G01X354372Y216122D01*
X354397Y216080D01*
G02X354372Y213797I-2040J-1119D01*
G03X354353Y212256I1365J-787D01*
G01X354372Y212222D01*
X354397Y212180D01*
G02X354372Y209897I-2040J-1119D01*
G01X354092Y209412D01*
Y204400D01*
X356398Y202094D01*
Y192691D01*
X357298Y191791D01*
Y191175D01*
G01X355737Y236409D02*
X357036Y233410D01*
X357102Y233297D01*
G02X356495Y231128I-1365J-787D01*
G01X355210Y230293D01*
X354534Y229678D01*
X354372Y229397D01*
G03X354162Y228648I1365J-787D01*
G01X354102Y228047D01*
X353932Y226696D01*
G02X353722Y225872I-1575J-37D01*
G03X353697Y223589I2015J-1164D01*
G01X353722Y223547D01*
X353741Y223513D01*
G02X353722Y221972I-1384J-754D01*
G03X353697Y219689I2015J-1164D01*
G01X353722Y219647D01*
X353741Y219613D01*
G02X353722Y218072I-1384J-754D01*
G03X353697Y215789I2015J-1164D01*
G01X353722Y215747D01*
X353741Y215713D01*
G02X353722Y214172I-1384J-754D01*
G03X353697Y211889I2015J-1164D01*
G01X353722Y211847D01*
X353741Y211813D01*
G02X353722Y210273I-1384J-753D01*
G01X353290Y209525D01*
Y203902D01*
X355298Y201894D01*
Y190725D01*
G01X352357Y242260D02*
X353654Y239264D01*
X353741Y239113D01*
G02X353722Y237572I-1384J-754D01*
G03X353697Y235289I2015J-1164D01*
G01X353722Y235247D01*
X353741Y235213D01*
G02X353722Y233672I-1384J-754D01*
G01X353543Y233362D01*
X351781Y232025D01*
G03X350782Y230566I576J-1466D01*
G01X350564Y228364D01*
X350455Y228063D01*
G02X350342Y227823I-1476J548D01*
G01X350317Y227781D01*
G03X350342Y225496I2040J-1120D01*
G02Y223922I-1364J-787D01*
G01X350307Y223862D01*
G03X350342Y221596I2050J-1102D01*
G02Y220022I-1364J-787D01*
G01X350307Y219962D01*
G03X350342Y217696I2050J-1102D01*
G02Y216122I-1364J-787D01*
G01X350307Y216062D01*
G03X350342Y213796I2050J-1102D01*
G02Y212222I-1364J-787D01*
G01X350307Y212162D01*
G03X350342Y209896I2050J-1102D01*
G02X351092Y207099I-4842J-2797D01*
G01Y201580D01*
X351298Y201374D01*
Y200173D01*
G01X355737Y240309D02*
X354438Y237310D01*
X354372Y237197D01*
G03X354353Y235656I1365J-787D01*
G01X354372Y235622D01*
X354397Y235580D01*
G02X354372Y233297I-2040J-1119D01*
G03X354167Y232643I1365J-787D01*
G01X353975Y230484D01*
X353858Y230008D01*
X353722Y229772D01*
G02X353244Y229248I-1430J825D01*
G01X351528Y228035D01*
G03X350993Y227448I1069J-1512D01*
G03Y225874I1364J-787D01*
G02Y223548I-2015J-1163D01*
G03Y221974I1364J-787D01*
G02Y219648I-2015J-1163D01*
G03Y218074I1364J-787D01*
G02Y215748I-2015J-1163D01*
G03Y214174I1364J-787D01*
G01X351023Y214122D01*
X351024Y214117D01*
G02X351028Y211907I-2046J-1109D01*
G01X350993Y211847D01*
X350992D01*
G02X350963Y211796I-2033J1122D01*
G03X350991Y210272I1394J-737D01*
G01X351242Y209837D01*
G02X352192Y206284I-6168J-3553D01*
G01Y203600D01*
X353298Y202494D01*
Y200493D01*
G01X329220Y194186D02*
X330538Y195504D01*
Y198615D01*
X332538Y200615D01*
Y202031D01*
X331626Y202943D01*
Y214987D01*
X330063Y217698D01*
G02Y220022I2015J1162D01*
G01X330082Y220056D01*
G03X330063Y221597I-1384J754D01*
G02X332008Y225085I2015J1163D01*
G01X332137D01*
G03X333443Y225872I-59J1575D01*
G02X335407Y227035I2015J-1163D01*
G01X335502D01*
G03X336823Y229397I-44J1575D01*
G01X336798Y229439D01*
G02X336823Y231722I2040J1119D01*
G01X336842Y231756D01*
G03X336823Y233297I-1384J754D01*
G02X336798Y235580I2015J1164D01*
G01X336823Y235622D01*
X336842Y235656D01*
G03X336823Y237197I-1384J754D01*
G02X336602Y237718I2016J1162D01*
G01X335458Y240309D01*
G01X331789Y194186D02*
X331286Y194689D01*
Y198293D01*
X333286Y200293D01*
Y202344D01*
X332376Y203254D01*
Y215186D01*
X330713Y218073D01*
G02Y219647I1365J787D01*
G01X330738Y219689D01*
G03X330713Y221972I-2040J1119D01*
G02X332034Y224335I1365J788D01*
G01X332163D01*
G03X334093Y225497I-85J2325D01*
G02X335399Y226284I1365J-788D01*
G01X335509D01*
G03X337498Y229730I-51J2326D01*
G01X337473Y229772D01*
G02Y231346I1365J787D01*
G03Y233672I-2015J1163D01*
G02X337454Y235213I1365J787D01*
G01X337473Y235247D01*
X337498Y235289D01*
G03X337473Y237572I-2040J1119D01*
G02X337454Y239113I1365J787D01*
G01X337473Y239147D01*
X337498Y239189D01*
G03X336972Y242076I-2040J1120D01*
G01Y242798D01*
X337918Y243744D01*
Y244724D01*
X336432Y246210D01*
X335848D01*
X335458Y245820D01*
Y244209D01*
G01X324028Y192131D02*
X325038Y193141D01*
Y194861D01*
X327800Y197623D01*
Y200383D01*
X328608Y201191D01*
Y212851D01*
X327448Y214011D01*
Y218323D01*
X326658Y219689D01*
G02X326683Y221972I2040J1119D01*
G03X326702Y223513I-1365J787D01*
G01X326683Y223547D01*
X326658Y223589D01*
G02X328647Y227035I2040J1120D01*
G01X328742D01*
G03X330063Y227823I-44J1575D01*
G02X331993Y228985I2015J-1163D01*
G01X332149D01*
G03X333443Y231346I-71J1574D01*
G02Y233672I2015J1163D01*
G03X333462Y235213I-1365J787D01*
G01X333375Y235364D01*
X332078Y238360D01*
G01X326578Y192141D02*
X325788Y192931D01*
Y194550D01*
X328550Y197312D01*
Y200075D01*
X329356Y200881D01*
Y213164D01*
X328198Y214322D01*
Y218522D01*
X327314Y220056D01*
G02X327333Y221597I1384J754D01*
G03X327358Y223880I-2015J1164D01*
G01X327333Y223922D01*
X327314Y223956D01*
G02X328639Y226284I1384J753D01*
G01X328749D01*
G03X330713Y227447I-51J2326D01*
G02X332007Y228234I1365J-787D01*
G01X332148D01*
G03X334093Y231722I-70J2325D01*
G01X334074Y231756D01*
G02X334093Y233297I1384J754D01*
G03X334118Y235580I-2015J1164D01*
G01X334093Y235622D01*
X334074Y235656D01*
G02X334093Y237197I1384J754D01*
G03X334118Y239480I-2015J1164D01*
G01X334093Y239522D01*
X334074Y239556D01*
G02X334093Y241097I1384J754D01*
G01X334057Y242153D01*
X332078Y246160D01*
G01X308418Y216909D02*
X309116Y214947D01*
X309783Y213795D01*
G02Y212221I-1365J-787D01*
G01X309758Y212179D01*
G03X309470Y211056I2047J-1123D01*
G01Y206468D01*
X300687Y197685D01*
X299837D01*
X295898Y193746D01*
Y192029D01*
G01X296648D02*
Y193435D01*
X300148Y196935D01*
X300998D01*
X310220Y206157D01*
Y209161D01*
X310222Y211060D01*
G02X310433Y211846I1576J-2D01*
G01X310458Y211888D01*
G03X310433Y214171I-2040J1119D01*
G01X310000Y214947D01*
Y220549D01*
X309740Y220809D01*
X308418D01*
G01X335458Y353409D02*
Y352209D01*
X334738Y351489D01*
X334190D01*
X333508Y352171D01*
Y354081D01*
X334588Y355161D01*
Y355771D01*
X333738Y356621D01*
Y357742D01*
X334093Y358097D01*
G02X335399Y358884I1365J-788D01*
G01X335400D01*
G03X336204Y359349I0J928D01*
G01X336286Y359491D01*
Y359680D01*
X336772Y360334D01*
X336842Y360456D01*
G03X336823Y361997I-1384J754D01*
G02X336798Y364280I2015J1164D01*
G01X336823Y364322D01*
X336842Y364356D01*
G03X336823Y365897I-1384J754D01*
G02Y368223I2015J1163D01*
G03X335529Y370584I-1365J787D01*
G01X335373D01*
G02X333443Y374072I85J2325D01*
G03X333462Y375613I-1365J787D01*
G01X333443Y375647D01*
X333418Y375689D01*
G02X333443Y377972I2040J1119D01*
G03X333462Y379513I-1365J787D01*
G01X333080Y380197D01*
Y400109D01*
X332048Y401141D01*
Y405793D01*
X331150Y406691D01*
G01X335458Y357309D02*
X335756Y357607D01*
X336554D01*
X337262Y358315D01*
Y359736D01*
X337407Y359931D01*
X337473Y360047D01*
X337498Y360089D01*
G03X337473Y362372I-2040J1119D01*
G02X337454Y363913I1365J787D01*
G01X337473Y363947D01*
X337498Y363989D01*
G03X337473Y366272I-2040J1119D01*
G02X337454Y367813I1365J787D01*
G01X337473Y367847D01*
G03X335528Y371335I-2015J1163D01*
G01X335387D01*
G02X334093Y373697I71J1574D01*
G03X334118Y375980I-2015J1164D01*
G01X334093Y376022D01*
X334074Y376056D01*
G02X334093Y377597I1384J754D01*
G03X334118Y379880I-2015J1164D01*
G01X333828Y380396D01*
Y400419D01*
X332796Y401451D01*
Y405787D01*
X333700Y406691D01*
G01X332078Y351460D02*
X330627Y354747D01*
G02X330506Y355474I1451J615D01*
G01D02*
X330504Y359184D01*
G02X330998Y360408I1574J77D01*
G02X332812Y361767I5140J-4970D01*
G03X333443Y362372I-723J1386D01*
G03X333462Y363913I-1365J787D01*
G01X333443Y363947D01*
X333418Y363989D01*
G02X333443Y366272I2040J1119D01*
G03X332149Y368634I-1365J788D01*
G01X332008D01*
G02X330063Y372122I70J2325D01*
G01X330082Y372156D01*
G03X330063Y373697I-1384J754D01*
G02X330038Y375980I2015J1164D01*
G01X330063Y376022D01*
X330082Y376056D01*
G03X330063Y377597I-1384J754D01*
G01X329501Y378570D01*
Y379930D01*
X329980Y380409D01*
Y396199D01*
X327030Y399149D01*
Y405711D01*
X326050Y406691D01*
G01X332078Y359260D02*
G03X334093Y361997I-11295J10426D01*
G03X334118Y364280I-2015J1164D01*
G01X334093Y364322D01*
X334074Y364356D01*
G02X334093Y365897I1384J754D01*
G03X332163Y369385I-2015J1163D01*
G01X332007D01*
G02X330713Y371746I71J1574D01*
G03Y374072I-2015J1163D01*
G02X330694Y375613I1365J787D01*
G01X330713Y375647D01*
X330738Y375689D01*
G03X330713Y377972I-2040J1119D01*
G01X330249Y378774D01*
Y379620D01*
X330728Y380099D01*
Y396510D01*
X330509Y396729D01*
Y396728D01*
X327778Y399459D01*
Y405869D01*
X328600Y406691D01*
G01X345598Y355360D02*
X346706Y357811D01*
G02X346963Y358472I2272J-503D01*
G03X346982Y360013I-1365J787D01*
G01X346963Y360047D01*
X346938Y360089D01*
G02X346963Y362372I2040J1119D01*
G03X346982Y363913I-1365J787D01*
G01X346963Y363947D01*
X346938Y363989D01*
G02X346963Y366272I2040J1119D01*
G03X346982Y367813I-1365J787D01*
G01X346963Y367847D01*
G02X346938Y370130I2015J1164D01*
G01X346963Y370172D01*
G03Y371746I-1365J787D01*
G02Y374072I2015J1163D01*
G03X346982Y375613I-1365J787D01*
G01X346963Y375647D01*
X346938Y375689D01*
G02X346963Y377972I2040J1119D01*
G03X346982Y379513I-1365J787D01*
G01X346963Y379547D01*
X346938Y379589D01*
G02X346963Y381872I2040J1119D01*
G03X346982Y383413I-1365J787D01*
G01X346963Y383447D01*
X346938Y383489D01*
G02X346963Y385772I2040J1119D01*
G03X346982Y387313I-1365J787D01*
G01X346963Y387347D01*
X346938Y387389D01*
G02X346963Y389672I2040J1119D01*
G03X346982Y391213I-1365J787D01*
G01X345792Y393264D01*
Y398948D01*
G01X345598Y351460D02*
X347452Y353954D01*
G03X347638Y356480I-1854J1406D01*
G01X347613Y356522D01*
X347594Y356556D01*
G02X347613Y358097I1384J754D01*
G03X347638Y360380I-2015J1164D01*
G01X347613Y360422D01*
X347594Y360456D01*
G02X347613Y361997I1384J754D01*
G03X347638Y364280I-2015J1164D01*
G01X347613Y364322D01*
X347594Y364356D01*
G02X347613Y365897I1384J754D01*
G03Y368223I-2015J1163D01*
G02Y369797I1365J787D01*
G01X347638Y369839D01*
G03X347613Y372122I-2040J1119D01*
G01X347594Y372156D01*
G02X347613Y373697I1384J754D01*
G03X347638Y375980I-2015J1164D01*
G01X347613Y376022D01*
X347594Y376056D01*
G02X347613Y377597I1384J754D01*
G03X347638Y379880I-2015J1164D01*
G01X347613Y379922D01*
X347594Y379956D01*
G02X347613Y381497I1384J754D01*
G03X347638Y383780I-2015J1164D01*
G01X347613Y383822D01*
X347594Y383856D01*
G02X347613Y385397I1384J754D01*
G03Y387723I-2015J1163D01*
G01Y387722D01*
X347594Y387756D01*
G02X347613Y389297I1384J754D01*
G03Y391623I-2015J1163D01*
G01X347392Y392015D01*
Y393960D01*
X347792Y394360D01*
Y395781D01*
G01X348978Y361209D02*
X350276Y364208D01*
X350342Y364322D01*
G03Y365896I-1364J787D01*
G02X350317Y368181I2015J1165D01*
G01X350342Y368223D01*
G03Y369797I-1364J787D01*
G01X350317Y369839D01*
G02X350342Y372122I2040J1119D01*
G03Y373696I-1364J787D01*
G02X350307Y375962I2015J1164D01*
G01X350342Y376022D01*
G03Y377596I-1364J787D01*
G02X350307Y379862I2015J1164D01*
G01X350342Y379922D01*
G03Y381496I-1364J787D01*
G02X350307Y383762I2015J1164D01*
G01X350342Y383822D01*
G03Y385396I-1364J787D01*
G02X350307Y387662I2015J1164D01*
G01X350342Y387722D01*
G03X350692Y389017I-2219J1295D01*
G01Y398000D01*
X349618Y399074D01*
Y404226D01*
X349792Y404400D01*
Y405706D01*
G01X345598Y363160D02*
X343892Y364866D01*
Y367506D01*
X344233Y367847D01*
G03X344258Y370130I-2015J1164D01*
G01X344233Y370172D01*
G02Y371746I1365J787D01*
G03Y374072I-2015J1163D01*
G02X344214Y375613I1365J787D01*
G01X344233Y375647D01*
X344258Y375689D01*
G03X344233Y377972I-2040J1119D01*
G02X344214Y379513I1365J787D01*
G01X344233Y379547D01*
X344258Y379589D01*
G03X344233Y381872I-2040J1119D01*
G02X344214Y383413I1365J787D01*
G01X344233Y383447D01*
X344258Y383489D01*
G03X344233Y385772I-2040J1119D01*
G02X344214Y387313I1365J787D01*
G01X344233Y387347D01*
X344258Y387389D01*
G03X344233Y389672I-2040J1119D01*
G02X344214Y391213I1365J787D01*
G01X344592Y391881D01*
Y397960D01*
X343792Y398760D01*
Y399647D01*
G01X342218Y357309D02*
Y358674D01*
X339946Y360946D01*
Y361710D01*
G02X340203Y362372I2272J-501D01*
G03X340222Y363913I-1365J787D01*
G01X340203Y363947D01*
X340178Y363989D01*
G02X340203Y366272I2040J1119D01*
G03X340222Y367813I-1365J787D01*
G01X340203Y367847D01*
G02X340178Y370130I2015J1164D01*
G01X340203Y370172D01*
G03Y371746I-1365J787D01*
G02Y374072I2015J1163D01*
G03X340222Y375613I-1365J787D01*
G01X340203Y375647D01*
X340178Y375689D01*
G02X340203Y377972I2040J1119D01*
G03X340222Y379513I-1365J787D01*
G01X340203Y379547D01*
X340178Y379589D01*
G02X340203Y381872I2040J1119D01*
G03X340222Y383413I-1365J787D01*
G01X340203Y383447D01*
X340178Y383489D01*
G02X340203Y385772I2040J1119D01*
G03X340222Y387313I-1365J787D01*
G01X340203Y387347D01*
G03X339871Y387778I-1630J-912D01*
G01X339692Y387957D01*
Y390400D01*
X339492Y390600D01*
Y397100D01*
X337792Y398800D01*
Y399687D01*
G01X342218Y369010D02*
G02X342692Y370800I2254J361D01*
G03X343583Y372122I-7456J5987D01*
G01X343602Y372156D01*
G03X343583Y373697I-1384J754D01*
G02X343558Y375980I2015J1164D01*
G01X343583Y376022D01*
X343602Y376056D01*
G03X343583Y377597I-1384J754D01*
G02X343558Y379880I2015J1164D01*
G01X343583Y379922D01*
X343602Y379956D01*
G03X343583Y381497I-1384J754D01*
G02X343558Y383780I2015J1164D01*
G01X343583Y383822D01*
X343602Y383856D01*
G03X343583Y385397I-1384J754D01*
G02X343558Y387680I2015J1164D01*
G01X343583Y387722D01*
X343602Y387756D01*
G03X343583Y389297I-1384J754D01*
G02X343473Y391409I2015J1164D01*
G01Y391571D01*
G02X343692Y392100I748J0D01*
G01Y397000D01*
X341792Y398900D01*
Y399889D01*
G01X339792Y399607D02*
Y398654D01*
X340292Y398154D01*
Y390900D01*
X340545Y390647D01*
Y388797D01*
G03X340853Y387722I2194J47D01*
G01X340878Y387680D01*
G02X340853Y385397I-2040J-1119D01*
G03X340834Y383856I1365J-787D01*
G01X340853Y383822D01*
X340878Y383780D01*
G02X340853Y381497I-2040J-1119D01*
G03X340834Y379956I1365J-787D01*
G01X340853Y379922D01*
X340878Y379880D01*
G02X340853Y377597I-2040J-1119D01*
G03X340834Y376056I1365J-787D01*
G01X340853Y376022D01*
X340878Y375980D01*
G02X340853Y373697I-2040J-1119D01*
G03X340834Y372156I1365J-787D01*
G01X340853Y372122D01*
G02X340878Y369839I-2015J-1164D01*
G01X340853Y369797D01*
G03Y368223I1365J-787D01*
G02Y365897I-2015J-1163D01*
G03X340834Y364356I1365J-787D01*
G01X340921Y364205D01*
X342218Y361209D01*
G01X352357Y351460D02*
X350782Y354245D01*
Y363179D01*
G02X350993Y363947I1575J-20D01*
G01X351028Y364007D01*
G03X350993Y366273I-2050J1102D01*
G02Y367847I1364J787D01*
G03X351018Y370130I-2015J1164D01*
G01X350993Y370172D01*
G02Y371746I1364J787D01*
G01X351018Y371788D01*
G03X350993Y374073I-2040J1120D01*
G02Y375647I1364J787D01*
G01X351028Y375707D01*
G03X350993Y377973I-2050J1102D01*
G02Y379547I1364J787D01*
G01X351028Y379607D01*
G03X350993Y381873I-2050J1102D01*
G02Y383447I1364J787D01*
G01X351028Y383507D01*
G03X350993Y385773I-2050J1102D01*
G02Y387347I1364J787D01*
G02X351486Y387908I1652J-955D01*
G01X351768Y388190D01*
Y397977D01*
X352792Y399001D01*
Y403600D01*
X351792Y404600D01*
Y406100D01*
G01X352357Y355360D02*
X353656Y358359D01*
X353722Y358472D01*
G03X353741Y360013I-1365J787D01*
G01X353722Y360047D01*
X353697Y360089D01*
G02X353722Y362372I2040J1119D01*
G03X353741Y363913I-1365J787D01*
G01X353722Y363947D01*
X353697Y363989D01*
G02X353722Y366272I2040J1119D01*
G03X353741Y367813I-1365J787D01*
G01X353722Y367847D01*
G02X353697Y370130I2015J1164D01*
G01X353722Y370172D01*
G03Y371746I-1365J787D01*
G02Y374072I2015J1163D01*
G03X353741Y375613I-1365J787D01*
G01X353722Y375647D01*
X353697Y375689D01*
G02X353722Y377972I2040J1119D01*
G03X353741Y379513I-1365J787D01*
G01X353722Y379547D01*
X353697Y379589D01*
G02X353722Y381872I2040J1119D01*
G03X353741Y383413I-1365J787D01*
G01X353722Y383447D01*
X353697Y383489D01*
G02X353722Y385772I2040J1119D01*
G03X353741Y387313I-1365J787D01*
G01X353722Y387347D01*
G02X353092Y389766I4328J2419D01*
G01Y393554D01*
X353792Y394254D01*
Y405714D01*
G01X355737Y357309D02*
X354440Y360305D01*
X354353Y360456D01*
G02X354372Y361997I1384J754D01*
G03X354397Y364280I-2015J1164D01*
G01X354372Y364322D01*
X354353Y364356D01*
G02X354372Y365897I1384J754D01*
G03Y368223I-2015J1163D01*
G02Y369797I1365J787D01*
G01X354397Y369839D01*
G03X354372Y372122I-2040J1119D01*
G01X354353Y372156D01*
G02X354372Y373697I1384J754D01*
G03X354397Y375980I-2015J1164D01*
G01X354372Y376022D01*
X354353Y376056D01*
G02X354372Y377597I1384J754D01*
G03X354397Y379880I-2015J1164D01*
G01X354372Y379922D01*
X354353Y379956D01*
G02X354372Y381497I1384J754D01*
G03X354397Y383780I-2015J1164D01*
G01X354372Y383822D01*
X354353Y383856D01*
G02X354372Y385397I1384J754D01*
G03X354397Y387680I-2015J1164D01*
G02X354118Y388694I1703J1014D01*
G01Y393330D01*
X354892Y394104D01*
Y403728D01*
X355792Y404628D01*
Y413600D01*
G01X359117Y363160D02*
X360416Y366159D01*
X360482Y366272D01*
G03X360501Y367813I-1365J787D01*
G01X360482Y367847D01*
G02X360457Y370130I2015J1164D01*
G01X360482Y370172D01*
G03Y371746I-1365J787D01*
G02Y374072I2015J1163D01*
G03X360501Y375613I-1365J787D01*
G01X360482Y375647D01*
X360457Y375689D01*
G02X360482Y377972I2040J1119D01*
G03X360501Y379513I-1365J787D01*
G01X360482Y379547D01*
X360457Y379589D01*
G02X360482Y381872I2040J1119D01*
G03X360501Y383413I-1365J787D01*
G01X360482Y383447D01*
X360457Y383489D01*
G02X360482Y385772I2040J1119D01*
G03X360501Y387313I-1365J787D01*
G01X359732Y388689D01*
X359718Y388703D01*
Y400026D01*
X360532Y400840D01*
Y404760D01*
G01X355737Y361209D02*
X357686Y363831D01*
X357752Y363947D01*
X357777Y363989D01*
G03X357752Y366272I-2040J1119D01*
G02X357733Y367813I1365J787D01*
G01X357752Y367847D01*
G03X357777Y370130I-2015J1164D01*
G01X357752Y370172D01*
G02Y371746I1365J787D01*
G03Y374072I-2015J1163D01*
G02X357733Y375613I1365J787D01*
G01X357752Y375647D01*
X357777Y375689D01*
G03X357752Y377972I-2040J1119D01*
G02X357733Y379513I1365J787D01*
G01X357752Y379547D01*
X357777Y379589D01*
G03X357752Y381872I-2040J1119D01*
G02X357733Y383413I1365J787D01*
G01X357752Y383447D01*
X357777Y383489D01*
G03X357752Y385772I-2040J1119D01*
G02X357733Y387313I1365J787D01*
G01X357752Y387347D01*
G03X358518Y390209I-4963J2862D01*
G01Y400826D01*
X359692Y402000D01*
Y403348D01*
X358501Y404539D01*
Y405305D01*
G01X355737Y369010D02*
X357037Y372010D01*
X357121Y372156D01*
G03X357102Y373697I-1384J754D01*
G02X357077Y375980I2015J1164D01*
G01X357102Y376022D01*
X357121Y376056D01*
G03X357102Y377597I-1384J754D01*
G02X357077Y379880I2015J1164D01*
G01X357102Y379922D01*
X357121Y379956D01*
G03X357102Y381497I-1384J754D01*
G02X357077Y383780I2015J1164D01*
G01X357102Y383822D01*
X357121Y383856D01*
G03X357102Y385397I-1384J754D01*
G02X357077Y387680I2015J1164D01*
G01X357102Y387722D01*
G03X357313Y388501I-1365J788D01*
G01Y391495D01*
X357318Y391500D01*
Y394460D01*
X356192Y395586D01*
Y403300D01*
X356712Y403820D01*
Y411679D01*
X357792Y412759D01*
Y413816D01*
G01X359117Y355360D02*
X360908Y358951D01*
Y365060D01*
G02X361132Y365897I1677J0D01*
G03Y368223I-2015J1163D01*
G02Y369797I1365J787D01*
G01X361157Y369839D01*
G03X361132Y372122I-2040J1119D01*
G01X361113Y372156D01*
G02X361132Y373697I1384J754D01*
G03X361157Y375980I-2015J1164D01*
G01X361132Y376022D01*
X361113Y376056D01*
G02X361132Y377597I1384J754D01*
G03X361157Y379880I-2015J1164D01*
G01X361132Y379922D01*
X361113Y379956D01*
G02X361132Y381497I1384J754D01*
G03X361157Y383780I-2015J1164D01*
G01X361132Y383822D01*
X361113Y383856D01*
G02X361132Y385397I1384J754D01*
G03X361157Y387680I-2015J1164D01*
G01X361132Y387722D01*
X360918Y388115D01*
Y399125D01*
X362532Y400739D01*
Y401713D01*
G01X379397Y230559D02*
X380697Y227559D01*
X380781Y227413D01*
G02X380762Y225872I-1384J-754D01*
G03X380737Y223589I2015J-1164D01*
G01X380762Y223547D01*
X380781Y223513D01*
G02X380762Y221972I-1384J-754D01*
G03X380737Y219689I2015J-1164D01*
G01X380762Y219647D01*
X380781Y219613D01*
G02X380762Y218072I-1384J-754D01*
G03X380737Y215789I2015J-1164D01*
G01X380762Y215747D01*
X380781Y215713D01*
G02X380762Y214172I-1384J-754D01*
G03X380737Y211889I2015J-1164D01*
G01X380762Y211847D01*
X380781Y211813D01*
G02X380762Y210272I-1384J-754D01*
G03Y207946I2015J-1163D01*
G02X380992Y207087I-1488J-859D01*
G01Y200761D01*
X383892Y197861D01*
Y191652D01*
X384632Y190912D01*
Y190071D01*
G01X372637Y234460D02*
X371483Y235126D01*
X371173Y235042D01*
G03X371062Y234488I1464J-581D01*
G03X372593Y232886I1575J-27D01*
G01X372722D01*
G02X374652Y229398I-85J-2325D01*
G03Y227824I1365J-787D01*
G02Y225498I-2015J-1163D01*
G03Y223924I1365J-787D01*
G02Y221598I-2015J-1163D01*
G03Y220024I1365J-787D01*
G02Y217698I-2015J-1163D01*
G03Y216124I1365J-787D01*
G02Y213798I-2015J-1163D01*
G03Y212224I1365J-787D01*
G02Y209898I-2015J-1163D01*
G03Y208324I1365J-787D01*
G01Y208323D01*
G02X374647Y205991I-2015J-1162D01*
G01X374398Y205578D01*
Y204394D01*
X376692Y202100D01*
Y192797D01*
X378273Y191216D01*
Y189544D01*
X378428Y189389D01*
Y189302D01*
G01X365877Y234460D02*
X364723Y235126D01*
X364413Y235042D01*
G03X364302Y234488I1464J-581D01*
G03X365833Y232886I1575J-27D01*
G01X365962D01*
G02X367892Y229398I-85J-2325D01*
G03Y227824I1365J-787D01*
G02Y225498I-2015J-1163D01*
G03Y223924I1365J-787D01*
G02Y221598I-2015J-1163D01*
G03Y220024I1365J-787D01*
G02Y217698I-2015J-1163D01*
G03Y216124I1365J-787D01*
G02Y213798I-2015J-1163D01*
G03X367681Y212992I1365J-788D01*
G01X367680Y212983D01*
Y205771D01*
X368292Y205159D01*
Y203197D01*
X371623Y199866D01*
Y188930D01*
X371778Y188775D01*
Y188688D01*
G01X372637Y230559D02*
X372224Y230146D01*
G03X371584Y228601I1545J-1545D01*
G02X371272Y227448I-2327J11D01*
G03Y225874I1365J-787D01*
G02Y223548I-2015J-1163D01*
G03Y221974I1365J-787D01*
G02Y219648I-2015J-1163D01*
G03Y218074I1365J-787D01*
G02Y215748I-2015J-1163D01*
G03Y214174I1365J-787D01*
G02Y211848I-2015J-1163D01*
G03Y210274I1365J-787D01*
G02Y207948I-2015J-1163D01*
G01Y207949D01*
G03Y206373I1365J-788D01*
G01X371372Y206199D01*
Y203770D01*
X374298Y200844D01*
Y191892D01*
X374948Y191242D01*
Y189476D01*
X375128Y189296D01*
Y189209D01*
G01X365877Y230559D02*
X365464Y230146D01*
G03X364824Y228601I1545J-1545D01*
G02X364512Y227448I-2327J11D01*
G03Y225874I1365J-787D01*
G02Y223548I-2015J-1163D01*
G03Y221974I1365J-787D01*
G02Y219648I-2015J-1163D01*
G03Y218074I1365J-787D01*
G02Y215748I-2015J-1163D01*
G03Y214174I1365J-787D01*
G01X365029Y213281D01*
Y204939D01*
X364258Y203608D01*
Y202390D01*
X368323Y198325D01*
Y196461D01*
X368478Y196306D01*
Y196219D01*
G01X369257Y236409D02*
X369705Y235960D01*
G02X370310Y234501I-1459J-1460D01*
G03X372552Y232136I2327J-40D01*
G01X372681D01*
G02X374002Y229774I-44J-1575D01*
G03Y227448I2015J-1163D01*
G02Y225874I-1365J-787D01*
G03Y223548I2015J-1163D01*
G02Y221974I-1365J-787D01*
G03Y219648I2015J-1163D01*
G02Y218074I-1365J-787D01*
G03Y215748I2015J-1163D01*
G02Y214174I-1365J-787D01*
G03Y211848I2015J-1163D01*
G02Y210274I-1365J-787D01*
G03Y207948I2015J-1163D01*
G02Y206374I-1365J-787D01*
G01X373648Y205787D01*
Y204083D01*
X375942Y201789D01*
Y192486D01*
X377523Y190905D01*
Y189544D01*
X377368Y189389D01*
Y189302D01*
G01X362497Y236409D02*
X362945Y235960D01*
G02X363550Y234501I-1459J-1460D01*
G03X365792Y232136I2327J-40D01*
G01X365921D01*
G02X367242Y229774I-44J-1575D01*
G03Y227448I2015J-1163D01*
G02Y225874I-1365J-787D01*
G03Y223548I2015J-1163D01*
G02Y221974I-1365J-787D01*
G03Y219648I2015J-1163D01*
G02Y218074I-1365J-787D01*
G03Y215748I2015J-1163D01*
G02Y214174I-1365J-787D01*
G03X366930Y212983I2015J-1164D01*
G01Y205460D01*
X367542Y204848D01*
Y202886D01*
X370873Y199555D01*
Y188887D01*
X370718Y188732D01*
Y188688D01*
G01X369257Y228610D02*
X370411Y229276D01*
X370721Y229192D01*
G02X370832Y228604I-1465J-581D01*
G02X370622Y227824I-1576J6D01*
G03Y225498I2015J-1163D01*
G02Y223924I-1365J-787D01*
G03Y221598I2015J-1163D01*
G02Y220024I-1365J-787D01*
G03Y217698I2015J-1163D01*
G02Y216124I-1365J-787D01*
G03Y213798I2015J-1163D01*
G02Y212224I-1365J-787D01*
G03Y209898I2015J-1163D01*
G02Y208324I-1365J-787D01*
G03Y205998I2015J-1163D01*
G01Y203459D01*
X373548Y200533D01*
Y191581D01*
X374198Y190931D01*
Y189497D01*
X374068Y189367D01*
G01X362497Y228610D02*
X363651Y229276D01*
X363961Y229192D01*
G02X364072Y228604I-1465J-581D01*
G02X363862Y227824I-1576J6D01*
G03Y225498I2015J-1163D01*
G02Y223924I-1365J-787D01*
G03Y221598I2015J-1163D01*
G02Y220024I-1365J-787D01*
G03Y217698I2015J-1163D01*
G02Y216124I-1365J-787D01*
G03Y213798I2015J-1163D01*
G01X364279Y213079D01*
Y205141D01*
X363508Y203810D01*
Y202079D01*
X367573Y198014D01*
Y196461D01*
X367418Y196306D01*
Y196219D01*
G01X382777Y228610D02*
X382749Y228540D01*
X383845Y226009D01*
X384142Y225497D01*
G02X384161Y223956I-1365J-787D01*
G01X384142Y223922D01*
X384117Y223880D01*
G03X384142Y221597I2040J-1119D01*
G02X384161Y220056I-1365J-787D01*
G01X384142Y220022D01*
X384117Y219980D01*
G03X384142Y217697I2040J-1119D01*
G02X384161Y216156I-1365J-787D01*
G01X384142Y216122D01*
X384117Y216080D01*
G03X384142Y213797I2040J-1119D01*
G02X384161Y212256I-1365J-787D01*
G01X384142Y212222D01*
X384117Y212180D01*
G03X384142Y209897I2040J-1119D01*
G02X384161Y208356I-1365J-787D01*
G01X384142Y208322D01*
X383626Y207498D01*
Y205467D01*
X385992Y203101D01*
Y200601D01*
X386948Y199645D01*
Y192744D01*
X388632Y191060D01*
Y190084D01*
G01X382777Y236409D02*
X384726Y233788D01*
X384792Y233672D01*
G02Y231346I-2015J-1163D01*
G03Y229772I1365J-787D01*
G01X384817Y229730D01*
G02X384792Y227447I-2040J-1119D01*
G01X384773Y227413D01*
G03X384792Y225872I1384J-754D01*
G02X384817Y223589I-2015J-1164D01*
G01X384792Y223547D01*
X384773Y223513D01*
G03X384792Y221972I1384J-754D01*
G02X384817Y219689I-2015J-1164D01*
G01X384792Y219647D01*
X384773Y219613D01*
G03X384792Y218072I1384J-754D01*
G02X384817Y215789I-2015J-1164D01*
G01X384792Y215747D01*
X384773Y215713D01*
G03X384792Y214172I1384J-754D01*
G02X384817Y211889I-2015J-1164D01*
G01X384792Y211847D01*
X384773Y211813D01*
G03X384792Y210272I1384J-754D01*
G02Y207946I-2015J-1163D01*
G01X384468Y207377D01*
Y206529D01*
X387292Y203705D01*
Y201200D01*
X388498Y199994D01*
Y193195D01*
X390632Y191061D01*
Y190240D01*
G01X376017Y236409D02*
X377822Y234604D01*
Y230599D01*
G03X378032Y229772I1575J-40D01*
G01X378057Y229730D01*
G02X378032Y227447I-2040J-1119D01*
G01X378013Y227413D01*
G03X378032Y225872I1384J-754D01*
G02X378057Y223589I-2015J-1164D01*
G01X378032Y223547D01*
X378013Y223513D01*
G03X378032Y221972I1384J-754D01*
G02X378057Y219689I-2015J-1164D01*
G01X378032Y219647D01*
X378013Y219613D01*
G03X378032Y218072I1384J-754D01*
G02X378057Y215789I-2015J-1164D01*
G01X378032Y215747D01*
X378013Y215713D01*
G03X378032Y214172I1384J-754D01*
G02X378057Y211889I-2015J-1164D01*
G01X378032Y211847D01*
X378013Y211813D01*
G03X378032Y210272I1384J-754D01*
G02Y207946I-2015J-1163D01*
G03X378013Y206407I1365J-786D01*
G01X378032Y206373D01*
G02X378305Y205805I-3154J-1865D01*
G01X379692Y204418D01*
Y200201D01*
X382632Y197261D01*
Y190375D01*
G01X386157Y230559D02*
X387457Y227559D01*
X387541Y227413D01*
G02X387522Y225872I-1384J-754D01*
G03X387497Y223589I2015J-1164D01*
G01X387522Y223547D01*
X387541Y223513D01*
G02X387522Y221972I-1384J-754D01*
G03X387497Y219689I2015J-1164D01*
G01X387522Y219647D01*
X387541Y219613D01*
G02X387522Y218072I-1384J-754D01*
G03X387497Y215789I2015J-1164D01*
G01X387522Y215747D01*
X387541Y215713D01*
G02X387522Y214172I-1384J-754D01*
G03X387497Y211889I2015J-1164D01*
G01X387522Y211847D01*
X387541Y211813D01*
G02X387522Y210272I-1384J-754D01*
G03Y207946I2015J-1163D01*
G01X387841Y207375D01*
X388348Y205691D01*
Y201845D01*
X390048Y200145D01*
Y193644D01*
X392632Y191060D01*
Y190218D01*
G01X379397Y234460D02*
X381201Y232656D01*
Y228599D01*
G03X381412Y227823I1576J12D01*
G02Y225497I-2015J-1163D01*
G03X381393Y223956I1365J-787D01*
G01X381412Y223922D01*
X381437Y223880D01*
G02X381412Y221597I-2040J-1119D01*
G03X381393Y220056I1365J-787D01*
G01X381412Y220022D01*
X381437Y219980D01*
G02X381412Y217697I-2040J-1119D01*
G03X381393Y216156I1365J-787D01*
G01X381412Y216122D01*
X381437Y216080D01*
G02X381412Y213797I-2040J-1119D01*
G03X381393Y212256I1365J-787D01*
G01X381412Y212222D01*
X381437Y212180D01*
G02X381412Y209897I-2040J-1119D01*
G03X381393Y208356I1365J-787D01*
G01X381651Y207895D01*
G02X382092Y206200I-3034J-1694D01*
G01Y205000D01*
X384748Y202344D01*
Y200044D01*
X385492Y199300D01*
Y192186D01*
X386632Y191046D01*
Y190168D01*
G01X386157Y234460D02*
X388107Y231835D01*
X388172Y231722D01*
G02X388197Y229439I-2015J-1164D01*
G01X388172Y229397D01*
G03Y227823I1365J-787D01*
G02Y225497I-2015J-1163D01*
G03X388153Y223956I1365J-787D01*
G01X388172Y223922D01*
X388197Y223880D01*
G02X388172Y221597I-2040J-1119D01*
G03X388153Y220056I1365J-787D01*
G01X388172Y220022D01*
X388197Y219980D01*
G02X388172Y217697I-2040J-1119D01*
G03X388153Y216156I1365J-787D01*
G01X388172Y216122D01*
X388197Y216080D01*
G02X388172Y213797I-2040J-1119D01*
G03X388153Y212256I1365J-787D01*
G01X388172Y212222D01*
X388197Y212180D01*
G02X388172Y209897I-2040J-1119D01*
G03X388153Y208356I1365J-787D01*
G01X389698Y205677D01*
Y202293D01*
X391292Y200699D01*
Y194365D01*
X394632Y191025D01*
Y190266D01*
G01X380630Y190273D02*
Y197259D01*
X378490Y199399D01*
Y204347D01*
X377814Y205022D01*
X377729Y205108D01*
G03X377382Y205997I-2851J-601D01*
G01X377357Y206039D01*
G02X377382Y208322I2040J1119D01*
G01X377401Y208356D01*
G03X377382Y209897I-1384J754D01*
G02X377357Y212180I2015J1164D01*
G01X377382Y212222D01*
X377401Y212256D01*
G03X377382Y213797I-1384J754D01*
G02X377357Y216080I2015J1164D01*
G01X377382Y216122D01*
X377401Y216156D01*
G03X377382Y217697I-1384J754D01*
G02X377357Y219980I2015J1164D01*
G01X377382Y220022D01*
X377401Y220056D01*
G03X377382Y221597I-1384J754D01*
G02X377357Y223880I2015J1164D01*
G01X377382Y223922D01*
X377401Y223956D01*
G03X377382Y225497I-1384J754D01*
G01X377316Y225611D01*
X376017Y228610D01*
G01X398632Y191296D02*
Y192796D01*
X394490Y196938D01*
Y205181D01*
X391552Y210273D01*
G02Y211847I1364J787D01*
G01X391587Y211907D01*
G03X391552Y214173I-2050J1102D01*
G02Y215747I1364J787D01*
G01X391587Y215807D01*
G03X391552Y218073I-2050J1102D01*
G02Y219647I1364J787D01*
G01X391587Y219707D01*
G03X391552Y221973I-2050J1102D01*
G02Y223547I1364J787D01*
G01X391587Y223607D01*
G03X391552Y225873I-2050J1102D01*
G02Y227447I1364J787D01*
G03X391577Y229730I-2015J1164D01*
G01X391552Y229772D01*
G02Y231346I1364J787D01*
G01X391577Y231388D01*
G03X391552Y233673I-2040J1120D01*
G01X391491Y233781D01*
X389537Y236409D01*
G01X399676Y230559D02*
X401468Y228767D01*
Y196024D01*
X406632Y190860D01*
Y189743D01*
G01X399676Y234460D02*
X403192Y230944D01*
Y203700D01*
X402392Y202900D01*
Y196600D01*
X408632Y190360D01*
Y189343D01*
G01X400632Y190799D02*
Y192060D01*
X398162Y194530D01*
Y197770D01*
X395492Y200440D01*
Y205852D01*
X394281Y207948D01*
G02Y210274I2015J1163D01*
G03Y211848I-1365J787D01*
G02Y214174I2017J1163D01*
G03Y215748I-1365J787D01*
G02Y218074I2015J1163D01*
G03Y219648I-1365J787D01*
G02Y221974I2015J1163D01*
G03Y223548I-1365J787D01*
G02Y225874I2015J1163D01*
G03Y227448I-1365J787D01*
G02X394116Y227798I2015J1164D01*
G01X392916Y230559D01*
G01X407706Y224709D02*
X404648Y221651D01*
Y203945D01*
X405992Y202601D01*
Y194799D01*
X410632Y190159D01*
Y188943D01*
G01X407706Y228610D02*
X409292Y227024D01*
Y224000D01*
X408092Y222800D01*
X407392D01*
X406092Y221500D01*
Y204201D01*
X406792Y203501D01*
Y195800D01*
X412740Y189852D01*
Y188712D01*
G01X402632Y190520D02*
Y191760D01*
X399092Y195300D01*
Y198000D01*
X396598Y200494D01*
Y206542D01*
X395087Y208053D01*
X394931Y208324D01*
G02Y209898I1365J787D01*
G03Y212224I-2015J1163D01*
G02Y213798I1364J787D01*
G03Y216124I-2015J1163D01*
G02Y217698I1365J787D01*
G03Y220024I-2015J1163D01*
G02Y221598I1365J787D01*
G03Y223924I-2015J1163D01*
G02Y225498I1365J787D01*
G03Y227824I-2015J1163D01*
G02Y229398I1365J787D01*
G03X394635Y232129I-2015J1163D01*
G01X392916Y234460D01*
G01X389537Y228610D02*
X390838Y225603D01*
X390901Y225496D01*
G02Y223922I-1364J-787D01*
G01X390866Y223862D01*
G03X390901Y221596I2050J-1102D01*
G02Y220022I-1364J-787D01*
G01X390866Y219962D01*
G03X390901Y217696I2050J-1102D01*
G02Y216122I-1364J-787D01*
G01X390866Y216062D01*
G03X390901Y213796I2050J-1102D01*
G02Y212222I-1364J-787D01*
G01X390866Y212162D01*
G03X390901Y209896I2050J-1102D01*
G01X391298Y209209D01*
Y202593D01*
X392692Y201199D01*
Y197524D01*
X396632Y193584D01*
Y191585D01*
G01X404632Y190277D02*
Y191500D01*
X400392Y195740D01*
Y197800D01*
X397948Y200244D01*
Y234741D01*
X396296Y236393D01*
Y236409D01*
G01X379397Y367060D02*
X380585Y369792D01*
G02X380737Y370130I2191J-782D01*
G01X380762Y370172D01*
G03Y371746I-1365J787D01*
G02Y374072I2015J1163D01*
G03X380781Y375613I-1365J787D01*
G01X380762Y375647D01*
X380737Y375689D01*
G02X380762Y377972I2040J1119D01*
G03X380781Y379513I-1365J787D01*
G01X380762Y379547D01*
X380737Y379589D01*
G02X380762Y381872I2040J1119D01*
G03X380781Y383413I-1365J787D01*
G01X380762Y383447D01*
X380737Y383489D01*
G02X380762Y385772I2040J1119D01*
G03X380781Y387313I-1365J787D01*
G01X380762Y387347D01*
X380737Y387389D01*
G02X380762Y389672I2040J1119D01*
G03X380992Y391200I-1829J1057D01*
G01X380977Y391215D01*
Y398529D01*
X383192Y400744D01*
Y402828D01*
G01X369257Y369010D02*
X370411Y368345D01*
X370721Y368429D01*
G03X370832Y369008I-1465J581D01*
G03X370622Y369797I-1576J3D01*
G01X370597Y369839D01*
G02X370622Y372122I2040J1119D01*
G01X370641Y372156D01*
G03X370622Y373697I-1384J754D01*
G02X370597Y375980I2015J1164D01*
G01X370622Y376022D01*
X370641Y376056D01*
G03X370622Y377597I-1384J754D01*
G02X370597Y379880I2015J1164D01*
G01X370622Y379922D01*
X370641Y379956D01*
G03X370622Y381497I-1384J754D01*
G02X370597Y383780I2015J1164D01*
G01X370622Y383822D01*
X370641Y383856D01*
G03X370622Y385397I-1384J754D01*
G02X370597Y387680I2015J1164D01*
G01X370622Y387722D01*
X370641Y387756D01*
G03X370622Y389297I-1384J754D01*
G02X370686Y391730I2017J1164D01*
G01X370687D01*
X371142Y392431D01*
Y395011D01*
X371622Y395491D01*
Y401171D01*
X371412Y401381D01*
G01X362497Y369010D02*
X363651Y368345D01*
X363961Y368429D01*
G03X364072Y369004I-1465J581D01*
G03X363862Y369797I-1576J7D01*
G01X363837Y369839D01*
G02X363862Y372122I2040J1119D01*
G01X363881Y372156D01*
G03X363862Y373697I-1384J754D01*
G02X363837Y375980I2015J1164D01*
G01X363862Y376022D01*
X363881Y376056D01*
G03X363862Y377597I-1384J754D01*
G02X363837Y379880I2015J1164D01*
G01X363862Y379922D01*
X363881Y379956D01*
G03X363862Y381497I-1384J754D01*
G02X363837Y383780I2015J1164D01*
G01X363890Y383870D01*
G03X363862Y385398I-1393J739D01*
G02X363813Y387640I2015J1166D01*
G01X363901Y387792D01*
G03X363862Y389298I-1404J717D01*
G02X363808Y391531I2015J1166D01*
G01X363822Y391554D01*
X363900Y391691D01*
X364092Y392056D01*
Y394861D01*
X364896Y395665D01*
Y401097D01*
X364716Y401277D01*
G01X369257Y361209D02*
X369723Y361674D01*
G03X370311Y363095I-1421J1420D01*
G02X372567Y365485I2325J65D01*
G01X372696D01*
G03X374021Y367813I-59J1575D01*
G01X374002Y367847D01*
G02X373977Y370130I2015J1164D01*
G01X374002Y370172D01*
G03Y371746I-1365J787D01*
G02Y374072I2015J1163D01*
G03X374021Y375613I-1365J787D01*
G01X374002Y375647D01*
X373977Y375689D01*
G02X374002Y377972I2040J1119D01*
G03X374021Y379513I-1365J787D01*
G01X374002Y379547D01*
X373977Y379589D01*
G02X374002Y381872I2040J1119D01*
G03X374021Y383413I-1365J787D01*
G01X374002Y383447D01*
X373977Y383489D01*
G02X374002Y385772I2040J1119D01*
G03X374021Y387313I-1365J787D01*
G01X374002Y387347D01*
X373977Y387389D01*
G02X374002Y389672I2040J1119D01*
G01X374003Y389673D01*
G03X374020Y391216I-1366J787D01*
G01X373692Y391804D01*
Y393661D01*
X374992Y394961D01*
Y401432D01*
X374812Y401612D01*
Y401699D01*
G01X368087Y401923D02*
Y401836D01*
X368242Y401681D01*
Y395012D01*
X366920Y393690D01*
Y391670D01*
X367105Y391485D01*
X367261Y391213D01*
G02X367242Y389672I-1384J-754D01*
G03X367217Y387389I2015J-1164D01*
G01X367242Y387347D01*
X367261Y387313D01*
G02X367242Y385772I-1384J-754D01*
G03X367217Y383489I2015J-1164D01*
G01X367242Y383447D01*
X367261Y383413D01*
G02X367242Y381872I-1384J-754D01*
G03X367217Y379589I2015J-1164D01*
G01X367242Y379547D01*
X367261Y379513D01*
G02X367242Y377972I-1384J-754D01*
G03X367217Y375689I2015J-1164D01*
G01X367242Y375647D01*
X367261Y375613D01*
G02X367242Y374072I-1384J-754D01*
G03Y371746I2015J-1163D01*
G02Y370172I-1365J-787D01*
G01X367217Y370130D01*
G03X367242Y367847I2040J-1119D01*
G01X367261Y367813D01*
G02X365936Y365485I-1384J-753D01*
G01X365807D01*
G03X363551Y363101I69J-2325D01*
G02X362958Y361671I-2023J1D01*
G01X362497Y361209D01*
G01X372637Y367060D02*
X372216Y367481D01*
G02X371584Y369007I1526J1526D01*
G03X371297Y370130I-2326J4D01*
G01X371272Y370172D01*
G02Y371746I1365J787D01*
G03Y374072I-2015J1163D01*
G02X371253Y375613I1365J787D01*
G01X371272Y375647D01*
X371297Y375689D01*
G03X371272Y377972I-2040J1119D01*
G02X371253Y379513I1365J787D01*
G01X371272Y379547D01*
X371297Y379589D01*
G03X371272Y381872I-2040J1119D01*
G02X371253Y383413I1365J787D01*
G01X371272Y383447D01*
X371297Y383489D01*
G03X371272Y385772I-2040J1119D01*
G02X371253Y387313I1365J787D01*
G01X371300Y387397D01*
X371297Y387389D01*
G03X371272Y389672I-2040J1119D01*
G02X371316Y391321I1368J789D01*
G01X371892Y392209D01*
Y394700D01*
X372372Y395180D01*
Y401314D01*
X372472Y401414D01*
Y401501D01*
G01X365877Y367060D02*
X365452Y367485D01*
G02X364824Y369001I1516J1516D01*
G03X364537Y370130I-2326J10D01*
G01X364512Y370172D01*
G02Y371746I1365J787D01*
G03Y374072I-2015J1163D01*
G02X364493Y375613I1365J787D01*
G01X364512Y375647D01*
X364537Y375689D01*
G03X364512Y377972I-2040J1119D01*
G02X364493Y379513I1365J787D01*
G01X364512Y379547D01*
X364537Y379589D01*
G03X364512Y381872I-2040J1119D01*
G02X364493Y383413I1365J787D01*
G01X364554Y383520D01*
G03X364512Y385774I-2057J1089D01*
G02X364473Y387280I1365J789D01*
G01X364566Y387442D01*
G03X364512Y389675I-2069J1067D01*
G02X364473Y391181I1365J789D01*
G01X364559Y391332D01*
X364842Y391871D01*
Y394550D01*
X365646Y395354D01*
Y401180D01*
X365776Y401310D01*
Y401397D01*
G01X372637Y363160D02*
X371483Y362494D01*
X371173Y362578D01*
G02X371062Y363116I1464J583D01*
G02X372593Y364735I1575J44D01*
G01X372722D01*
G03X374652Y368223I-85J2325D01*
G02Y369797I1365J787D01*
G01X374677Y369839D01*
G03X374652Y372122I-2040J1119D01*
G01X374633Y372156D01*
G02X374652Y373697I1384J754D01*
G03X374677Y375980I-2015J1164D01*
G01X374652Y376022D01*
X374633Y376056D01*
G02X374652Y377597I1384J754D01*
G03X374677Y379880I-2015J1164D01*
G01X374652Y379922D01*
X374633Y379956D01*
G02X374652Y381497I1384J754D01*
G03X374677Y383780I-2015J1164D01*
G01X374652Y383822D01*
X374633Y383856D01*
G02X374652Y385397I1384J754D01*
G03X374677Y387680I-2015J1164D01*
G01X374652Y387722D01*
X374633Y387756D01*
G02X374652Y389297I1384J754D01*
G01X374653Y389298D01*
G03X374677Y391579I-2016J1162D01*
G01X374442Y392000D01*
Y393350D01*
X375742Y394650D01*
Y401449D01*
X375872Y401579D01*
G01X365877Y363160D02*
X364723Y362494D01*
X364413Y362578D01*
G02X365833Y364735I1464J582D01*
G01X365962D01*
G03X367892Y368223I-85J2325D01*
G02Y369797I1365J787D01*
G01X367917Y369839D01*
G03X367892Y372122I-2040J1119D01*
G01X367873Y372156D01*
G02X367892Y373697I1384J754D01*
G03X367917Y375980I-2015J1164D01*
G01X367892Y376022D01*
X367873Y376056D01*
G02X367892Y377597I1384J754D01*
G03X367917Y379880I-2015J1164D01*
G01X367892Y379922D01*
X367873Y379956D01*
G02X367892Y381497I1384J754D01*
G03X367917Y383780I-2015J1164D01*
G01X367892Y383822D01*
X367873Y383856D01*
G02X367892Y385397I1384J754D01*
G03X367917Y387680I-2015J1164D01*
G01X367892Y387722D01*
X367873Y387756D01*
G02X367892Y389297I1384J754D01*
G03Y391623I-2015J1163D01*
G01X367705Y391946D01*
X367670Y391981D01*
Y393379D01*
X368992Y394701D01*
Y401681D01*
X369147Y401836D01*
Y401923D01*
G01X382777Y369010D02*
X384077Y372010D01*
X384161Y372156D01*
G03X384142Y373697I-1384J754D01*
G02X384117Y375980I2015J1164D01*
G01X384142Y376022D01*
X384161Y376056D01*
G03X384142Y377597I-1384J754D01*
G02X384117Y379880I2015J1164D01*
G01X384142Y379922D01*
X384161Y379956D01*
G03X384142Y381497I-1384J754D01*
G02X384117Y383780I2015J1164D01*
G01X384142Y383822D01*
X384161Y383856D01*
G03X384142Y385397I-1384J754D01*
G02X384117Y387680I2015J1164D01*
G01X384142Y387722D01*
X384161Y387756D01*
G03X384142Y389297I-1384J754D01*
G02X383392Y391900I4887J2818D01*
G01X383398Y391906D01*
Y396070D01*
X387192Y399864D01*
Y405200D01*
G01X389537Y361209D02*
X391488Y363834D01*
X391587Y364007D01*
G03X391552Y366273I-2050J1102D01*
G02Y367847I1364J787D01*
G03X391577Y370130I-2015J1164D01*
G01X391552Y370172D01*
G02Y371746I1364J787D01*
G01X391577Y371788D01*
G03X391552Y374073I-2040J1120D01*
G02Y375647I1364J787D01*
G01X391587Y375707D01*
G03X391552Y377973I-2050J1102D01*
G02Y379547I1364J787D01*
G01X391587Y379607D01*
G03X391552Y381873I-2050J1102D01*
G02Y383447I1364J787D01*
G01X391587Y383507D01*
G03X391552Y385773I-2050J1102D01*
G02Y387347I1364J787D01*
G01X391587Y387407D01*
G03X391552Y389673I-2050J1102D01*
G01X391520Y389729D01*
G02X391551Y391248I1396J731D01*
G02X393086Y392422I2178J-1257D01*
G01X395192Y394528D01*
Y403301D01*
X397292Y405401D01*
Y406829D01*
G01X382777Y361209D02*
Y362685D01*
X384605Y364513D01*
Y366785D01*
G02X384773Y367813I1552J274D01*
G01X384792Y367847D01*
G03X384817Y370130I-2015J1164D01*
G01X384792Y370172D01*
G02Y371746I1365J787D01*
G03Y374072I-2015J1163D01*
G02X384773Y375613I1365J787D01*
G01X384792Y375647D01*
X384817Y375689D01*
G03X384792Y377972I-2040J1119D01*
G02X384773Y379513I1365J787D01*
G01X384792Y379547D01*
X384817Y379589D01*
G03X384792Y381872I-2040J1119D01*
G02X384773Y383413I1365J787D01*
G01X384792Y383447D01*
X384817Y383489D01*
G03X384792Y385772I-2040J1119D01*
G02X384773Y387313I1365J787D01*
G01X384792Y387347D01*
X384817Y387389D01*
G03X384792Y389672I-2040J1119D01*
G02X384492Y392100I2714J1568D01*
G01X384488Y392104D01*
Y395040D01*
X388492Y399044D01*
Y404266D01*
X389192Y404966D01*
Y405821D01*
G01X399292Y407111D02*
Y405872D01*
X396092Y402672D01*
Y391893D01*
X394841Y390642D01*
X394281Y389672D01*
G03X394256Y387389I2015J-1164D01*
G01X394281Y387347D01*
X394300Y387313D01*
G02X394281Y385772I-1384J-754D01*
G03X394256Y383489I2015J-1164D01*
G01X394281Y383447D01*
X394300Y383413D01*
G02X394281Y381872I-1384J-754D01*
G03X394256Y379589I2015J-1164D01*
G01X394281Y379547D01*
X394300Y379513D01*
G02X394281Y377972I-1384J-754D01*
G03X394256Y375689I2015J-1164D01*
G01X394281Y375647D01*
X394300Y375613D01*
G02X394281Y374072I-1384J-754D01*
G03Y371746I2015J-1163D01*
G02Y370172I-1365J-787D01*
G01X394256Y370130D01*
G03X394111Y369810I2041J-1118D01*
G01X392916Y367060D01*
G01X376017Y361209D02*
Y362725D01*
X378079Y364787D01*
Y366097D01*
G03X378032Y366272I-351J0D01*
G02X378013Y367813I1365J787D01*
G01X378032Y367847D01*
G03X378057Y370130I-2015J1164D01*
G01X378032Y370172D01*
G02Y371746I1365J787D01*
G03Y374072I-2015J1163D01*
G02X378013Y375613I1365J787D01*
G01X378032Y375647D01*
X378057Y375689D01*
G03X378032Y377972I-2040J1119D01*
G02X378013Y379513I1365J787D01*
G01X378032Y379547D01*
X378057Y379589D01*
G03X378032Y381872I-2040J1119D01*
G02X378013Y383413I1365J787D01*
G01X378032Y383447D01*
X378057Y383489D01*
G03X378032Y385772I-2040J1119D01*
G02X378013Y387313I1365J787D01*
G01X378032Y387347D01*
X378057Y387389D01*
G03X378032Y389672I-2040J1119D01*
G02X378013Y391213I1365J787D01*
G01X378032Y391247D01*
G02X378844Y392166I2517J-1405D01*
G01Y398556D01*
X381192Y400904D01*
Y405204D01*
G01X386157Y367060D02*
X387455Y370057D01*
X387522Y370172D01*
G03Y371746I-1365J787D01*
G02Y374072I2015J1163D01*
G03X387541Y375613I-1365J787D01*
G01X387522Y375647D01*
X387497Y375689D01*
G02X387522Y377972I2040J1119D01*
G03X387541Y379513I-1365J787D01*
G01X387522Y379547D01*
X387497Y379589D01*
G02X387522Y381872I2040J1119D01*
G03X387541Y383413I-1365J787D01*
G01X387522Y383447D01*
X387497Y383489D01*
G02X387522Y385772I2040J1119D01*
G03X387541Y387313I-1365J787D01*
G01X387522Y387347D01*
X387497Y387389D01*
G02X387522Y389672I2040J1119D01*
G03X387292Y391800I-1570J907D01*
G01X386678Y392414D01*
Y395086D01*
X390092Y398500D01*
Y403719D01*
X391258Y404885D01*
Y405606D01*
G01X379397Y363160D02*
X381385Y365850D01*
G03X381412Y368223I-1988J1209D01*
G02Y369797I1365J787D01*
G01X381437Y369839D01*
G03X381412Y372122I-2040J1119D01*
G01X381393Y372156D01*
G02X381412Y373697I1384J754D01*
G03X381437Y375980I-2015J1164D01*
G01X381412Y376022D01*
X381393Y376056D01*
G02X381412Y377597I1384J754D01*
G03X381437Y379880I-2015J1164D01*
G01X381412Y379922D01*
X381393Y379956D01*
G02X381412Y381497I1384J754D01*
G03X381437Y383780I-2015J1164D01*
G01X381412Y383822D01*
X381393Y383856D01*
G02X381412Y385397I1384J754D01*
G03X381437Y387680I-2015J1164D01*
G01X381412Y387722D01*
X381393Y387756D01*
G02X381412Y389297I1384J754D01*
G03X382092Y391838I-4407J2541D01*
G01Y397174D01*
X385192Y400274D01*
Y405100D01*
G01X386157Y363160D02*
Y364465D01*
X388021Y366329D01*
Y368580D01*
G02X388172Y369797I1516J430D01*
G01X388197Y369839D01*
G03X388172Y372122I-2040J1119D01*
G01X388153Y372156D01*
G02X388172Y373697I1384J754D01*
G03X388197Y375980I-2015J1164D01*
G01X388172Y376022D01*
X388153Y376056D01*
G02X388172Y377597I1384J754D01*
G03X388197Y379880I-2015J1164D01*
G01X388172Y379922D01*
X388153Y379956D01*
G02X388172Y381497I1384J754D01*
G03X388197Y383780I-2015J1164D01*
G01X388172Y383822D01*
X388153Y383856D01*
G02X388172Y385397I1384J754D01*
G03X388197Y387680I-2015J1164D01*
G01X388172Y387722D01*
X388153Y387756D01*
G02X388172Y389297I1384J754D01*
G03X388592Y392300I-3506J2021D01*
G01X388492Y392400D01*
Y394684D01*
X393392Y399584D01*
Y404200D01*
X393292Y404300D01*
Y405741D01*
G01X401292Y407111D02*
Y406128D01*
X400292Y405128D01*
Y402400D01*
X398092Y400200D01*
Y387854D01*
X397028Y386790D01*
X396159D01*
X395084Y385715D01*
G02X394931Y385397I-2167J847D01*
G03X394912Y383856I1365J-787D01*
G01X394931Y383822D01*
X394956Y383780D01*
G02X394931Y381497I-2040J-1119D01*
G03X394912Y379956I1365J-787D01*
G01X394931Y379922D01*
X394956Y379880D01*
G02X394931Y377597I-2040J-1119D01*
G03X394912Y376056I1365J-787D01*
G01X394931Y376022D01*
X394956Y375980D01*
G02X394931Y373697I-2040J-1119D01*
G03X394912Y372156I1365J-787D01*
G01X394931Y372122D01*
G02X394956Y369839I-2015J-1164D01*
G01X394931Y369797D01*
G03Y368223I1365J-787D01*
G02X394830Y365737I-2015J-1163D01*
G01X392916Y363160D01*
G01X389537Y369010D02*
X390838Y372014D01*
X390901Y372122D01*
G03Y373696I-1364J787D01*
G02X390866Y375962I2015J1164D01*
G01X390901Y376022D01*
G03Y377596I-1364J787D01*
G02X390866Y379862I2015J1164D01*
G01X390901Y379922D01*
G03Y381496I-1364J787D01*
G02X390866Y383762I2015J1164D01*
G01X390901Y383822D01*
G03Y385396I-1364J787D01*
G02X390866Y387662I2015J1164D01*
G01X390901Y387722D01*
G03Y389296I-1364J787D01*
G02X390858Y391546I2015J1164D01*
G02X392692Y393900I7524J-3970D01*
G01X394192Y395400D01*
Y404000D01*
X395292Y405100D01*
Y406265D01*
G01X376017Y369010D02*
X377317Y372010D01*
X377401Y372156D01*
G03X377382Y373697I-1384J754D01*
G02X377357Y375980I2015J1164D01*
G01X377382Y376022D01*
X377401Y376056D01*
G03X377382Y377597I-1384J754D01*
G02X377357Y379880I2015J1164D01*
G01X377382Y379922D01*
X377401Y379956D01*
G03X377382Y381497I-1384J754D01*
G02X377357Y383780I2015J1164D01*
G01X377382Y383822D01*
X377401Y383856D01*
G03X377382Y385397I-1384J754D01*
G02X377357Y387680I2015J1164D01*
G01X377382Y387722D01*
X377401Y387756D01*
G03X377382Y389297I-1384J754D01*
G02Y391623I2015J1163D01*
G03X377592Y392407I-1358J784D01*
G01Y399494D01*
X379868Y401770D01*
Y403624D01*
X379192Y404300D01*
Y405271D01*
G01X436113Y220096D02*
X435947Y219920D01*
G03X434114Y217388I11333J-10134D01*
G01X434098Y217360D01*
G03Y215034I2015J-1163D01*
G02Y213459I-1364J-788D01*
G01X433646Y212676D01*
Y209959D01*
X430869Y207182D01*
Y202811D01*
X426476Y198418D01*
Y189269D01*
X426148Y188941D01*
Y186756D01*
X424692Y185300D01*
G01X436113Y227896D02*
X434748Y224784D01*
G03X435509Y222542I1365J-787D01*
G02X437363Y221056I-1636J-3940D01*
G02X436687Y218630I-1250J-959D01*
G03X434748Y216984I1328J-3530D01*
G03Y215410I1365J-787D01*
G02Y213084I-2017J-1163D01*
G01X434746Y213085D01*
X434396Y212478D01*
Y209648D01*
X431619Y206871D01*
Y202500D01*
X427226Y198107D01*
Y185633D01*
X426592Y184999D01*
G01X446253Y222047D02*
Y223378D01*
X446481Y223606D01*
G02X447618Y221259I-228J-1559D01*
G03X447593Y218976I2015J-1164D01*
G03X447637Y218900I1668J915D01*
G02X447618Y217359I-1384J-754D01*
G01X447308Y216822D01*
Y208361D01*
X447828Y207841D01*
Y205751D01*
X443957Y201880D01*
Y197356D01*
X439018Y192417D01*
Y187674D01*
X440092Y186600D01*
G01X446253Y225947D02*
Y224616D01*
X446510Y224359D01*
G02X448268Y223209I-257J-2312D01*
G01X448293Y223167D01*
G02X448268Y220884I-2040J-1119D01*
G03X448249Y219343I1365J-787D01*
G01X448268Y219309D01*
X448293Y219267D01*
G02X448268Y216984I-2040J-1119D01*
G01X448058Y216609D01*
Y208673D01*
X448578Y208153D01*
Y205437D01*
X444707Y201566D01*
Y197045D01*
X439768Y192106D01*
Y189321D01*
X441992Y187097D01*
G01X432733Y222047D02*
X430782Y219422D01*
X430718Y219309D01*
G03X430601Y219081I1790J-1062D01*
G03X430718Y216983I2132J-933D01*
G02Y215409I-1364J-787D01*
G01X430676Y215336D01*
G03X430718Y213082I2057J-1089D01*
G01X430968Y212652D01*
Y211311D01*
X428019Y208362D01*
Y203992D01*
X423526Y199499D01*
Y189469D01*
X419592Y185535D01*
G01X432733Y225947D02*
X434030Y222951D01*
X434117Y222800D01*
G02X434098Y221259I-1384J-754D01*
G01X433986Y221064D01*
G02X432340Y219672I-2267J1011D01*
G03X431497Y219122I394J-1525D01*
G03X431270Y218728I1244J-979D01*
G03X431369Y217360I1463J-582D01*
G02X431404Y215094I-2015J-1164D01*
G01X431369Y215034D01*
X431350Y215000D01*
G03X431369Y213459I1383J-754D01*
G01X431718Y212858D01*
Y211000D01*
X428769Y208051D01*
Y203681D01*
X424276Y199188D01*
Y187284D01*
X421692Y184700D01*
G01X442873Y220096D02*
X444088Y217296D01*
G03X444238Y216984I2166J849D01*
G02X444449Y216196I-1365J-788D01*
G01Y208614D01*
X439418Y203583D01*
Y196848D01*
X435760Y193190D01*
Y186432D01*
X436292Y185900D01*
G01X445199Y216241D02*
Y208298D01*
X440168Y203267D01*
Y196537D01*
X436510Y192879D01*
Y187882D01*
X438192Y186200D01*
G01X456393Y220096D02*
X454444Y217475D01*
X454378Y217359D01*
G03X454353Y215076I2015J-1164D01*
G01X454378Y215034D01*
X454397Y215000D01*
G02X454378Y213459I-1384J-754D01*
G03X454066Y212296I2015J-1164D01*
G01Y211263D01*
X454272Y211057D01*
Y203994D01*
X453394Y203116D01*
Y200479D01*
X452805Y199890D01*
Y196592D01*
X453098Y196299D01*
Y189716D01*
X452318Y188936D01*
G01X457592Y221172D02*
X457758Y220884D01*
G02X457777Y219343I-1365J-787D01*
G01X457514Y218887D01*
X455563Y217536D01*
G03X455009Y215443I830J-1340D01*
G01X455028Y215409D01*
X455053Y215367D01*
G02X455028Y213084I-2040J-1119D01*
G03X454817Y212296I1365J-788D01*
G01Y211575D01*
X455022Y211370D01*
Y203683D01*
X454144Y202805D01*
Y200167D01*
X453555Y199578D01*
Y196904D01*
X453848Y196611D01*
Y189956D01*
X454868Y188936D01*
G01X453013Y222047D02*
X452928Y222034D01*
X451311Y219860D01*
X450998Y219309D01*
X450973Y219267D01*
G03X450998Y216984I2040J-1119D01*
G02X451017Y215443I-1365J-787D01*
G01X450998Y215409D01*
X450973Y215367D01*
G03X450998Y213084I2040J-1119D01*
G01X451252Y212644D01*
Y205005D01*
X450546Y204299D01*
Y201659D01*
X449776Y200889D01*
Y197213D01*
X448156Y195593D01*
Y194374D01*
X447218Y193436D01*
G01X453013Y225947D02*
X454310Y222951D01*
X454397Y222800D01*
G02X453656Y220608I-1384J-753D01*
G01X452840Y220278D01*
X452225Y219724D01*
X451810Y219215D01*
X451629Y218900D01*
G03X451648Y217359I1384J-754D01*
G02X451673Y215076I-2015J-1164D01*
G01X451648Y215034D01*
X451629Y215000D01*
G03X451648Y213459I1384J-754D01*
G01X452002Y212901D01*
Y204694D01*
X451296Y203988D01*
Y201347D01*
X450526Y200577D01*
Y196901D01*
X448906Y195281D01*
Y194298D01*
X449768Y193436D01*
G01X439493Y218147D02*
X438880Y216874D01*
X438435Y215549D01*
X438116Y215015D01*
X438108Y215001D01*
X438109Y215000D01*
G03X438128Y213460I1384J-753D01*
G02Y211134I-2017J-1163D01*
G01X437381Y209839D01*
Y208573D01*
X434469Y205661D01*
Y201319D01*
X430302Y197152D01*
Y185442D01*
X430457Y185287D01*
G01X459773Y218147D02*
X459160Y216874D01*
X458715Y215549D01*
X458396Y215015D01*
X458388Y215001D01*
G03X458408Y213460I1385J-753D01*
G01X458738Y212886D01*
Y203718D01*
X456994Y201974D01*
Y199698D01*
X458347Y198345D01*
Y189968D01*
X458502Y189813D01*
Y189726D01*
G01X439493Y229847D02*
G02X437785Y227526I-11194J6449D01*
G03X439408Y223622I1708J-1579D01*
G01X439537D01*
G02X440858Y221260I-44J-1575D01*
G03Y218934I2015J-1163D01*
G02Y217360I-1365J-787D01*
G01X440857Y217358D01*
G03X440546Y216197I2013J-1161D01*
G03X440858Y215035I2326J2D01*
G01X441098Y214620D01*
Y209291D01*
X436569Y204762D01*
Y198029D01*
X432710Y194170D01*
Y185442D01*
X432643Y185375D01*
X432599D01*
X432555Y185331D01*
Y185287D01*
G01X459773Y229847D02*
Y228516D01*
X459516Y228259D01*
G03X457758Y227109I257J-2312D01*
G01X457733Y227067D01*
G03X457758Y224784I2040J-1119D01*
G03X459688Y223622I2015J1163D01*
G01X459817D01*
G02X461138Y221260I-44J-1575D01*
G03Y218934I2015J-1163D01*
G02Y217360I-1365J-787D01*
G03Y215034I2015J-1163D01*
G01X461653Y214147D01*
Y213497D01*
X461187Y213031D01*
Y202460D01*
X460542Y201815D01*
Y200211D01*
X459642Y199311D01*
Y197389D01*
X462528Y194503D01*
Y190855D01*
X462373Y190700D01*
Y190613D01*
G01X439493Y222047D02*
X439486Y222032D01*
G02X438128Y218934I-14719J4605D01*
G03X437967Y217755I1365J-787D01*
G02X437478Y215410I-3808J-429D01*
G01X437472Y215400D01*
X437463Y215384D01*
X437459Y215378D01*
X437453Y215367D01*
G03X437478Y213084I2040J-1119D01*
G02Y211509I-1364J-787D01*
G01X436631Y210040D01*
Y208884D01*
X433719Y205972D01*
Y201630D01*
X429552Y197463D01*
Y185442D01*
X429485Y185375D01*
X429441D01*
X429397Y185331D01*
Y185287D01*
G01X459773Y222047D02*
X459766Y222032D01*
G02X458408Y218934I-14719J4605D01*
G03X458247Y217755I1365J-787D01*
G02X457758Y215410I-3808J-429D01*
G01X457753Y215401D01*
X457729Y215360D01*
G03X457757Y213087I2044J-1111D01*
G01X457988Y212685D01*
Y204029D01*
X456244Y202285D01*
Y199387D01*
X457597Y198034D01*
Y189968D01*
X457442Y189813D01*
Y189726D01*
G01X439493Y225947D02*
X440292Y226746D01*
Y227096D01*
G03X439957Y227432I-535J-199D01*
G03X439265Y227506I-490J-1308D01*
G03X438336Y227017I228J-1559D01*
G03X439449Y224372I1157J-1070D01*
G01X439578D01*
G02X441508Y220884I-85J-2325D01*
G03Y219310I1365J-787D01*
G02Y216984I-2015J-1163D01*
G03X441297Y216197I1365J-788D01*
G03X441508Y215411I1575J2D01*
G01X441848Y214822D01*
Y208980D01*
X437319Y204451D01*
Y197718D01*
X433460Y193859D01*
Y185442D01*
X433615Y185287D01*
G01X445199Y216241D02*
G03X444888Y217360I-2326J-44D01*
G02Y218934I1365J787D01*
G03Y221260I-2015J1163D01*
G02X444425Y223727I3278J1892D01*
G03X444238Y224784I-1552J270D01*
G02X444106Y226050I1355J781D01*
G01X444579Y226523D01*
Y227648D01*
X444331Y227896D01*
X442873D01*
G01X466533Y222047D02*
X467720Y219317D01*
G03X467873Y218976I2193J779D01*
G01X467898Y218934D01*
X467917Y218900D01*
G02X467898Y217359I-1384J-754D01*
G01X467544Y216745D01*
Y211075D01*
X468198Y210421D01*
Y203367D01*
X469855Y201710D01*
Y197484D01*
X471858Y195481D01*
Y194346D01*
X471108Y193596D01*
G01X466533Y225947D02*
X468235Y223633D01*
G02X468548Y220884I-1702J-1586D01*
G03X468529Y219343I1365J-787D01*
G01X468548Y219309D01*
X468573Y219267D01*
G02X468548Y216984I-2040J-1119D01*
G01X468294Y216544D01*
Y211386D01*
X468948Y210732D01*
Y203679D01*
X470605Y202022D01*
Y197796D01*
X472608Y195793D01*
Y194646D01*
X473658Y193596D01*
G01X463153Y220096D02*
X464391Y217238D01*
G03X464518Y216984I2141J912D01*
G02X464729Y216196I-1365J-788D01*
G01Y211038D01*
X464207Y210516D01*
Y203056D01*
X466835Y200428D01*
Y191423D01*
X466008Y190596D01*
G01X463153Y227896D02*
X464518Y224784D01*
G02X464705Y223727I-1365J-787D01*
G03X465168Y221260I3741J-575D01*
G02Y218934I-2015J-1163D01*
G03Y217360I1365J-787D01*
G02X465242Y217219I-1738J-1002D01*
G02X465480Y216196I-2097J-1027D01*
G01Y210635D01*
X464958Y210113D01*
Y203397D01*
X467585Y200770D01*
Y191569D01*
X468558Y190596D01*
G01X476672Y220096D02*
X476611Y220087D01*
X474900Y217786D01*
X474657Y217359D01*
G03X474632Y215076I2015J-1164D01*
G01X474657Y215034D01*
X474676Y215000D01*
G02X474657Y213459I-1384J-754D01*
G01X474292Y212752D01*
Y211313D01*
X477715Y207890D01*
Y205174D01*
X483392Y199497D01*
Y197701D01*
G01X476672Y227896D02*
X477971Y224897D01*
X478037Y224784D01*
G02X478056Y223243I-1365J-787D01*
G01X478037Y223209D01*
X478012Y223167D01*
G03X478037Y220884I2040J-1119D01*
G02X477245Y218628I-1365J-788D01*
G01X476758Y218423D01*
X476036Y217889D01*
X475491Y217303D01*
X475307Y216984D01*
G03X475288Y215443I1365J-787D01*
G01X475307Y215409D01*
X475332Y215367D01*
G02X475307Y213084I-2040J-1119D01*
G01X475042Y212570D01*
Y211625D01*
X478465Y208202D01*
Y205489D01*
X484992Y198962D01*
G01X473292Y222047D02*
X471884D01*
X471673Y221836D01*
Y220171D01*
G02X471590Y219860I-636J3D01*
G01X471277Y219309D01*
X471252Y219267D01*
G03X471277Y216984I2040J-1119D01*
G02X471296Y215443I-1365J-787D01*
G01X471277Y215409D01*
X471252Y215367D01*
G03X471277Y213084I2040J-1119D01*
G01X471492Y212712D01*
Y210156D01*
X474861Y206787D01*
Y203668D01*
X478595Y199934D01*
Y196500D01*
X479692Y195403D01*
Y194501D01*
G01X473292Y225947D02*
X474589Y222951D01*
X474676Y222800D01*
G02X473935Y220608I-1384J-753D01*
G01X473119Y220278D01*
X472504Y219724D01*
X472089Y219215D01*
X471908Y218900D01*
G03X471927Y217359I1384J-754D01*
G02X471952Y215076I-2015J-1164D01*
G01X471927Y215034D01*
X471908Y215000D01*
G03X471927Y213459I1384J-754D01*
G01X472242Y212963D01*
Y210467D01*
X475611Y207098D01*
Y203981D01*
X479392Y200200D01*
Y197301D01*
X480392Y196301D01*
X481192D01*
G01X480052Y222047D02*
X479198Y220522D01*
G02X478712Y218976I-4113J444D01*
G01X478687Y218934D01*
X477948Y217541D01*
X478037Y216984D01*
G02X478132Y216790I-1364J-788D01*
G02X478056Y215443I-1459J-593D01*
G02X478012Y215367I-1486J809D01*
G03X480001Y211921I2040J-1120D01*
G01X480096D01*
G02X481417Y209559I-44J-1575D01*
G03Y207233I2015J-1163D01*
G01X482017Y206195D01*
X487396Y200816D01*
Y200604D01*
X487458Y200542D01*
G01X459773Y225947D02*
Y227278D01*
X459545Y227506D01*
G03X458408Y226734I228J-1559D01*
G01X458389Y226700D01*
G03X458408Y225159I1384J-754D01*
G03X459714Y224372I1365J788D01*
G01X459858D01*
G02X461788Y220884I-85J-2325D01*
G03Y219310I1365J-787D01*
G02Y216985I-2016J-1162D01*
G03Y215409I1365J-788D01*
G01X462403Y214349D01*
Y213186D01*
X461937Y212720D01*
Y202149D01*
X461292Y201504D01*
Y199900D01*
X460392Y199000D01*
Y197700D01*
X463278Y194814D01*
Y190855D01*
X463433Y190700D01*
Y190613D01*
G01X457592Y221172D02*
X456868Y221774D01*
X455463Y222724D01*
G02X455028Y224784I930J1272D01*
G01X455094Y224897D01*
X456393Y227896D01*
G01X514972Y274696D02*
X510431D01*
X508862Y276265D01*
X507434D01*
X505399Y278300D01*
X503700D01*
X502427Y277027D01*
X500173D01*
X498800Y278400D01*
X497499D01*
X496126Y277027D01*
X494042D01*
X492841Y278228D01*
X490351D01*
X490336Y278243D01*
X489798D01*
X488582Y277027D01*
X487282D01*
X486094Y278215D01*
X483010D01*
X481822Y277027D01*
X479653D01*
X477702Y278978D01*
X477142D01*
X472000Y284120D01*
Y286528D01*
X470563Y287965D01*
X470025D01*
X468344Y289646D01*
Y290174D01*
X466066Y292452D01*
G01X460239Y267274D02*
X465624D01*
X465626Y267272D01*
X466603D01*
G02X468548Y266109I-70J-2325D01*
G03X471264Y266086I1365J787D01*
G01X471277Y266109D01*
G02X475307I2015J-1162D01*
G03X476628Y265321I1365J787D01*
G01X476757D01*
G02X478687Y264159I-85J-2325D01*
G03X479993Y263372I1365J788D01*
G01X480122D01*
G02X482067Y262209I-70J-2325D01*
G03X483388Y261421I1365J787D01*
G01X483517D01*
G02X485447Y260259I-85J-2325D01*
G03X486809Y259473I1362J787D01*
G01X490772D01*
X492743Y257502D01*
G01X508212Y274696D02*
X504516D01*
X502216Y272396D01*
X500797D01*
X499554Y271153D01*
X496590D01*
X495353Y272390D01*
X494010D01*
X492084Y274316D01*
X490417D01*
X489228Y273127D01*
X487073D01*
X485884Y274316D01*
X483516D01*
X482200Y273000D01*
X481100D01*
X479278Y271178D01*
X475822D01*
X475000Y272000D01*
X472300D01*
X471050Y273250D01*
X463150D01*
X462984Y273416D01*
X461062D01*
X460847Y273201D01*
X448090D01*
X448089Y273200D01*
X448003D01*
X442651Y267848D01*
Y264951D01*
X441399Y263699D01*
X439764D01*
G01X449288Y266435D02*
X450800Y267947D01*
Y270900D01*
X451550Y271650D01*
X454050D01*
X454985Y270715D01*
X459385D01*
X460572Y269528D01*
X463067D01*
X463955Y270416D01*
X467585D01*
X468774Y269227D01*
X471417D01*
X472606Y270416D01*
X474123D01*
X475689Y268850D01*
X477250D01*
X478847Y267253D01*
X485322D01*
X486559Y268490D01*
X489409D01*
X490646Y267253D01*
X492254D01*
X493491Y268490D01*
X495957D01*
X497194Y267253D01*
X499554D01*
X500766Y268465D01*
X502138D01*
X502303Y268300D01*
X504285D01*
X504832Y268847D01*
G01X491312Y272747D02*
X490930Y272365D01*
X486389D01*
X485202Y271178D01*
X483773D01*
X481822Y269227D01*
X478274D01*
X477901Y269600D01*
X476000D01*
X474350Y271250D01*
X471989D01*
X470739Y272500D01*
X462839D01*
X462673Y272666D01*
X461373D01*
X461158Y272451D01*
X448401D01*
X444408Y268458D01*
Y267305D01*
G01X504832Y276647D02*
X504450Y276265D01*
X500040D01*
X498852Y275077D01*
X496530D01*
X495342Y276265D01*
X493150D01*
X491962Y275077D01*
X490623D01*
X489435Y276265D01*
X486390D01*
X485202Y275077D01*
X483140D01*
X481952Y276265D01*
X480214D01*
X478299Y274350D01*
X476950D01*
X475700Y273100D01*
X473051D01*
X469501Y276650D01*
X467849D01*
X465856Y274657D01*
X455467D01*
X454809Y273999D01*
X447828D01*
X447779Y273950D01*
X447692D01*
X441901Y268159D01*
Y268158D01*
X440500Y266757D01*
Y266500D01*
G01X488382Y257798D02*
X487461Y258719D01*
X486814D01*
G02X484797Y259884I0J2328D01*
G03X483491Y260671I-1365J-788D01*
G01X483362D01*
G02X481417Y261834I70J2325D01*
G03X480096Y262622I-1365J-787D01*
G01X479967D01*
G02X478037Y263784I85J2325D01*
G03X476731Y264571I-1365J-788D01*
G01X476602D01*
G02X474657Y265734I70J2325D01*
G03X471941Y265757I-1365J-787D01*
G01X471928Y265734D01*
G02X467898I-2015J1162D01*
G03X466577Y266522I-1365J-787D01*
G01X464976D01*
G01X473292Y261047D02*
X472139Y260382D01*
X472056Y260072D01*
G03X473292Y259472I1237J975D01*
G01X473362D01*
G02X475307Y258309I-70J-2325D01*
G03X476625Y257521I1365J787D01*
G03X476719I47J1575D01*
G03X478037Y258309I-47J1575D01*
G02X479982Y259472I2015J-1162D01*
G01X480122D01*
G02X482067Y258309I-70J-2325D01*
G03X483388Y257521I1365J787D01*
G01X483517D01*
G02X485447Y256359I-85J-2325D01*
G03X486753Y255572I1365J788D01*
G01X488389D01*
X490549Y253412D01*
Y251512D01*
X492340Y249721D01*
X494777D01*
G02X496707Y248559I-85J-2325D01*
G03X498013Y247772I1365J788D01*
G01X498142D01*
G02X500087Y246609I-70J-2325D01*
G03X501408Y245821I1365J787D01*
G01X501537D01*
G02X503467Y244659I-85J-2325D01*
G03X504773Y243872I1365J788D01*
G01X504902D01*
G02X506847Y242709I-70J-2325D01*
G03X508168Y241921I1365J787D01*
G01X508297D01*
G02X510227Y240759I-85J-2325D01*
G03X511533Y239972I1365J788D01*
G01X511662D01*
G02X513607Y238809I-70J-2325D01*
G03X514928Y238021I1365J787D01*
G01X515057D01*
G02X516987Y234533I-85J-2325D01*
G03Y232959I1365J-787D01*
G01X517012Y232917D01*
G02X516987Y230634I-2040J-1119D01*
G01X516968Y230600D01*
G03X516987Y229059I1384J-754D01*
G02X517012Y226776I-2015J-1164D01*
G01X516987Y226734D01*
X516968Y226700D01*
G03X516987Y225159I1384J-754D01*
G02X517012Y222876I-2015J-1164D01*
G01X516987Y222834D01*
X516968Y222800D01*
G03X518293Y220472I1384J-753D01*
G01X518422D01*
G02X520367Y219309I-70J-2325D01*
G01X520380Y219286D01*
G03X521731Y218521I1351J810D01*
G01X521816D01*
G02X523746Y217359I-85J-2325D01*
G03X525067Y216571I1365J787D01*
G01X525196D01*
G02X527126Y215409I-85J-2325D01*
G03X528432Y214622I1365J788D01*
G01X528561D01*
G02X530506Y213459I-70J-2325D01*
G03X531827Y212671I1365J787D01*
G01X531956D01*
G02X533886Y211509I-85J-2325D01*
G03X535192Y210722I1365J788D01*
G01X535302D01*
G02X537266Y209559I-51J-2326D01*
G03X538560Y208772I1365J787D01*
G01X538582Y208771D01*
X538718D01*
G02X540646Y207609I-87J-2324D01*
G01X541272Y206524D01*
X541770Y206026D01*
Y206027D01*
X542268Y205529D01*
X542660D01*
X543155Y205034D01*
Y204642D01*
X543453Y204344D01*
Y204346D01*
X543806Y203993D01*
X549043D01*
X549243Y204193D01*
X549330D01*
G01Y203043D02*
X549243D01*
X549043Y203243D01*
X543493D01*
X540671Y206063D01*
X539996Y207234D01*
G03X538702Y208021I-1365J-787D01*
G01X538546D01*
G02X536616Y209183I85J2325D01*
G03X535295Y209971I-1365J-787D01*
G01X535200D01*
G02X533236Y211134I51J2326D01*
G03X531930Y211921I-1365J-788D01*
G01X531801D01*
G02X529856Y213084I70J2325D01*
G03X528535Y213872I-1365J-787D01*
G01X528406D01*
G02X526476Y215034I85J2325D01*
G03X525170Y215821I-1365J-788D01*
G01X525041D01*
G02X523096Y216984I70J2325D01*
G03X521790Y217771I-1365J-788D01*
G01X521661D01*
G02X519716Y218934I70J2325D01*
G01X519703Y218957D01*
G03X518352Y219722I-1351J-810D01*
G01X518267D01*
G02X516312Y223167I85J2325D01*
G01X516337Y223209D01*
X516356Y223243D01*
G03X516337Y224784I-1384J754D01*
G02X516312Y227067I2015J1164D01*
G01X516337Y227109D01*
X516356Y227143D01*
G03X516337Y228684I-1384J754D01*
G02Y231010I2015J1163D01*
G03Y232584I-1365J787D01*
G01X516312Y232626D01*
G02X516337Y234909I2040J1119D01*
G01X516356Y234943D01*
G03X515031Y237271I-1384J753D01*
G01X514902D01*
G02X512957Y238434I70J2325D01*
G03X511636Y239222I-1365J-787D01*
G01X511507D01*
G02X509577Y240384I85J2325D01*
G03X508271Y241171I-1365J-788D01*
G01X508142D01*
G02X506197Y242334I70J2325D01*
G03X504876Y243122I-1365J-787D01*
G01X504747D01*
G02X502817Y244284I85J2325D01*
G03X501511Y245071I-1365J-788D01*
G01X501382D01*
G02X499437Y246234I70J2325D01*
G03X498116Y247022I-1365J-787D01*
G01X497987D01*
G02X496057Y248184I85J2325D01*
G03X494751Y248971I-1365J-788D01*
G01X492029D01*
X489800Y251200D01*
Y253100D01*
X488078Y254822D01*
X486727D01*
G02X484797Y255984I85J2325D01*
G03X483491Y256771I-1365J-788D01*
G01X483362D01*
G02X481417Y257934I70J2325D01*
G03X480099Y258722I-1365J-787D01*
G03X480005I-47J-1575D01*
G03X478687Y257934I47J-1575D01*
G02X476742Y256771I-2015J1162D01*
G01X476602D01*
G02X474657Y257934I70J2325D01*
G03X473336Y258722I-1365J-787D01*
G01X473194D01*
G02X471418Y259666I97J2325D01*
G01X471066Y259761D01*
X469913Y259096D01*
G01X498072Y280547D02*
X497690Y280165D01*
X494042D01*
X492855Y278978D01*
X490662D01*
X489475Y280165D01*
X486389D01*
X485202Y278978D01*
X483902D01*
X481953Y280927D01*
X480522D01*
X479333Y282116D01*
X476843D01*
X473500Y285459D01*
Y288928D01*
X469801Y292627D01*
X469073D01*
X467200Y294500D01*
X464000D01*
G01X466100Y300021D02*
X468100Y298021D01*
Y297690D01*
X469263Y296527D01*
X469801D01*
X472700Y293628D01*
Y291840D01*
X474800Y289740D01*
Y285220D01*
X477142Y282878D01*
X479335D01*
X480522Y284065D01*
X481822D01*
X483771Y282116D01*
X485202D01*
X486391Y280927D01*
X488582D01*
X489771Y282116D01*
X491962D01*
X493151Y280927D01*
X496233D01*
X497422Y282116D01*
X498722D01*
X501452Y279386D01*
Y278596D01*
G01X443993Y381947D02*
X442044Y384568D01*
X441978Y384684D01*
G02X441953Y386967I2015J1164D01*
G01X441978Y387009D01*
X441997Y387043D01*
G03X441978Y388584I-1384J754D01*
G02X441953Y390867I2015J1164D01*
G01X441978Y390909D01*
G03X440684Y393270I-1365J787D01*
G01X440543D01*
G02X439263Y393701I70J2325D01*
G02X438129Y394896I2503J3511D01*
G01X438116Y394916D01*
X435167Y400019D01*
Y405482D01*
X427382Y413267D01*
Y416403D01*
X426498Y417287D01*
G01X443993Y389747D02*
X442694Y392745D01*
X442628Y392858D01*
G03X440683Y394021I-2015J-1162D01*
G01X440554D01*
G02X439466Y394516I59J1574D01*
G02X438267Y396160I5957J5604D01*
G01X435915Y400229D01*
Y405792D01*
X428130Y413577D01*
Y416369D01*
X429048Y417287D01*
G01X454133Y383896D02*
X452836Y386892D01*
X452749Y387043D01*
G02X452768Y388584I1384J754D01*
G01X453416Y389707D01*
G02X454133Y390121I717J-414D01*
G01X454177D01*
G03X455708Y391740I-44J1575D01*
G01Y393718D01*
X455381Y394045D01*
Y401473D01*
X452018Y404836D01*
Y409289D01*
X448948Y412359D01*
Y416285D01*
X448092Y417141D01*
G01X454133Y387796D02*
X456082Y390418D01*
X456147Y390533D01*
X456150D01*
X456178Y390584D01*
G03X456460Y391750I-2045J1112D01*
G01X456456Y391754D01*
Y394028D01*
X456129Y394355D01*
Y401783D01*
X452766Y405146D01*
Y409599D01*
X449696Y412669D01*
Y416171D01*
X450666Y417141D01*
G01X440613Y383896D02*
Y385227D01*
X440356Y385484D01*
G02X438598Y388959I257J2312D01*
G03X437277Y391322I-1365J788D01*
G01X437135D01*
G02X435218Y392483I98J2325D01*
G01X435216Y392485D01*
X431747Y398486D01*
Y400330D01*
X422268Y409809D01*
Y415968D01*
X421049Y417187D01*
G01X440613Y387796D02*
Y386465D01*
X440385Y386237D01*
G02X439248Y388584I228J1559D01*
G03X437303Y392072I-2015J1163D01*
G01X437233D01*
G02X435882Y392837I0J1575D01*
G01X432497Y398693D01*
Y400638D01*
X423016Y410119D01*
Y416255D01*
X423948Y417187D01*
G01X450753Y381947D02*
X449454Y384946D01*
X449388Y385059D01*
G02X449369Y386600I1365J787D01*
G01X449388Y386634D01*
X449413Y386676D01*
G03X449388Y388959I-2040J1119D01*
G02X449369Y390500I1365J787D01*
G01X450036Y391658D01*
G02X450753Y392072I717J-414D01*
G01X450812D01*
G03X452118Y392859I-59J1575D01*
G01X452328Y393222D01*
Y399657D01*
X449000Y402985D01*
Y408185D01*
X443696Y413489D01*
Y416269D01*
X442498Y417467D01*
G01X450753Y389747D02*
X452702Y392368D01*
X453076Y393020D01*
Y399967D01*
X449748Y403295D01*
Y408495D01*
X444444Y413799D01*
Y416423D01*
X445428Y417407D01*
G01X462717Y386097D02*
G03X462783Y385338I1556J-247D01*
G01Y384076D01*
X462498Y383791D01*
Y382301D01*
X462852Y381947D01*
X464273D01*
G01X462717Y386097D02*
G03X462258Y388586I-3743J597D01*
G02Y390912I2015J1163D01*
G03Y392484I-1362J786D01*
G02X462157Y394614I2015J1163D01*
G02X462258Y394808I1938J-886D01*
G03Y396382I-1365J787D01*
G01X462233Y396424D01*
G02X462258Y398707I2040J1119D01*
G03X462277Y400248I-1365J787D01*
G01X462258Y400282D01*
G02Y402608I2015J1163D01*
G01X462277Y402642D01*
G03X462258Y404183I-1384J754D01*
G02X461946Y405347I2015J1164D01*
G01Y411578D01*
X459936Y413588D01*
Y414682D01*
X459168Y415450D01*
G01X464273Y389747D02*
X463120Y392368D01*
G03X462908Y392859I-2227J-670D01*
G02X462824Y394265I1377J788D01*
G02X462908Y394432I1308J-553D01*
G03X462933Y396715I-2015J1164D01*
G01X462908Y396757D01*
X462889Y396791D01*
G02X462908Y398332I1384J754D01*
G03Y400658I-2015J1163D01*
G02Y402232I1365J787D01*
G01X462933Y402274D01*
G03X462908Y404559I-2040J1120D01*
G02X462697Y405346I1365J788D01*
G01Y411890D01*
X460687Y413900D01*
Y414454D01*
X461718Y415485D01*
G01X474413Y383896D02*
X473116Y386892D01*
X473029Y387043D01*
G02X473930Y389296I1384J753D01*
G01X474029Y389340D01*
G03X475610Y390648I-1546J3478D01*
G03X475777Y390910I-3270J2269D01*
G03Y392483I-1363J787D01*
G02X475742Y394749I2015J1164D01*
G01X475777Y394809D01*
G03Y396383I-1364J787D01*
G02X475742Y398649I2015J1164D01*
G01X475777Y398709D01*
G03Y400283I-1364J787D01*
G02X475742Y402549I2015J1164D01*
G01X475777Y402609D01*
G03Y404183I-1364J787D01*
G02X475742Y406449I2015J1164D01*
G01X475777Y406509D01*
G03Y408083I-1364J787D01*
G02X475742Y410349I2015J1164D01*
G01X476141Y411218D01*
Y417374D01*
X477514Y418747D01*
Y420136D01*
G01X474413Y387796D02*
G03X476295Y390309I-11321J10439D01*
G01X476298Y390314D01*
G03X476463Y390595I-3642J2328D01*
G03X476428Y392860I-2049J1101D01*
G02Y394434I1364J787D01*
G01X476463Y394494D01*
G03X476428Y396760I-2050J1102D01*
G02Y398334I1364J787D01*
G01X476463Y398394D01*
G03X476428Y400660I-2050J1102D01*
G02Y402234I1364J787D01*
G01X476463Y402294D01*
G03X476428Y404560I-2050J1102D01*
G02Y406134I1364J787D01*
G01X476463Y406194D01*
G03X476428Y408460I-2050J1102D01*
G02Y410034I1364J787D01*
G01X476891Y411047D01*
Y417064D01*
X478104Y418277D01*
X479092D01*
G01X460893Y383896D02*
X459438D01*
X459088Y384246D01*
Y386426D01*
X458878Y386636D01*
G02X458761Y386866I1906J1114D01*
G02X458878Y388962I2132J932D01*
G03Y390536I-1365J787D01*
G02X458677Y392408I2015J1163D01*
G02X458878Y392859I2266J-740D01*
G03X458905Y394385I-1365J787D01*
G01X458843Y394493D01*
G02X458878Y396759I2050J1102D01*
G03X458905Y398285I-1365J787D01*
G01X458843Y398393D01*
G02X458878Y400659I2050J1102D01*
G03X458905Y402185I-1365J787D01*
G01X458843Y402293D01*
G02X458565Y403395I2049J1103D01*
G01Y407012D01*
X454966Y410611D01*
Y413838D01*
X454068Y414736D01*
G01X460893Y387796D02*
G03X459528Y390912I-14773J-4615D01*
G02X459392Y392178I1365J787D01*
G02X459528Y392484I1462J-467D01*
G03X459553Y394767I-2015J1164D01*
G01X459528Y394809D01*
X459501Y394857D01*
G02X459528Y396383I1392J739D01*
G03X459563Y398649I-2015J1164D01*
G01X459501Y398757D01*
G02X459528Y400283I1392J739D01*
G03X459563Y402549I-2015J1164D01*
G01X459501Y402657D01*
X459500D01*
G02X459316Y403396I1392J739D01*
G01Y407319D01*
X455716Y410919D01*
Y413804D01*
X456618Y414706D01*
G01X471033Y381947D02*
X472332Y384946D01*
X472398Y385059D01*
G03X471546Y387337I-1365J788D01*
G02X469668Y388959I1394J3512D01*
G02X469918Y390861I1364J788D01*
G01X469954Y390896D01*
G02X471768Y392255I5140J-4970D01*
G03X472003Y392407I-735J1394D01*
G03X472398Y392859I-981J1255D01*
G03X472417Y394400I-1365J787D01*
G01X472398Y394434D01*
X472373Y394476D01*
G02X472398Y396759I2040J1119D01*
G03X472417Y398300I-1365J787D01*
G01X472398Y398334D01*
X472373Y398376D01*
G02X472398Y400659I2040J1119D01*
G03X472417Y402200I-1365J787D01*
G01X472398Y402234D01*
X472373Y402276D01*
G02X472398Y404559I2040J1119D01*
G03X472417Y406100I-1365J787D01*
G01X472398Y406134D01*
X472373Y406176D01*
G02X472398Y408459I2040J1119D01*
G03X472417Y410000I-1365J787D01*
G01X472323Y410169D01*
Y417736D01*
X471668Y418391D01*
G01X474218Y419224D02*
X473073Y418079D01*
Y410367D01*
G02X473048Y408084I-2040J-1119D01*
G03X473029Y406543I1365J-787D01*
G01X473048Y406509D01*
X473073Y406467D01*
G02X473048Y404184I-2040J-1119D01*
G03X473029Y402643I1365J-787D01*
G01X473048Y402609D01*
X473073Y402567D01*
G02X473048Y400284I-2040J-1119D01*
G03X473029Y398743I1365J-787D01*
G01X473048Y398709D01*
X473073Y398667D01*
G02X473048Y396384I-2040J-1119D01*
G03X473029Y394843I1365J-787D01*
G01X473048Y394809D01*
X473073Y394767D01*
G02X473048Y392484I-2040J-1119D01*
G01X472982Y392368D01*
X471033Y389747D01*
G01X447373Y383896D02*
X447731D01*
X448419Y383208D01*
Y382713D01*
X448007Y382301D01*
X447181D01*
X447145Y382337D01*
G02X446964Y382374I225J1560D01*
G02X446008Y384684I408J1522D01*
G03X446033Y386967I-2015J1164D01*
G01X446008Y387009D01*
X445989Y387043D01*
G02X446008Y388584I1384J754D01*
G03X446033Y390867I-2015J1164D01*
G01X446008Y390909D01*
X445989Y390943D01*
G02X446008Y392484I1384J754D01*
G02X446033Y392525I847J-488D01*
G03X444078Y395970I-2040J1120D01*
G01X443922D01*
G02X442628Y396757I71J1574D01*
G01X439037Y402980D01*
Y407212D01*
X432548Y413701D01*
Y417945D01*
X432703Y418100D01*
Y418187D01*
G01X467653Y379996D02*
G02X469353Y382310I10709J-6086D01*
G03X467738Y386221I-1701J1586D01*
G01X467609D01*
G02X466313Y386967I0J1499D01*
G01X466288Y387009D01*
X466269Y387043D01*
G02X466288Y388584I1384J754D01*
G03X466313Y390867I-2015J1164D01*
G01X466288Y390909D01*
G02Y392483I1365J787D01*
G01X466313Y392525D01*
G03X466288Y394808I-2040J1119D01*
G02X466261Y396334I1365J787D01*
G01X466323Y396442D01*
G03X466288Y398708I-2050J1102D01*
G02X466269Y400249I1365J787D01*
G01X466288Y400283D01*
X466313Y400325D01*
G03X466288Y402608I-2040J1119D01*
G02Y404184I1365J788D01*
G03X466314Y406463I-2015J1163D01*
G01X465795Y407390D01*
Y412675D01*
X465243Y413227D01*
Y416145D01*
X465398Y416300D01*
Y416387D01*
G01X447373Y391696D02*
G02X448738Y394811I14713J-4591D01*
G03X448949Y395598I-1365J788D01*
G01Y396040D01*
X446848Y398141D01*
Y400941D01*
X444768Y403021D01*
X443029D01*
X441585Y404465D01*
Y409304D01*
X438998Y411891D01*
Y418245D01*
X438843Y418400D01*
Y418487D01*
G01X467653Y391696D02*
G02X468910Y394622I14708J-4585D01*
G02X469037Y394843I9038J-5047D01*
G03X469018Y396384I-1384J754D01*
G02X468993Y398667I2015J1164D01*
G01X469018Y398709D01*
X469037Y398743D01*
G03X469018Y400284I-1384J754D01*
G02X468993Y402567I2015J1164D01*
G01X469018Y402609D01*
X469037Y402643D01*
G03X469018Y404184I-1384J754D01*
G02X468993Y406467I2015J1164D01*
G01X469018Y406509D01*
X469037Y406543D01*
G03X469018Y408084I-1384J754D01*
G02X468706Y409248I2014J1164D01*
G01Y417088D01*
X468183Y417611D01*
Y419645D01*
X468028Y419800D01*
Y419887D01*
G01X447373Y379996D02*
X446770Y381649D01*
G02X445358Y385059I603J2247D01*
G03X445377Y386600I-1365J787D01*
G01X445358Y386634D01*
X445333Y386676D01*
G02X445358Y388959I2040J1119D01*
G03X445377Y390500I-1365J787D01*
G01X445358Y390534D01*
X445333Y390576D01*
G02X445358Y392859I2040J1119D01*
G01X445377Y392892D01*
G03X444074Y395219I-1384J753D01*
G01X444055Y395220D01*
X443906D01*
G02X441978Y396382I87J2324D01*
G01X438287Y402779D01*
Y406901D01*
X431798Y413390D01*
Y417945D01*
X431643Y418100D01*
Y418187D01*
G01X467653Y383896D02*
X466322D01*
X466094Y383668D01*
G03X468806Y382821I1559J228D01*
G03X467712Y385471I-1153J1075D01*
G01X467583D01*
G02X465657Y386600I-2J2204D01*
G01X465638Y386634D01*
X465613Y386676D01*
G02X465638Y388959I2040J1119D01*
G03X465657Y390500I-1365J787D01*
G01X465638Y390534D01*
G02Y392858I2015J1162D01*
G01X465657Y392892D01*
G03X465638Y394433I-1384J754D01*
G02X465613Y396716I2015J1164D01*
G01X465638Y396758D01*
X465665Y396806D01*
G03X465638Y398332I-1392J739D01*
G02X465603Y400598I2015J1164D01*
G01X465638Y400658D01*
X465657Y400692D01*
G03X465638Y402233I-1384J754D01*
G02Y404559I2015J1163D01*
G03X465657Y406100I-1365J787D01*
G01X465045Y407194D01*
Y412364D01*
X464493Y412916D01*
Y416145D01*
X464338Y416300D01*
Y416387D01*
G01X449699Y396351D02*
X447598Y398452D01*
Y401252D01*
X445079Y403771D01*
X443340D01*
X442335Y404776D01*
Y409615D01*
X439748Y412202D01*
Y418245D01*
X439903Y418400D01*
Y418487D01*
G01X449699Y396351D02*
Y395597D01*
G01D02*
G02X449388Y394436I-2326J1D01*
G03X448935Y391903I3762J-1980D01*
G02X448738Y390912I-1562J-205D01*
G03X447373Y387796I13480J-7762D01*
G01X467653D02*
G02X469018Y390912I14845J-4646D01*
G03X469215Y391903I-1365J786D01*
G02X469554Y394203I4215J554D01*
G02X469693Y394476I2929J-1319D01*
G03X469668Y396759I-2040J1119D01*
G02X469649Y398300I1365J787D01*
G01X469668Y398334D01*
X469693Y398376D01*
G03X469668Y400659I-2040J1119D01*
G02X469649Y402200I1365J787D01*
G01X469668Y402234D01*
X469693Y402276D01*
G03X469668Y404559I-2040J1119D01*
G02X469649Y406100I1365J787D01*
G01X469678Y406151D01*
X469693Y406179D01*
X469696Y406184D01*
G03X469668Y408459I-2043J1113D01*
G02X469456Y409247I1364J790D01*
G01Y417399D01*
X468933Y417922D01*
Y419645D01*
X469088Y419800D01*
Y419887D01*
G01X483432Y227896D02*
X484501Y225679D01*
G03X486727Y223622I2311J268D01*
G01X489037D01*
X491458Y221201D01*
Y212128D01*
X497486Y206100D01*
X500291D01*
X501097Y205294D01*
G01X483432Y231797D02*
Y230466D01*
X483689Y230209D01*
G02X485447Y229059I-257J-2312D01*
G02X485472Y226776I-2015J-1164D01*
G01X485447Y226734D01*
X485428Y226700D01*
G03X486753Y224372I1384J-753D01*
G01X489348D01*
X492208Y221512D01*
Y212440D01*
X497748Y206900D01*
X502292D01*
G01X483432Y216196D02*
Y217527D01*
X483689Y217784D01*
G03X485447Y218934I-257J2312D01*
G02X486768Y219722I1365J-787D01*
G01X487487D01*
X488438Y218771D01*
Y210881D01*
X495592Y203727D01*
Y202900D01*
G01X483432Y220096D02*
Y218765D01*
X483660Y218537D01*
G03X484616Y219057I-228J1559D01*
G03X484797Y219309I-1199J1052D01*
G02X486742Y220472I2015J-1162D01*
G01X486812D01*
X486814Y220470D01*
X487799D01*
X489188Y219081D01*
Y211192D01*
X496480Y203900D01*
X497392D01*
G01X480052Y218147D02*
X478848Y217441D01*
X478760Y217236D01*
X478827Y217073D01*
G02X478712Y215076I-2155J-878D01*
G01X478687Y215034D01*
X478668Y215000D01*
G03X479993Y212672I1384J-753D01*
G01X480103D01*
G02X482067Y209183I-51J-2326D01*
G01X482048Y209149D01*
G03X482067Y207608I1384J-754D01*
G01X482617Y206656D01*
X487922Y201351D01*
X488142D01*
X488204Y201289D01*
G01X480052Y225947D02*
Y227278D01*
X480280Y227506D01*
G02X481417Y226734I-228J-1559D01*
G01X481436Y226700D01*
G02X481417Y225159I-1384J-754D01*
G03X481392Y222876I2015J-1164D01*
G01X481417Y222834D01*
X481436Y222800D01*
G02X481417Y221259I-1384J-754D01*
G03X481392Y218976I2015J-1164D01*
G01X481417Y218934D01*
X481436Y218900D01*
G02X481417Y217359I-1384J-754D01*
G03X481389Y215084I2015J-1162D01*
G03X481576Y214794I2043J1112D01*
G03X483362Y213871I1856J1402D01*
G01X483491D01*
G02X484816Y211543I-59J-1575D01*
G03X484797Y209183I1998J-1196D01*
G03X485685Y208313I2003J1156D01*
G01X485687Y208312D01*
X490179Y203820D01*
Y203600D01*
X490241Y203538D01*
G01X480052Y229847D02*
Y228516D01*
X480309Y228259D01*
G02X482067Y227109I-257J-2312D01*
G01X482092Y227067D01*
G02X482067Y224784I-2040J-1119D01*
G03X482048Y223243I1365J-787D01*
G01X482067Y223209D01*
X482092Y223167D01*
G02X482067Y220884I-2040J-1119D01*
G03X482048Y219343I1365J-787D01*
G01X482067Y219309D01*
X482092Y219267D01*
G02X482067Y216984I-2040J-1119D01*
G03X482048Y215443I1365J-787D01*
G03X482175Y215246I1396J761D01*
G03X483388Y214621I1257J950D01*
G01X483517D01*
G02X485447Y211133I-85J-2325D01*
G03Y209558I1364J-788D01*
G03X486047Y208970I1353J781D01*
G01X486142Y208918D01*
Y208919D01*
X490711Y204350D01*
X490929D01*
X490991Y204288D01*
G01X552886Y206886D02*
X552825Y206947D01*
Y207231D01*
X551056Y209000D01*
X548575D01*
X547185Y210390D01*
X546756Y211134D01*
G03X545460Y211921I-1365J-788D01*
G01X545321D01*
G02X543376Y213084I70J2325D01*
G03X542055Y213872I-1365J-787D01*
G01X541926D01*
G02X539996Y215034I85J2325D01*
G03X538690Y215821I-1365J-788D01*
G01X538561D01*
G02X536616Y216984I70J2325D01*
G03X535310Y217771I-1365J-788D01*
G01X535192D01*
G03X533886Y216984I59J-1575D01*
G02X531956Y215822I-2015J1163D01*
G01X531786D01*
G02X529856Y216984I85J2325D01*
G03X528550Y217771I-1365J-788D01*
G01X528421D01*
G02X526476Y218934I70J2325D01*
G03X525155Y219722I-1365J-787D01*
G01X525026D01*
G02X523096Y220884I85J2325D01*
G02X523071Y223167I2015J1164D01*
G01X523096Y223209D01*
X523115Y223243D01*
G03X523096Y224784I-1384J754D01*
G03X521790Y225571I-1365J-788D01*
G01X521661D01*
G02X519716Y226734I70J2325D01*
G01X519681Y226794D01*
G02X519716Y229060I2050J1102D01*
G03Y230634I-1364J787D01*
G02X519691Y232917I2015J1164D01*
G01X519716Y232959D01*
G03Y234533I-1364J787D01*
G01X519691Y234575D01*
G02X519716Y236860I2040J1120D01*
G03Y238434I-1364J787D01*
G01X519681Y238494D01*
G02X519716Y240760I2050J1102D01*
G03Y242334I-1364J787D01*
G01X519681Y242394D01*
G02X519716Y244660I2050J1102D01*
G03Y246234I-1364J787D01*
G01X519681Y246294D01*
G02X519716Y248560I2050J1102D01*
G03Y250134I-1364J787D01*
G01X519681Y250194D01*
G02X519716Y252460I2050J1102D01*
G03Y254034I-1364J787D01*
G01X519681Y254094D01*
G02X519716Y256360I2050J1102D01*
G03Y257934I-1364J787D01*
G01X519681Y257994D01*
G02X519716Y260260I2050J1102D01*
G03Y261834I-1364J787D01*
G01X519681Y261894D01*
G02X519716Y264160I2050J1102D01*
G03Y265734I-1364J787D01*
G01X519681Y265794D01*
G02X519716Y268060I2050J1102D01*
G03Y269634I-1364J787D01*
G01X519681Y269694D01*
G02X519716Y271960I2050J1102D01*
G03Y273534I-1364J787D01*
G01X519691Y273576D01*
G02X519716Y275859I2040J1119D01*
G03Y277433I-1364J787D01*
G01X519691Y277475D01*
G02X519716Y279760I2040J1120D01*
G03Y281334I-1364J787D01*
G01X519681Y281394D01*
G02X519716Y283660I2050J1102D01*
G03Y285234I-1364J787D01*
G01X519703Y285257D01*
G03X518352Y286022I-1351J-810D01*
G01X518267D01*
G02X516337Y287184I85J2325D01*
G03X515031Y287971I-1365J-788D01*
G01X514902D01*
G02X512957Y289134I70J2325D01*
G03X511820Y289906I-1365J-787D01*
G01X511592Y289678D01*
Y288347D01*
G01Y292245D02*
Y290914D01*
X511846Y290660D01*
G02X511929Y290649I-264J-2311D01*
G02X513607Y289509I-337J-2301D01*
G03X514928Y288721I1365J787D01*
G01X515057D01*
G02X516987Y287559I-85J-2325D01*
G03X518293Y286772I1365J788D01*
G01X518422D01*
G02X520367Y285609I-70J-2325D01*
G01X520402Y285549D01*
G02X520367Y283283I-2050J-1102D01*
G03Y281709I1364J-787D01*
G01X520402Y281649D01*
G02X520367Y279383I-2050J-1102D01*
G03Y277809I1364J-787D01*
G02Y275483I-2015J-1163D01*
G03Y273909I1364J-787D01*
G01X520402Y273849D01*
G02X520367Y271583I-2050J-1102D01*
G03Y270009I1364J-787D01*
G01X520402Y269949D01*
G02X520367Y267683I-2050J-1102D01*
G03Y266109I1364J-787D01*
G01X520402Y266049D01*
G02X520367Y263783I-2050J-1102D01*
G03Y262209I1364J-787D01*
G01X520402Y262149D01*
G02X520367Y259883I-2050J-1102D01*
G03Y258309I1364J-787D01*
G01X520402Y258249D01*
G02X520367Y255983I-2050J-1102D01*
G03Y254409I1364J-787D01*
G01X520402Y254349D01*
G02X520367Y252083I-2050J-1102D01*
G03Y250509I1364J-787D01*
G01X520402Y250449D01*
G02X520367Y248183I-2050J-1102D01*
G03Y246609I1364J-787D01*
G01X520402Y246549D01*
G02X520367Y244283I-2050J-1102D01*
G03Y242709I1364J-787D01*
G01X520402Y242649D01*
G02X520367Y240383I-2050J-1102D01*
G03Y238809I1364J-787D01*
G01X520402Y238749D01*
G02X520367Y236483I-2050J-1102D01*
G03Y234909I1364J-787D01*
G02X520392Y232626I-2015J-1164D01*
G01X520367Y232584D01*
G03Y231010I1364J-787D01*
G01X520392Y230968D01*
G02X520367Y228683I-2040J-1120D01*
G03Y227109I1364J-787D01*
G01X520380Y227086D01*
G03X521731Y226321I1351J810D01*
G01X521816D01*
G02X523746Y225159I-85J-2325D01*
G02X523771Y222876I-2015J-1164D01*
G01X523746Y222834D01*
X523727Y222800D01*
G03X523746Y221259I1384J-754D01*
G03X525052Y220472I1365J788D01*
G01X525181D01*
G02X527126Y219309I-70J-2325D01*
G03X528447Y218521I1365J787D01*
G01X528576D01*
G02X530506Y217359I-85J-2325D01*
G03X531812Y216572I1365J788D01*
G01X531930D01*
G03X533236Y217359I-59J1575D01*
G02X535166Y218521I2015J-1163D01*
G01X535336D01*
G02X537266Y217359I-85J-2325D01*
G03X538587Y216571I1365J787D01*
G01X538716D01*
G02X540646Y215409I-85J-2325D01*
G03X541952Y214622I1365J788D01*
G01X542081D01*
G02X544026Y213459I-70J-2325D01*
G03X545347Y212671I1365J787D01*
G01X545476D01*
G02X547406Y211509I-85J-2325D01*
G01X547786Y210851D01*
X548886Y209750D01*
X551368D01*
X553358Y207760D01*
X553638Y207761D01*
X553699Y207700D01*
G01X511592Y300047D02*
Y301378D01*
X511820Y301606D01*
G02X512957Y300834I-228J-1559D01*
G03X514902Y299671I2015J1162D01*
G01X515042D01*
G03X516987Y300834I-70J2325D01*
G02X518308Y301622I1365J-787D01*
G01X518352D01*
G02X519703Y300857I0J-1575D01*
G01X519716Y300834D01*
G03X521661Y299671I2015J1162D01*
G01X521790D01*
G02X523096Y298884I-59J-1575D01*
G03X525026Y297722I2015J1163D01*
G01X525155D01*
G02X526476Y296934I-44J-1575D01*
G03X528421Y295771I2015J1162D01*
G01X528550D01*
G02X529856Y294984I-59J-1575D01*
G03X531820Y293821I2015J1163D01*
G01X531922D01*
G03X533886Y294984I-51J2326D01*
G02X535192Y295771I1365J-788D01*
G01X535310D01*
G02X536616Y294984I-59J-1575D01*
G03X538580Y293821I2015J1163D01*
G01X538650D01*
G02X539996Y293033I-19J-1576D01*
G03X541926Y291871I2015J1163D01*
G01X542055D01*
G02X543376Y291083I-44J-1575D01*
G03X545293Y289921I2015J1162D01*
G01X545462D01*
G02X546756Y289134I-71J-1574D01*
G03X548701Y287971I2015J1162D01*
G01X548841D01*
G03X550786Y289134I-70J2325D01*
G02X552080Y289921I1365J-787D01*
G01X556906D01*
X558865Y291880D01*
X563098D01*
X564539Y290439D01*
Y290331D01*
X564600Y290270D01*
G01X511592Y303947D02*
Y302616D01*
X511849Y302359D01*
G02X513607Y301209I-257J-2312D01*
G03X514928Y300421I1365J787D01*
G01X515016D01*
G03X516337Y301209I-44J1575D01*
G02X518282Y302372I2015J-1162D01*
G01X518422D01*
G02X520367Y301209I-70J-2325D01*
G01X520380Y301186D01*
G03X521731Y300421I1351J810D01*
G01X521816D01*
G02X523746Y299259I-85J-2325D01*
G03X525052Y298472I1365J788D01*
G01X525181D01*
G02X527126Y297309I-70J-2325D01*
G03X528447Y296521I1365J787D01*
G01X528576D01*
G02X530506Y295359I-85J-2325D01*
G03X531852Y294571I1365J788D01*
G01X531890D01*
G03X533236Y295359I-19J1576D01*
G02X535166Y296521I2015J-1163D01*
G01X535336D01*
G02X537266Y295359I-85J-2325D01*
G03X538612Y294571I1365J788D01*
G01X538682D01*
G02X540646Y293408I-51J-2326D01*
G03X541952Y292621I1365J788D01*
G01X542081D01*
G02X544026Y291458I-70J-2325D01*
G03X545320Y290671I1365J787D01*
G01X545489D01*
G02X547406Y289509I-98J-2324D01*
G03X548727Y288721I1365J787D01*
G01X548815D01*
G03X550136Y289509I-44J1575D01*
G02X552064Y290671I2015J-1162D01*
G01X556595D01*
X558654Y292730D01*
X563452D01*
X565143Y291039D01*
X565246D01*
X565307Y290978D01*
G01X484552Y381947D02*
X482603Y384568D01*
X482537Y384684D01*
G02X482512Y386967I2015J1164D01*
G01X482537Y387009D01*
X482556Y387043D01*
G03X482537Y388584I-1384J754D01*
G02X482512Y390867I2015J1164D01*
G01X482537Y390909D01*
X482556Y390943D01*
G03X482537Y392484I-1384J754D01*
G02X482512Y394767I2015J1164D01*
G01X482747Y395173D01*
Y403864D01*
X482229Y404382D01*
Y406586D01*
X495792Y420149D01*
Y421150D01*
G01X497454Y419550D02*
X496254D01*
X482977Y406273D01*
Y404695D01*
X483497Y404175D01*
Y394972D01*
X483168Y394400D01*
G03X483187Y392859I1384J-754D01*
G01X483253Y392746D01*
X484552Y389747D01*
G01X494692Y395597D02*
Y396901D01*
X493888Y397705D01*
X493308Y398743D01*
G02X493327Y400284I1384J754D01*
G01X493469Y400504D01*
X495648Y402683D01*
Y402684D01*
X495652D01*
X498316Y405348D01*
X511032D01*
X516784Y411100D01*
X521591D01*
X522491Y412000D01*
G01X494692Y399496D02*
X496179Y400983D01*
Y402149D01*
X498628Y404598D01*
X511344D01*
X517096Y410350D01*
X521642D01*
X522492Y409500D01*
G01X481172Y383896D02*
Y385227D01*
X480915Y385484D01*
G02X479157Y388959I257J2312D01*
G03X479176Y390500I-1365J787D01*
G01X479157Y390534D01*
X479132Y390576D01*
G02X479157Y392859I2040J1119D01*
G03X479176Y394400I-1365J787D01*
G01X479157Y394434D01*
X479132Y394476D01*
G02X479157Y396759I2040J1119D01*
G01X479897Y398042D01*
Y402783D01*
X479379Y403301D01*
Y409998D01*
X491992Y422611D01*
Y423500D01*
G01X481172Y387796D02*
Y386465D01*
X480944Y386237D01*
G02X479807Y388584I228J1559D01*
G03X479832Y390867I-2015J1164D01*
G01X479807Y390909D01*
X479788Y390943D01*
G02X479807Y392484I1384J754D01*
G03X479832Y394767I-2015J1164D01*
G01X479807Y394809D01*
X479788Y394843D01*
G02X479807Y396384I1384J754D01*
G01X480647Y397840D01*
Y403094D01*
X480129Y403612D01*
Y409687D01*
X492392Y421950D01*
X493692D01*
G01X491312Y401447D02*
X492579Y402714D01*
Y403651D01*
X497128Y408200D01*
X509680D01*
X516880Y415400D01*
X522192D01*
X522792Y416000D01*
G01X491312Y393647D02*
X492168Y395801D01*
X492677Y396759D01*
G03Y398333I-1365J787D01*
G02Y400659I2015J1163D01*
G01X493329Y401788D01*
Y403339D01*
X497440Y407450D01*
X509992D01*
X517192Y414650D01*
X522192D01*
X522742Y414100D01*
G01X487932Y379996D02*
Y381327D01*
X488189Y381584D01*
G03X488017Y386221I-257J2312D01*
G01X487888D01*
G02X486567Y388584I44J1575D01*
G03X486592Y390867I-2015J1164D01*
G01X486567Y390909D01*
X486548Y390943D01*
G02X486567Y392484I1384J754D01*
G03Y394810I-2015J1163D01*
G02Y396384I1365J787D01*
G01X486592Y396426D01*
G03X486567Y398709I-2040J1119D01*
G01X486548Y398743D01*
G02X486567Y400284I1384J754D01*
G03X486592Y402567I-2015J1164D01*
G01X486567Y402609D01*
X486548Y402643D01*
G02X486567Y404184I1384J754D01*
G01X487629Y406025D01*
X494854Y413250D01*
X501692D01*
X505731Y417289D01*
X505951D01*
X506013Y417351D01*
G01X487932Y391696D02*
Y390365D01*
X488160Y390137D01*
G03X489239Y390816I-228J1559D01*
G03X489297Y392484I-1307J880D01*
G02Y394810I2015J1163D01*
G03Y396384I-1365J787D01*
G01X489272Y396426D01*
G02X489297Y398709I2040J1119D01*
G01X489316Y398743D01*
G03X489297Y400284I-1384J754D01*
G02X489272Y402567I2015J1164D01*
G01X489322Y402651D01*
G03X489729Y404253I-2955J1603D01*
G01Y404901D01*
X495904Y411076D01*
X502807D01*
X506643Y414912D01*
X506642Y415130D01*
G01X487932Y383896D02*
Y382565D01*
X488160Y382337D01*
G03X487991Y385471I-227J1559D01*
G01X487862D01*
G02X485917Y388959I70J2325D01*
G03X485936Y390500I-1365J787D01*
G01X485917Y390534D01*
X485892Y390576D01*
G02X485917Y392859I2040J1119D01*
G03X485936Y394400I-1365J787D01*
G01X485917Y394434D01*
G02X485892Y396717I2015J1164D01*
G01X485917Y396759D01*
G03Y398333I-1365J787D01*
G02Y400659I2015J1163D01*
G03X485936Y402200I-1365J787D01*
G01X485917Y402234D01*
X485892Y402276D01*
G02X485917Y404559I2040J1119D01*
G01X486879Y406226D01*
Y406337D01*
X494542Y414000D01*
X501381D01*
X505202Y417821D01*
X505201Y418039D01*
X505262Y418100D01*
G01X487932Y387796D02*
G03X489862Y390396I-27406J22360D01*
G03X489947Y392859I-1930J1300D01*
G02X489928Y394400I1365J787D01*
G01X489947Y394434D01*
G03X489972Y396717I-2015J1164D01*
G01X489947Y396759D01*
G02Y398333I1365J787D01*
G03Y400659I-2015J1163D01*
G02X489928Y402200I1365J787D01*
G01X489947Y402234D01*
X489972Y402276D01*
G03X490479Y404254I-3605J1978D01*
G01Y404590D01*
X496215Y410326D01*
X503118D01*
X507292Y414500D01*
X507512D01*
G01X563187Y295696D02*
X563100D01*
X563025Y295771D01*
X555174D01*
G03X554323Y294995I657J-1575D01*
G02X552948Y293821I-2172J1152D01*
G01X552132D01*
G03X550786Y293033I19J-1576D01*
G02X549027Y291883I-2015J1162D01*
G01X548771Y291627D01*
Y290296D01*
G01X563187Y296596D02*
X563100D01*
X563025Y296521D01*
X555031D01*
G03X553659Y295348I800J-2325D01*
G02X552805Y294571I-1508J799D01*
G01X552100D01*
G03X550136Y293408I51J-2326D01*
G02X548999Y292637I-1365J789D01*
G01X548771Y292865D01*
Y294196D01*
G01X908000Y260363D02*
X910386D01*
X912889Y257860D01*
X913787D01*
G01X920847D02*
X916696D01*
X914799Y255963D01*
X912386D01*
X910486Y257863D01*
X908000D01*
G01X913787Y261760D02*
X910184Y265363D01*
X907500D01*
G01X920847Y261760D02*
X916771D01*
X914867Y259856D01*
X913145D01*
X910138Y262863D01*
X907500D01*
G01X908984Y254183D02*
X909071D01*
X909144Y254256D01*
X910192D01*
X912813Y251635D01*
X914832D01*
X916781Y253584D01*
X918201D01*
G03X918930Y253860I0J1101D01*
G02X919194Y253960I264J-299D01*
G01X920847D01*
G01X917467Y255909D02*
X918201D01*
G02X918551Y255559I0J-350D01*
G01Y254684D01*
G02X918433Y254422I-350J0D01*
G02X918201Y254334I-232J262D01*
G01X916470D01*
X914521Y252385D01*
X913124D01*
X910503Y255006D01*
X909341D01*
X909104Y255243D01*
G01X920847Y335860D02*
X916806D01*
X914859Y333913D01*
X914213D01*
X912585Y333915D01*
X911664Y334836D01*
X908899D01*
G01X913787Y335860D02*
X912311Y337336D01*
X908914D01*
G01X920847Y331960D02*
X917651D01*
X915293Y330983D01*
X914557Y330247D01*
X908732D01*
G01X913787Y331960D02*
X911631D01*
X911255Y332336D01*
X908841D01*
G01X920847Y339760D02*
X919300Y339921D01*
X918700Y339983D01*
X918113Y340044D01*
G03X917552Y340134I-646J-2235D01*
G01X917423D01*
G02X916102Y340922I44J1575D01*
G03X914157Y342085I-2015J-1162D01*
G01X912794D01*
X911679Y340970D01*
X908806D01*
X908620Y341156D01*
G01X917467Y337809D02*
X918621Y338475D01*
X918700Y338770D01*
X918704Y338785D01*
G03X917904Y339323I-1237J-976D01*
G03X917526Y339384I-438J-1514D01*
G01X917397D01*
G02X915452Y340547I70J2325D01*
G03X914131Y341335I-1365J-787D01*
G01X913105D01*
X911990Y340220D01*
X911290D01*
X910890Y339820D01*
X910190D01*
X909790Y340220D01*
X908666D01*
X908542Y340096D01*
X908455D01*
G01X934367Y230559D02*
X933142Y233385D01*
G03X933002Y233672I-2156J-874D01*
G03X931072Y234834I-2015J-1163D01*
G01X930943D01*
G02X929622Y235622I44J1575D01*
G03X927677Y236785I-2015J-1162D01*
G01X927537D01*
G03X925592Y235622I70J-2325D01*
G02X924271Y234834I-1365J787D01*
G01X918091D01*
X915795Y232538D01*
X911458D01*
X911044Y232952D01*
X910653D01*
G01X910506Y230402D02*
X910816D01*
X912202Y231788D01*
X916103D01*
X918399Y234084D01*
X924297D01*
G03X926242Y235247I-70J2325D01*
G02X927651Y236035I1365J-787D01*
G02X928972Y235247I-44J-1575D01*
G03X930917Y234084I2015J1162D01*
G01X931046D01*
G02X932352Y233297I-59J-1575D01*
G02X932547Y232733I-1365J-788D01*
G01X932817Y230093D01*
X933002Y229772D01*
G03X934296Y228985I1365J787D01*
G01X934511D01*
X937747Y228610D01*
G01X913700Y242260D02*
X909688D01*
X909289Y242659D01*
X908000D01*
G01X907500Y240159D02*
X914570D01*
X916671Y242260D01*
X920847D01*
G01X908000Y247659D02*
X909789D01*
X911288Y246160D01*
X913787D01*
G01X920847D02*
X916695D01*
X914791Y244256D01*
X910493D01*
X909590Y245159D01*
X908000D01*
G01X920847Y250060D02*
X920033D01*
G02X918551Y250333I0J4159D01*
G03X918002Y250434I-548J-1437D01*
G01X916469D01*
X914520Y248485D01*
X913046D01*
X910325Y251206D01*
X909642D01*
X909454Y251394D01*
G01Y250334D02*
X909576Y250456D01*
X910014D01*
X912735Y247735D01*
X914831D01*
X916780Y249684D01*
X918002D01*
G02X918283Y249632I0J-787D01*
G02X918002Y248109I-281J-736D01*
G01X917467D01*
G01X937747Y372909D02*
X936449Y369912D01*
X936382Y369797D01*
G02X934437Y368634I-2015J1162D01*
G01X934296D01*
G03X933002Y367847I71J-1574D01*
G02X931038Y366684I-2015J1163D01*
G01X930928D01*
G03X929622Y365897I59J-1575D01*
G02X927692Y364735I-2015J1163D01*
G01X927563D01*
G03X926242Y363947I44J-1575D01*
G02X924297Y362784I-2015J1162D01*
G01X914255D01*
X913274Y363765D01*
X912796D01*
X912107Y363076D01*
G01X937747Y369010D02*
X936382Y365897D01*
G02X934452Y364735I-2015J1163D01*
G01X934323D01*
G03X933002Y363947I44J-1575D01*
G02X931057Y362784I-2015J1162D01*
G01X930928D01*
G03X929622Y361997I59J-1575D01*
G02X927692Y360835I-2015J1163D01*
G01X927563D01*
G03X926242Y360047I44J-1575D01*
G02X924297Y358884I-2015J1162D01*
G01X923649D01*
X923456Y358691D01*
X913704D01*
X912844Y357831D01*
G01X934367Y367060D02*
X932418Y364437D01*
X932352Y364322D01*
G02X931031Y363534I-1365J787D01*
G01X930902D01*
G03X928972Y362372I85J-2325D01*
G02X927666Y361585I-1365J788D01*
G01X927537D01*
G03X925592Y360422I70J-2325D01*
G02X924271Y359634I-1365J787D01*
G01X923341D01*
X923146Y359439D01*
X913814D01*
X912872Y360381D01*
G01X913787Y351460D02*
X909030D01*
G01X920847D02*
X916635D01*
X914549Y353546D01*
X912963D01*
X912509Y354000D01*
X909088D01*
G01X913787Y347560D02*
X908942D01*
G01X920847D02*
X916677D01*
X914621Y349616D01*
X908942D01*
G01X908262Y343817D02*
X908432Y343987D01*
X911787D01*
X913035Y345235D01*
X914442D01*
G02X915295Y344458I-655J-1575D01*
G03X916669Y343284I2172J1151D01*
G01X917537D01*
G03X918567Y343559I-69J2325D01*
G02X918969Y343660I402J-750D01*
G01X920847D01*
G01X917467Y345609D02*
X918621Y344944D01*
X918700Y344649D01*
X918704Y344634D01*
G02X918212Y344221I-1238J975D01*
G02X917511Y344034I-746J1388D01*
G01X916812D01*
G02X915959Y344811I655J1575D01*
G03X914585Y345985I-2172J-1151D01*
G01X912724D01*
X911476Y344737D01*
X910700D01*
X910437Y345000D01*
X909700D01*
X909437Y344737D01*
X908402D01*
X908262Y344877D01*
G01X910448Y227852D02*
X911293D01*
X912782Y229341D01*
X917098D01*
X918691Y230934D01*
X923656D01*
X923657Y230935D01*
X924297D01*
G02X924885Y230841I-70J-2326D01*
G01X925737D01*
X926242Y231346D01*
G02X928972I1365J-787D01*
G01X929037Y231232D01*
X930987Y228610D01*
G01X909817Y225302D02*
X913106Y228591D01*
X917406D01*
X918999Y230184D01*
X924298D01*
G02X925592Y229397I-71J-1574D01*
G01X926004Y228985D01*
X927692D01*
G02X929622Y227823I-85J-2325D01*
G03X930943Y227035I1365J787D01*
G01X931038D01*
G03X932599Y227436I108J2818D01*
G01X933554Y228010D01*
G02X934296Y228234I812J-1350D01*
G01X934438D01*
G02X935732Y227447I-71J-1574D01*
G01X935797Y227334D01*
X937747Y224709D01*
G01X927607Y218860D02*
X928761Y218194D01*
X928844Y217884D01*
G02X927666Y217285I-1238J976D01*
G01X927537D01*
G03X925592Y213797I70J-2325D01*
G02X924271Y211434I-1365J-788D01*
G01X924142D01*
G03X922212Y210272I85J-2325D01*
G02X920906Y209485I-1365J788D01*
G01X920796D01*
G03X918832Y208322I51J-2326D01*
G01X918700Y208117D01*
X918364Y207596D01*
X917056Y205756D01*
G01X930987Y216909D02*
X929833Y217575D01*
X929481Y217480D01*
G02X927692Y216535I-1873J1380D01*
G01X927563D01*
G03X926242Y214172I44J-1575D01*
G02X924297Y210684I-2015J-1163D01*
G01X924168D01*
G03X922862Y209897I59J-1575D01*
G02X920898Y208734I-2015J1163D01*
G01X920803D01*
G03X919482Y207946I44J-1575D01*
G01X919300Y207596D01*
X919011Y207040D01*
Y204104D01*
X918220Y203313D01*
G01X914216Y212380D02*
X915007Y211589D01*
X915602D01*
X923247Y219234D01*
X924271D01*
G03X925592Y220022I-44J1575D01*
G02X927537Y221185I2015J-1162D01*
G01X927666D01*
G03X928844Y221784I-60J1575D01*
G01X928761Y222094D01*
X927607Y222760D01*
G01X914344Y209830D02*
X915355Y210841D01*
X915912D01*
X923555Y218484D01*
X924297D01*
G03X926242Y219647I-70J2325D01*
G02X927563Y220435I1365J-787D01*
G01X927692D01*
G02X929161Y219948I0J-2459D01*
G01X930621Y218860D01*
X934367D01*
G01X947887Y214960D02*
X945938Y212338D01*
X945872Y212222D01*
G02X944551Y211434I-1365J787D01*
G01X944422D01*
G03X942492Y210272I85J-2325D01*
G02X941186Y209485I-1365J788D01*
G01X941076D01*
G03X939112Y208322I51J-2326D01*
G02X937818Y207535I-1365J787D01*
G01X937677D01*
G03X935732Y206372I70J-2325D01*
G02X934438Y205585I-1365J787D01*
G01X934282D01*
G03X932352Y204423I85J-2325D01*
G02X931031Y203635I-1365J787D01*
G01X930936D01*
G03X928972Y202472I51J-2326D01*
G02X928028Y201741I-1365J788D01*
G03X925521Y199919I1181J-4261D01*
G01X925060Y199116D01*
Y197494D01*
X924669Y197103D01*
G01X927974Y196801D02*
X929232Y198059D01*
Y201346D01*
X929622Y202097D01*
G02X930928Y202884I1365J-788D01*
G01X931038D01*
G03X933002Y204047I-51J2326D01*
G02X934296Y204834I1365J-787D01*
G01X934437D01*
G03X936382Y205997I-70J2325D01*
G02X937676Y206784I1365J-787D01*
G01X937832D01*
G03X939762Y207946I-85J2325D01*
G02X941083Y208734I1365J-787D01*
G01X941178D01*
G03X943142Y209897I-51J2326D01*
G02X944448Y210684I1365J-788D01*
G01X944577D01*
G03X946522Y211847I-70J2325D01*
G02X946928Y212309I1355J-781D01*
G02X948056Y213041I5343J-6998D01*
G03X949252Y214172I-1299J2571D01*
G03X948574Y216378I-1365J788D01*
G02X946767Y217752I2504J5168D01*
G02X946503Y219613I1120J1108D01*
G01X946590Y219764D01*
X947887Y222760D01*
G01X920331Y199979D02*
X921049Y200697D01*
X921226Y200871D01*
X922212Y202472D01*
G02X924176Y203635I2015J-1163D01*
G01X924271D01*
G03X925592Y204423I-44J1575D01*
G02X927522Y205585I2015J-1163D01*
G01X927678D01*
G03X928972Y206372I-71J1574D01*
G02X930917Y207535I2015J-1162D01*
G01X931058D01*
G03X932352Y208322I-71J1574D01*
G02X934316Y209485I2015J-1163D01*
G01X934426D01*
G03X935732Y210272I-59J1575D01*
G02X937662Y211434I2015J-1163D01*
G01X937791D01*
G03X939112Y212222I-44J1575D01*
G02X941057Y213385I2015J-1162D01*
G01X941186D01*
G03X942492Y214172I-59J1575D01*
G01X942558Y214288D01*
X944507Y216909D01*
G01X921363Y197404D02*
X922436Y198477D01*
Y201351D01*
X922862Y202097D01*
G02X924168Y202884I1365J-788D01*
G01X924278D01*
G03X926242Y204047I-51J2326D01*
G02X927536Y204834I1365J-787D01*
G01X927677D01*
G03X929622Y205997I-70J2325D01*
G02X930916Y206784I1365J-787D01*
G01X931072D01*
G03X933002Y207946I-85J2325D01*
G02X934323Y208734I1365J-787D01*
G01X934418D01*
G03X936382Y209897I-51J2326D01*
G02X937688Y210684I1365J-788D01*
G01X937817D01*
G03X939762Y211847I-70J2325D01*
G02X941083Y212635I1365J-787D01*
G01X941212D01*
G03X943142Y213797I-85J2325D01*
G02X944448Y214584I1365J-788D01*
G01X944507D01*
G03X945224Y214998I0J828D01*
G01X945872Y216122D01*
X945891Y216156D01*
G03X945872Y217697I-1384J754D01*
G01X945806Y217810D01*
X944507Y220809D01*
G01X954647Y214960D02*
X955849Y212188D01*
G03X956011Y211847I2176J825D01*
G02X956222Y211060I-1365J-788D01*
G01X956223Y209152D01*
X956224Y209151D01*
Y207891D01*
X950018Y201685D01*
X947817D01*
G03X945872Y200522I70J-2325D01*
G02X944551Y199734I-1365J787D01*
G01X944422D01*
G03X942492Y198572I85J-2325D01*
G01X941656Y197123D01*
Y194341D01*
X941356Y194041D01*
X940334D01*
X940145Y193852D01*
G01X941899Y191998D02*
X942156Y192255D01*
Y193741D01*
X942406Y193991D01*
Y196921D01*
X943142Y198197D01*
G02X944448Y198984I1365J-788D01*
G01X944577D01*
G03X946522Y200147I-70J2325D01*
G02X947843Y200935I1365J-787D01*
G01X950329D01*
X956974Y207580D01*
X956973Y207581D01*
Y211060D01*
G03X956661Y212223I-2327J-1D01*
G02Y213797I1365J787D01*
G03Y216123I-2015J1163D01*
G02X956198Y218590I3278J1892D01*
G03X956134Y219377I-1552J270D01*
G01Y222543D01*
X955917Y222760D01*
X954647D01*
G01X907976Y219025D02*
X908038Y219087D01*
Y219307D01*
X908673Y219942D01*
X909381D01*
X910017Y220579D01*
Y221287D01*
X913062Y224335D01*
X918450D01*
X920399Y226284D01*
X924278D01*
G03X925415Y226610I-52J2326D01*
G01X925416Y226609D01*
G03X925603Y226734I-1175J1960D01*
G02X927056Y227209I1453J-1984D01*
G01X927058D01*
X927607Y226660D01*
G01X930476Y193956D02*
Y194306D01*
X932786Y196616D01*
Y199772D01*
X933002Y200147D01*
G02X934323Y200935I1365J-787D01*
G01X934452D01*
G03X936382Y202097I-85J2325D01*
G02X937688Y202884I1365J-788D01*
G01X937798D01*
G03X939762Y204047I-51J2326D01*
G02X941056Y204834I1365J-787D01*
G01X941197D01*
G03X943142Y205997I-70J2325D01*
G02X944436Y206784I1365J-787D01*
G01X944592D01*
G03X946522Y207946I-85J2325D01*
G02X947843Y208734I1365J-787D01*
G01X947938D01*
G03X949902Y209897I-51J2326D01*
G02X950554Y210728I3238J-1870D01*
G01X951267Y213009D01*
G01X937747Y220809D02*
X936593Y221475D01*
X936499Y221827D01*
G03X934437Y225085I-2131J933D01*
G01X934297D01*
G03X932352Y223922I70J-2325D01*
G01X932351D01*
G02X930988Y223134I-1363J786D01*
G01X930986D01*
G02X929622Y223922I0J1574D01*
G03X927608Y225085I-2014J-1162D01*
G01X927605D01*
G03X925592Y223922I0J-2324D01*
G02X924271Y223134I-1365J787D01*
G01X922188D01*
X917295Y218241D01*
X915311D01*
X915156Y218396D01*
X915069D01*
G01X951267Y224709D02*
Y223378D01*
X951011Y223122D01*
G03X951197Y218484I256J-2312D01*
G01X951326D01*
G02X952651Y216156I-59J-1575D01*
G01X952632Y216122D01*
X952607Y216080D01*
G03X952632Y213797I2040J-1119D01*
G02X952651Y212256I-1365J-787D01*
G01X952632Y212222D01*
X952607Y212180D01*
G03X952632Y209897I2040J-1119D01*
G02X951311Y207534I-1365J-788D01*
G01X951182D01*
G03X949252Y206372I85J-2325D01*
G02X947946Y205585I-1365J788D01*
G01X947817D01*
G03X945872Y204422I70J-2325D01*
G02X944551Y203634I-1365J787D01*
G01X944422D01*
G03X942492Y202472I85J-2325D01*
G02X941186Y201685I-1365J788D01*
G01X941057D01*
G03X939112Y200522I70J-2325D01*
G02X937791Y199734I-1365J787D01*
G01X937662D01*
G03X935732Y198572I85J-2325D01*
G03X935578Y197997I997J-575D01*
G01Y194838D01*
X935423Y194683D01*
G01X930987Y224709D02*
X931150Y224872D01*
Y226066D01*
X930936Y226284D01*
G02X928972Y227447I51J2326D01*
G03X927678Y228234I-1365J-787D01*
G01X927536D01*
G03X925158Y227339I414J-4707D01*
G02X925032Y227255I-936J1268D01*
G02X924271Y227035I-804J1355D01*
G02X924268Y227034I-498J1490D01*
G01X920088D01*
X918139Y225085D01*
X912751D01*
X907506Y219837D01*
X907288D01*
X907226Y219775D01*
G01X951267Y216909D02*
X949969Y213912D01*
X949902Y213797D01*
G03Y212223I1365J-787D01*
G02X949876Y211360I-1049J-400D01*
G02X949844Y211297I-716J324D01*
G01X949252Y210272D01*
G02X947946Y209485I-1365J788D01*
G01X947836D01*
G03X945872Y208322I51J-2326D01*
G02X944578Y207535I-1365J787D01*
G01X944437D01*
G03X942492Y206372I70J-2325D01*
G02X941198Y205585I-1365J787D01*
G01X941042D01*
G03X939112Y204423I85J-2325D01*
G02X937791Y203635I-1365J787D01*
G01X937696D01*
G03X935732Y202472I51J-2326D01*
G02X934426Y201685I-1365J788D01*
G01X934313D01*
G03X932351Y200522I53J-2325D01*
G01X932036Y199973D01*
Y196928D01*
X929919Y194811D01*
X929811D01*
G01X915069Y217336D02*
X915156D01*
X915311Y217491D01*
X917606D01*
X922499Y222384D01*
X924281D01*
G03X926242Y223547I-54J2325D01*
G02X927606Y224335I1364J-786D01*
G01X927609D01*
G02X928972Y223547I-1J-1574D01*
G03X930985Y222384I2013J1161D01*
G01X930987D01*
G03X933002Y223547I2J2324D01*
G02X934319Y224334I1364J-788D01*
G02X934414I48J-1575D01*
G02X935831Y222178I-47J-1575D01*
G01X935521Y222094D01*
X934367Y222760D01*
G01X936483Y194683D02*
X936328Y194838D01*
Y197996D01*
G02X936382Y198197I401J0D01*
G02X937688Y198984I1365J-788D01*
G01X937817D01*
G03X939762Y200147I-70J2325D01*
G02X941083Y200935I1365J-787D01*
G01X941212D01*
G03X943142Y202097I-85J2325D01*
G02X944448Y202884I1365J-788D01*
G01X944577D01*
G03X946522Y204047I-70J2325D01*
G02X947843Y204835I1365J-787D01*
G01X947972D01*
G03X949902Y205997I-85J2325D01*
G02X951208Y206784I1365J-788D01*
G01X951337D01*
G03X953282Y210272I-70J2325D01*
G02X953263Y211813I1365J787D01*
G01X953282Y211847D01*
X953307Y211889D01*
G03X953282Y214172I-2040J1119D01*
G02X953263Y215713I1365J787D01*
G01X953282Y215747D01*
X953307Y215789D01*
G03X951352Y219234I-2040J1120D01*
G01X951223D01*
G02X951039Y222368I44J1575D01*
G01X951267Y222140D01*
Y220809D01*
G01X930987Y369010D02*
X929038Y366387D01*
X928972Y366272D01*
G02X927666Y365485I-1365J788D01*
G01X927537D01*
G03X925592Y364322I70J-2325D01*
G02X924271Y363534I-1365J787D01*
G01X914563D01*
X913584Y364513D01*
X913221D01*
X912107Y365627D01*
G01X930987Y380709D02*
Y379172D01*
X928806Y376991D01*
X926705D01*
X925312Y378384D01*
X922099D01*
X921656Y377941D01*
X914330D01*
X911656Y380615D01*
Y385241D01*
X905856Y391041D01*
X904586D01*
G01X927607Y378760D02*
X926126D01*
X925752Y379134D01*
X921788D01*
X921343Y378689D01*
X914640D01*
X912404Y380925D01*
Y385551D01*
X906356Y391599D01*
Y392878D01*
G01X934367Y378760D02*
X932418Y376138D01*
X932352Y376022D01*
G02X931031Y375234I-1365J787D01*
G01X930902D01*
G03X928972Y374072I85J-2325D01*
G02X927666Y373285I-1365J788D01*
G01X927548D01*
G02X926242Y374072I59J1575D01*
G01X924912Y374484D01*
X923013D01*
X922556Y374941D01*
X912556D01*
X907849Y379648D01*
Y381848D01*
X907292Y382405D01*
X906008D01*
G01X927607Y374860D02*
X926287D01*
X925913Y375234D01*
X923324D01*
X922869Y375689D01*
X912866D01*
X908597Y379958D01*
Y382158D01*
X907712Y383043D01*
Y384308D01*
G01X944507Y376809D02*
Y378140D01*
X944250Y378397D01*
G02X942492Y379547I257J2312D01*
G03X941171Y380335I-1365J-787D01*
G01X941042D01*
G02X939112Y381497I85J2325D01*
G03X937806Y382284I-1365J-788D01*
G01X937677D01*
G02X935732Y383447I70J2325D01*
G03X934411Y384235I-1365J-787D01*
G01X934282D01*
G02X932352Y385397I85J2325D01*
G03X931046Y386184I-1365J-788D01*
G01X930917D01*
G02X928972Y387347I70J2325D01*
G03X927651Y388135I-1365J-787D01*
G01X927522D01*
G02X925592Y389297I85J2325D01*
G03X924271Y390085I-1365J-787D01*
G01X924142D01*
G02X922212Y391247I85J2325D01*
G03X920918Y392034I-1365J-787D01*
G01X920777D01*
G02X918832Y393197I70J2325D01*
G01X918411Y393927D01*
X918117Y394221D01*
X917255D01*
X911896Y399581D01*
X910716D01*
X906788Y403509D01*
X905358D01*
G01X907161Y405313D02*
Y404194D01*
X911026Y400329D01*
X912206D01*
X917565Y394969D01*
X918427D01*
X919010Y394386D01*
X919480Y393571D01*
X919482Y393572D01*
G03X920776Y392785I1365J787D01*
G01X920932D01*
G02X922862Y391623I-85J-2325D01*
G03X924183Y390835I1365J787D01*
G01X924312D01*
G02X926242Y389673I-85J-2325D01*
G03X927563Y388885I1365J787D01*
G01X927677D01*
G02X929622Y387722I-70J-2325D01*
G03X930943Y386934I1365J787D01*
G01X931072D01*
G02X933002Y385772I-85J-2325D01*
G03X934308Y384985I1365J788D01*
G01X934437D01*
G02X936382Y383822I-70J-2325D01*
G03X937703Y383034I1365J787D01*
G01X937832D01*
G02X939762Y381872I-85J-2325D01*
G03X941068Y381085I1365J788D01*
G01X941197D01*
G02X943142Y379922I-70J-2325D01*
G03X944279Y379150I1365J787D01*
G01X944507Y379378D01*
Y380709D01*
G01X934367Y374860D02*
X935521Y375525D01*
X935831Y375441D01*
G02X934426Y373285I-1465J-581D01*
G01X934316D01*
G03X932352Y372122I51J-2326D01*
G02X931058Y371335I-1365J787D01*
G01X930917D01*
G03X928972Y370172I70J-2325D01*
G02X927678Y369385I-1365J787D01*
G01X927522D01*
G03X927503I-9J-2325D01*
G01Y369384D01*
G03X925592Y368222I104J-2324D01*
G02X924268Y367434I-1365J788D01*
G01X922791D01*
X922382Y367025D01*
X916437D01*
X914171Y369291D01*
X909980D01*
X907999Y371272D01*
X908000Y371490D01*
X907939Y371551D01*
G01X903413Y379826D02*
X903475Y379764D01*
X903697D01*
X904756Y378705D01*
Y378341D01*
X911256Y371841D01*
X919556D01*
X920812Y370585D01*
X924311D01*
X924842Y370583D01*
X925252Y370621D01*
X927607Y370959D01*
G01X907189Y370801D02*
X907251Y370739D01*
X907471D01*
X909669Y368541D01*
X913860D01*
X916126Y366275D01*
X922693D01*
X923102Y366684D01*
X924277D01*
G03X926242Y367847I-50J2326D01*
G02X927536Y368634I1365J-787D01*
G01X927677D01*
G03X929622Y369797I-70J2325D01*
G02X930916Y370584I1365J-787D01*
G01X931072D01*
G03X933002Y371746I-85J2325D01*
G02X934323Y372534I1365J-787D01*
G01X934418D01*
G03X936499Y375793I-51J2326D01*
G01X936593Y376144D01*
X937747Y376809D01*
G01X930987Y372909D02*
X928219Y372536D01*
X927194D01*
X925252Y371712D01*
G02X925141Y371625I-1027J1196D01*
G02X924308Y371335I-914J1284D01*
G01X921123D01*
X919867Y372591D01*
X911567D01*
X905506Y378652D01*
Y379016D01*
X904226Y380296D01*
Y380516D01*
X904164Y380578D01*
G01X947887Y374860D02*
X945938Y377481D01*
X945872Y377597D01*
G02X945847Y379880I2015J1164D01*
G01X945872Y379922D01*
X945891Y379956D01*
G03X944566Y382284I-1384J753D01*
G01X944437D01*
G02X942492Y383447I70J2325D01*
G03X941171Y384235I-1365J-787D01*
G01X941042D01*
G02X939112Y385397I85J2325D01*
G03X937806Y386184I-1365J-788D01*
G01X937677D01*
G02X935732Y387347I70J2325D01*
G03X934411Y388135I-1365J-787D01*
G01X934282D01*
G02X932352Y389297I85J2325D01*
G03X931046Y390084I-1365J-788D01*
G01X930936D01*
G02X928972Y391247I51J2326D01*
G03X927678Y392034I-1365J-787D01*
G01X927537D01*
G02X925592Y393197I70J2325D01*
G03X924298Y393984I-1365J-787D01*
G01X924142D01*
G02X922212Y395146I85J2325D01*
G03X920852Y395932I-1360J-784D01*
G01X919811D01*
X918386Y397357D01*
Y398991D01*
X910661Y406716D01*
X909465D01*
X909416Y406667D01*
G01X947887Y382660D02*
X944653Y383034D01*
X944463D01*
G02X943142Y383822I44J1575D01*
G03X941197Y384985I-2015J-1162D01*
G01X941068D01*
G02X939762Y385772I59J1575D01*
G03X937832Y386934I-2015J-1163D01*
G01X937703D01*
G02X936382Y387722I44J1575D01*
G03X934437Y388885I-2015J-1162D01*
G01X934308D01*
G02X933002Y389672I59J1575D01*
G03X931038Y390835I-2015J-1163D01*
G01X930943D01*
G02X929622Y391623I44J1575D01*
G03X927692Y392785I-2015J-1163D01*
G01X927536D01*
G02X926242Y393572I71J1574D01*
G03X924297Y394735I-2015J-1162D01*
G01X924156D01*
G02X922862Y395522I71J1574D01*
G03X920898Y396685I-2015J-1163D01*
G01X920116D01*
X919134Y397667D01*
Y399301D01*
X911268Y407167D01*
Y408422D01*
G01X954647Y374860D02*
X953348Y377859D01*
X953282Y377972D01*
G02X953263Y379513I1365J787D01*
G01X953282Y379547D01*
X953307Y379589D01*
G03X953282Y381872I-2040J1119D01*
G02X953270Y383427I1289J787D01*
G01X953307Y383489D01*
G03X953594Y384611I-2040J1119D01*
G01Y385013D01*
G03X953309Y386015I-1904J0D01*
G02X952843Y387517I2667J1651D01*
G01Y388509D01*
G03X951326Y390084I-1576J0D01*
G03X951219Y390086I-107J-2851D01*
G01X951182D01*
G02X949252Y391247I0J2185D01*
G03X947958Y392034I-1365J-787D01*
G01X947817D01*
G02X945872Y393197I70J2325D01*
G03X944578Y393984I-1365J-787D01*
G01X944422D01*
G02X942492Y395146I85J2325D01*
G03X941171Y395934I-1365J-787D01*
G01X941076D01*
G02X939112Y397097I51J2326D01*
G03X937806Y397884I-1365J-788D01*
G01X937693D01*
G02X937683I-5J2326D01*
G02X935731Y399047I63J2325D01*
G01X935412Y399600D01*
X924851Y410161D01*
X923652D01*
G01X951267Y376809D02*
Y375478D01*
X951039Y375250D01*
G02X949902Y377597I228J1559D01*
G03X949927Y379880I-2015J1164D01*
G01X949902Y379922D01*
X949883Y379956D01*
G02X949902Y381497I1384J754D01*
G03X947957Y384985I-2015J1163D01*
G01X947828D01*
G02X946522Y385772I59J1575D01*
G03X944592Y386934I-2015J-1163D01*
G01X944463D01*
G02X943142Y387722I44J1575D01*
G03X941197Y388885I-2015J-1162D01*
G01X941068D01*
G02X939762Y389672I59J1575D01*
G03X937798Y390835I-2015J-1163D01*
G01X937703D01*
G02X936382Y391623I44J1575D01*
G03X934452Y392785I-2015J-1163D01*
G01X934296D01*
G02X933002Y393572I71J1574D01*
G03X931057Y394735I-2015J-1162D01*
G01X930916D01*
G02X929622Y395522I71J1574D01*
G03X927658Y396685I-2015J-1163D01*
G01X927548D01*
G02X926242Y397472I59J1575D01*
G03X924312Y398634I-2015J-1163D01*
G01X924170D01*
G02X922862Y399422I57J1575D01*
G01X922592Y399888D01*
X920656Y401824D01*
Y403992D01*
X919288Y405360D01*
Y405580D01*
X919227Y405641D01*
G01X951267Y384609D02*
G03X949800Y386650I-3679J-1097D01*
G02X949252Y387347I2143J2249D01*
G03X947931Y388135I-1365J-787D01*
G01X947802D01*
G02X945872Y389297I85J2325D01*
G03X944566Y390084I-1365J-788D01*
G01X944456D01*
G02X942492Y391247I51J2326D01*
G03X941198Y392034I-1365J-787D01*
G01X941057D01*
G02X939112Y393197I70J2325D01*
G03X937818Y393984I-1365J-787D01*
G01X937662D01*
G02X935732Y395146I85J2325D01*
G03X934411Y395934I-1365J-787D01*
G01X934316D01*
G02X932352Y397097I51J2326D01*
G03X931046Y397884I-1365J-788D01*
G01X930917D01*
G02X928971Y399047I69J2325D01*
G01X927924Y400864D01*
X923051Y405759D01*
X916486Y412354D01*
X916266D01*
X916204Y412416D01*
G01X951267Y372909D02*
Y374240D01*
X951010Y374497D01*
G02X949252Y377972I257J2312D01*
G03X949271Y379513I-1365J787D01*
G01X949252Y379547D01*
X949227Y379589D01*
G02X949252Y381872I2040J1119D01*
G03X947931Y384235I-1365J788D01*
G01X947802D01*
G02X945872Y385397I85J2325D01*
G03X944566Y386184I-1365J-788D01*
G01X944437D01*
G02X942492Y387347I70J2325D01*
G03X941171Y388135I-1365J-787D01*
G01X941042D01*
G02X939112Y389297I85J2325D01*
G03X937806Y390084I-1365J-788D01*
G01X937696D01*
G02X935732Y391247I51J2326D01*
G03X934438Y392034I-1365J-787D01*
G01X934297D01*
G02X932352Y393197I70J2325D01*
G03X931058Y393984I-1365J-787D01*
G01X930902D01*
G02X928972Y395146I85J2325D01*
G03X927651Y395934I-1365J-787D01*
G01X927556D01*
G02X925592Y397097I51J2326D01*
G03X924286Y397884I-1365J-788D01*
G01X924157D01*
G02X922212Y399047I70J2325D01*
G01X921992Y399427D01*
X919906Y401513D01*
Y403681D01*
X918759Y404828D01*
X918539D01*
X918477Y404890D01*
G01X951267Y380709D02*
Y382040D01*
G02X952021Y383225I1447J-88D01*
G03X951933Y386038I-752J1384D01*
G02X951225Y386615I797J1701D01*
G03X950662Y387054I-1082J-808D01*
G02X950308Y387258I603J1456D01*
G02X949902Y387722I960J1250D01*
G03X947957Y388885I-2015J-1162D01*
G01X947828D01*
G02X946522Y389672I59J1575D01*
G03X944558Y390835I-2015J-1163D01*
G01X944463D01*
G02X943142Y391623I44J1575D01*
G03X941212Y392785I-2015J-1163D01*
G01X941056D01*
G02X939762Y393572I71J1574D01*
G03X937817Y394735I-2015J-1162D01*
G01X937676D01*
G02X936382Y395522I71J1574D01*
G03X934418Y396685I-2015J-1163D01*
G01X934308D01*
G02X933002Y397472I59J1575D01*
G03X931072Y398634I-2015J-1163D01*
G01X930930D01*
G02X929622Y399422I57J1575D01*
G01X928522Y401329D01*
X924111Y405759D01*
X917015Y412886D01*
X917016Y413104D01*
X916955Y413165D01*
G01X998586Y236409D02*
X997408D01*
X996800Y235801D01*
Y234404D01*
G02X996637Y233788I-1246J0D01*
G01X996571Y233672D01*
G02X996035Y233120I-1364J789D01*
G01X995496Y232803D01*
X994006Y231632D01*
X993841Y231346D01*
G03Y229772I1365J-787D01*
G01X993866Y229730D01*
G02X993841Y227447I-2040J-1119D01*
G01X993822Y227413D01*
G03X993841Y225872I1384J-754D01*
G02X993866Y223589I-2015J-1164D01*
G01X993841Y223547D01*
X993822Y223513D01*
G03X993841Y221972I1384J-754D01*
G02X993866Y219689I-2015J-1164D01*
G01X993841Y219647D01*
X993822Y219613D01*
G03X993841Y218072I1384J-754D01*
G02X993866Y215789I-2015J-1164D01*
G01X993841Y215747D01*
X993822Y215713D01*
G03X993841Y214172I1384J-754D01*
G02X993866Y211889I-2015J-1164D01*
G01X993841Y211847D01*
X993822Y211813D01*
G03X993841Y210272I1384J-754D01*
G02Y207946I-2015J-1163D01*
G03Y206372I1365J-787D01*
G01X993866Y206330D01*
G02X993841Y204047I-2040J-1119D01*
G01X993631Y203672D01*
Y202594D01*
X994906Y201319D01*
Y200336D01*
G01X992881Y200681D02*
Y203868D01*
X993191Y204422D01*
G03Y205997I-1365J787D01*
G01X993166Y206039D01*
G02X993191Y208322I2040J1119D01*
G01X993210Y208356D01*
G03X993191Y209897I-1384J754D01*
G02X993166Y212180I2015J1164D01*
G01X993191Y212222D01*
X993210Y212256D01*
G03X993191Y213797I-1384J754D01*
G02X993166Y216080I2015J1164D01*
G01X993191Y216122D01*
X993210Y216156D01*
G03X993191Y217697I-1384J754D01*
G02X993166Y219980I2015J1164D01*
G01X993191Y220022D01*
X993210Y220056D01*
G03X993191Y221597I-1384J754D01*
G02X993166Y223880I2015J1164D01*
G01X993191Y223922D01*
X993210Y223956D01*
G03X993191Y225497I-1384J754D01*
G02Y227823I2015J1163D01*
G03Y229397I-1365J787D01*
G01X993166Y229439D01*
G02X993191Y231722I2040J1119D01*
G01X993378Y232048D01*
X995166Y234454D01*
X995206Y234460D01*
G01X991826Y240309D02*
X990527Y237310D01*
X989811Y236071D01*
G03Y235247I714J-412D01*
G01X989830Y235213D01*
G02X989811Y233672I-1384J-754D01*
G03Y231346I2015J-1163D01*
G02X990017Y230685I-1365J-788D01*
G01X990021Y230681D01*
Y230520D01*
G02X989831Y229807I-1576J38D01*
G01X989200Y228712D01*
Y226900D01*
X987393Y225093D01*
Y224700D01*
G02X987081Y223548I-2327J12D01*
G03Y221974I1365J-787D01*
G02Y219648I-2015J-1163D01*
G03Y218074I1365J-787D01*
G02Y215748I-2015J-1163D01*
G03Y214174I1365J-787D01*
G02Y211848I-2015J-1163D01*
G03X986870Y211047I1365J-788D01*
G01Y202330D01*
X988153Y201047D01*
Y193086D01*
X986881Y191814D01*
Y190678D01*
G01X991826Y228610D02*
X990527Y225611D01*
X990461Y225497D01*
G03X990442Y223956I1365J-787D01*
G01X990461Y223922D01*
X990486Y223880D01*
G02X990461Y221597I-2040J-1119D01*
G03X990442Y220056I1365J-787D01*
G01X990461Y220022D01*
X990486Y219980D01*
G02X990461Y217697I-2040J-1119D01*
G03X990442Y216156I1365J-787D01*
G01X990461Y216122D01*
X990486Y216080D01*
G02X990461Y213797I-2040J-1119D01*
G03X990442Y212256I1365J-787D01*
G01X990461Y212222D01*
X990486Y212180D01*
G02X990461Y209897I-2040J-1119D01*
G03X990442Y208356I1365J-787D01*
G01X990461Y208322D01*
G02X990486Y206039I-2015J-1164D01*
G01X990461Y205997D01*
G03Y204423I1365J-787D01*
G01X990881Y203694D01*
Y200481D01*
G01X991826Y236409D02*
X990527Y233410D01*
X990461Y233297D01*
G03X990442Y231756I1365J-787D01*
G01X990530Y231599D01*
G02X990515Y229488I-1865J-1042D01*
G01X990061Y228703D01*
Y226461D01*
X989499Y225899D01*
Y224730D01*
G03X989786Y223589I2327J-21D01*
G01X989811Y223547D01*
X989830Y223513D01*
G02X989811Y221972I-1384J-754D01*
G03X989786Y219689I2015J-1164D01*
G01X989811Y219647D01*
X989830Y219613D01*
G02X989811Y218072I-1384J-754D01*
G03X989786Y215789I2015J-1164D01*
G01X989811Y215747D01*
X989830Y215713D01*
G02X989811Y214172I-1384J-754D01*
G03X989786Y211889I2015J-1164D01*
G01X989811Y211847D01*
X989830Y211813D01*
G02X989811Y210272I-1384J-754D01*
G03Y207946I2015J-1163D01*
G02Y206372I-1365J-787D01*
G03Y204048I2015J-1162D01*
G01X990031Y203666D01*
Y202376D01*
X989426Y201771D01*
Y192522D01*
X988881Y191977D01*
Y191212D01*
G01X958026Y216909D02*
X958200Y216420D01*
X958724Y214947D01*
X959391Y213795D01*
G02Y212221I-1365J-787D01*
G01X959366Y212179D01*
G03X959078Y211056I2047J-1123D01*
G01Y206468D01*
X950295Y197685D01*
X949445D01*
X945506Y193746D01*
Y190692D01*
X944755Y189941D01*
X943449D01*
G01X945356Y188241D02*
Y189341D01*
X946256Y190241D01*
Y193435D01*
X949756Y196935D01*
X950606D01*
X958200Y204529D01*
G01X965200Y188900D02*
Y188987D01*
X965045Y189142D01*
Y194451D01*
X972074Y201480D01*
X972728Y202608D01*
Y205790D01*
X970306Y208212D01*
Y217300D01*
X970509Y217503D01*
Y219443D01*
X970158Y220060D01*
G02X970181Y221597I1388J748D01*
G03X970207Y223876I-2015J1163D01*
G01X970181Y223922D01*
X970158Y223960D01*
G02X970181Y225497I1388J748D01*
G03X970207Y227776I-2015J1163D01*
G01X970181Y227822D01*
G02X971489Y230185I1365J788D01*
G01X971633D01*
G03X973561Y231347I-87J2324D01*
G02X974885Y232135I1365J-788D01*
G01X974998D01*
G03X976941Y233297I-72J2325D01*
G03X977222Y233873I-3968J2292D01*
G01X978306Y236409D01*
G01Y248109D02*
Y246778D01*
X978050Y246522D01*
G03X978236Y241884I256J-2312D01*
G01X978365D01*
G02X979690Y239556I-59J-1575D01*
G01X979671Y239522D01*
X979646Y239480D01*
G03X979671Y237197I2040J-1119D01*
G02X979690Y235656I-1365J-787D01*
G01X979671Y235622D01*
X979646Y235580D01*
G03X979671Y233297I2040J-1119D01*
G02X978377Y230935I-1365J-788D01*
G01X978236D01*
G03X976291Y229772I70J-2325D01*
G02X974997Y228985I-1365J787D01*
G01X974841D01*
G03X972911Y225497I85J-2325D01*
G02X972930Y223956I-1365J-787D01*
G01X972911Y223922D01*
X972906Y223914D01*
X972902Y223908D01*
X972897Y223898D01*
X972886Y223880D01*
G03X972911Y221597I2040J-1119D01*
G02X972861Y219893I-1405J-812D01*
G01X972598Y219630D01*
Y209119D01*
X975396Y206321D01*
Y200651D01*
X969876Y195131D01*
Y193079D01*
X969740Y192943D01*
G01X978306Y240309D02*
X978299Y240294D01*
G02X976941Y237196I-14719J4605D01*
G03X976780Y236017I1365J-787D01*
G02X976526Y234154I-3808J-430D01*
G02X976291Y233672I-3553J1434D01*
G02X974985Y232885I-1365J788D01*
G01X974875D01*
G03X972911Y231722I51J-2326D01*
G02X971617Y230935I-1365J787D01*
G01X971476D01*
G03X969531Y227447I70J-2325D01*
G01X969550Y227413D01*
G02X969531Y225872I-1384J-754D01*
G03X969506Y223589I2015J-1164D01*
G01X969531Y223547D01*
X969550Y223513D01*
G02X969531Y221972I-1384J-754D01*
G03X969502Y219696I2015J-1164D01*
G01X969759Y219244D01*
Y217814D01*
X969556Y217611D01*
Y207901D01*
X971978Y205479D01*
Y202810D01*
X971474Y201941D01*
X964295Y194762D01*
Y189142D01*
X964140Y188987D01*
Y188900D01*
G01X970800Y192965D02*
X970626Y193139D01*
Y194820D01*
X976146Y200340D01*
Y206632D01*
X973348Y209430D01*
Y219319D01*
X973440Y219411D01*
G03X973561Y221972I-1933J1375D01*
G02X973542Y223513I1365J787D01*
G01X973541Y223514D01*
X973543Y223517D01*
X973586Y223589D01*
G03X973561Y225872I-2040J1119D01*
G02X974855Y228234I1365J788D01*
G01X974996D01*
G03X976941Y229397I-70J2325D01*
G02X978235Y230184I1365J-787D01*
G01X978391D01*
G03X980321Y233672I-85J2325D01*
G02X980302Y235213I1365J787D01*
G01X980321Y235247D01*
X980346Y235289D01*
G03X980321Y237572I-2040J1119D01*
G02X980302Y239113I1365J787D01*
G01X980321Y239147D01*
X980346Y239189D01*
G03X978391Y242634I-2040J1120D01*
G01X978262D01*
G02X978078Y245768I44J1575D01*
G01X978306Y245540D01*
Y244209D01*
G01X959200Y194265D02*
X959786Y194851D01*
Y196491D01*
X966946Y203651D01*
Y207161D01*
X966481Y207626D01*
Y217073D01*
X966151Y217698D01*
G02Y220022I2015J1162D01*
G01X966170Y220056D01*
G03X966151Y221597I-1384J754D01*
G02X966126Y223880I2015J1164D01*
G01X966151Y223922D01*
X966170Y223956D01*
G03X966151Y225497I-1384J754D01*
G02Y227823I2015J1163D01*
G03Y229397I-1365J787D01*
G01X966126Y229439D01*
G02X968115Y232885I2040J1120D01*
G01X968225D01*
G03X969531Y233672I-59J1575D01*
G02X971461Y234834I2015J-1163D01*
G01X971590D01*
G03X972911Y235622I-38J1564D01*
G01X972927Y235650D01*
G02X973444Y236482I13165J-7604D01*
G03X973545Y236812I-498J333D01*
G01Y237352D01*
X973323Y237574D01*
Y238068D01*
X973615Y238360D01*
X974926D01*
G01X961476Y193991D02*
X960534Y194933D01*
Y196181D01*
X967694Y203341D01*
Y207474D01*
X967231Y207937D01*
Y217383D01*
X966801Y218073D01*
G02Y219647I1365J787D01*
G01X966826Y219689D01*
G03X966801Y221972I-2040J1119D01*
G02X966782Y223513I1365J787D01*
G01X966801Y223547D01*
X966826Y223589D01*
G03X966801Y225872I-2040J1119D01*
G02X966782Y227413I1365J787D01*
G01X966801Y227447D01*
G03X966826Y229730I-2015J1164D01*
G01X966801Y229772D01*
G02X968122Y232134I1365J787D01*
G01X968217D01*
G03X970181Y233297I-51J2326D01*
G02X971487Y234084I1365J-788D01*
G01X971616D01*
G03X973561Y235246I-68J2323D01*
G02X975500Y236892I3267J-1884D01*
G03X976176Y239318I-574J1467D01*
G03X974322Y240804I-3490J-2454D01*
G02X973351Y242279I604J1455D01*
G01Y243071D01*
X973946Y243666D01*
Y244501D01*
X973351Y245096D01*
Y248256D01*
X973556Y248461D01*
X974426D01*
X974926Y247961D01*
Y246160D01*
G01X978828Y194186D02*
X980146Y195504D01*
Y198615D01*
X982146Y200615D01*
Y202031D01*
X981234Y202943D01*
Y214987D01*
X979671Y217698D01*
G02Y220022I2015J1162D01*
G01X979690Y220056D01*
G03X979671Y221597I-1384J754D01*
G02X981616Y225085I2015J1163D01*
G01X981745D01*
G03X983051Y225872I-59J1575D01*
G02X985015Y227035I2015J-1163D01*
G01X985110D01*
G03X986431Y229397I-44J1575D01*
G01X986406Y229439D01*
G02X986431Y231722I2040J1119D01*
G01X986450Y231756D01*
G03X986431Y233297I-1384J754D01*
G02X986406Y235580I2015J1164D01*
G01X986431Y235622D01*
X986450Y235656D01*
G03X986431Y237197I-1384J754D01*
G02X986210Y237718I2016J1162D01*
G01X985066Y240309D01*
G01X981397Y194186D02*
X980894Y194689D01*
Y198293D01*
X982894Y200293D01*
Y202344D01*
X981984Y203254D01*
Y215186D01*
X980321Y218073D01*
G02Y219647I1365J787D01*
G01X980346Y219689D01*
G03X980321Y221972I-2040J1119D01*
G02X981642Y224335I1365J788D01*
G01X981771D01*
G03X983701Y225497I-85J2325D01*
G02X985007Y226284I1365J-788D01*
G01X985117D01*
G03X987106Y229730I-51J2326D01*
G01X987081Y229772D01*
G02Y231346I1365J787D01*
G03Y233672I-2015J1163D01*
G02X987062Y235213I1365J787D01*
G01X987081Y235247D01*
X987106Y235289D01*
G03X987081Y237572I-2040J1119D01*
G02X987062Y239113I1365J787D01*
G01X987081Y239147D01*
X987106Y239189D01*
G03X986580Y242076I-2040J1120D01*
G01Y242798D01*
X987526Y243744D01*
Y244724D01*
X986040Y246210D01*
X985456D01*
X985066Y245820D01*
Y244209D01*
G01X953826Y193611D02*
X954676Y194461D01*
Y195702D01*
X961356Y202382D01*
Y203401D01*
X960916Y203841D01*
Y205901D01*
X962187Y207172D01*
Y209259D01*
X962771Y210272D01*
G03X962790Y211813I-1365J787D01*
G01X962771Y211847D01*
X962746Y211889D01*
G02X962771Y214172I2040J1119D01*
G03X962790Y215713I-1365J787D01*
G01X962771Y215747D01*
X962746Y215789D01*
G02X962771Y218072I2040J1119D01*
G03X962790Y219613I-1365J787D01*
G01X962771Y219647D01*
X962746Y219689D01*
G02X962771Y221972I2040J1119D01*
G03X962790Y223513I-1365J787D01*
G01X962771Y223547D01*
X962746Y223589D01*
G02X962771Y225872I2040J1119D01*
G03X962790Y227413I-1365J787D01*
G01X962771Y227447D01*
G02X962746Y229730I2015J1164D01*
G01X962771Y229772D01*
G03Y231346I-1365J787D01*
G02X964701Y234834I2015J1163D01*
G01X964830D01*
G03X966151Y235622I-44J1575D01*
G02X968096Y236785I2015J-1162D01*
G01X968225D01*
G03X969531Y237572I-59J1575D01*
G02X969781Y237925I2015J-1162D01*
G01X971546Y240309D01*
G01X956376Y193511D02*
X955432Y194455D01*
Y195388D01*
X964106Y204062D01*
Y206181D01*
X962937Y207350D01*
Y209058D01*
X963421Y209897D01*
G03X963446Y212180I-2015J1164D01*
G01X963421Y212222D01*
X963402Y212256D01*
G02X963421Y213797I1384J754D01*
G03X963446Y216080I-2015J1164D01*
G01X963421Y216122D01*
X963402Y216156D01*
G02X963421Y217697I1384J754D01*
G03X963446Y219980I-2015J1164D01*
G01X963421Y220022D01*
X963402Y220056D01*
G02X963421Y221597I1384J754D01*
G03X963446Y223880I-2015J1164D01*
G01X963421Y223922D01*
X963402Y223956D01*
G02X963421Y225497I1384J754D01*
G03Y227823I-2015J1163D01*
G02Y229397I1365J787D01*
G01X963446Y229439D01*
G03X963421Y231722I-2040J1119D01*
G01X963402Y231756D01*
G02X964727Y234084I1384J753D01*
G01X964856D01*
G03X966801Y235247I-70J2325D01*
G02X968122Y236035I1365J-787D01*
G01X968251D01*
G03X970181Y237197I-85J2325D01*
G02X970705Y237742I1365J-788D01*
G01X971873Y238510D01*
X972733Y239189D01*
X972922Y239517D01*
G03X972911Y241097I-1397J780D01*
G01X972845Y241210D01*
X972698Y241550D01*
Y241558D01*
X971546Y242710D01*
Y244209D01*
G01X981686Y238360D02*
X982983Y235364D01*
X983070Y235213D01*
G02X983051Y233672I-1384J-754D01*
G03Y231346I2015J-1163D01*
G02X981757Y228985I-1365J-787D01*
G01X981601D01*
G03X979671Y227823I85J-2325D01*
G02X978350Y227035I-1365J787D01*
G01X978255D01*
G03X976266Y223589I51J-2326D01*
G01X976291Y223547D01*
X976310Y223513D01*
G02X976291Y221972I-1384J-754D01*
G03X976266Y219689I2015J-1164D01*
G01X977056Y218323D01*
Y214011D01*
X978216Y212851D01*
Y201191D01*
X977408Y200383D01*
Y197623D01*
X974646Y194861D01*
Y193141D01*
X973636Y192131D01*
G01X976186Y192141D02*
X975396Y192931D01*
Y194550D01*
X978158Y197312D01*
Y200075D01*
X978964Y200881D01*
Y213164D01*
X977806Y214322D01*
Y218522D01*
X976922Y220056D01*
G02X976941Y221597I1384J754D01*
G03X976966Y223880I-2015J1164D01*
G01X976941Y223922D01*
X976922Y223956D01*
G02X978247Y226284I1384J753D01*
G01X978357D01*
G03X980321Y227447I-51J2326D01*
G02X981615Y228234I1365J-787D01*
G01X981756D01*
G03X983701Y231722I-70J2325D01*
G01X983682Y231756D01*
G02X983701Y233297I1384J754D01*
G03X983726Y235580I-2015J1164D01*
G01X983701Y235622D01*
X983682Y235656D01*
G02X983701Y237197I1384J754D01*
G03X983726Y239480I-2015J1164D01*
G01X983701Y239522D01*
X983682Y239556D01*
G02X983701Y241097I1384J754D01*
G01X983665Y242153D01*
X981686Y246160D01*
G01X958200Y204529D02*
X959828Y206157D01*
Y209161D01*
X959830Y211060D01*
G02X960041Y211846I1576J-2D01*
G01X960066Y211888D01*
G03X960041Y214171I-2040J1119D01*
G01X959608Y214947D01*
Y220549D01*
X959348Y220809D01*
X958026D01*
G01X1212979Y280580D02*
X1211490D01*
G02X1210184Y281334I0J1508D01*
G03X1208863Y282122I-1365J-787D01*
G01X1208019D01*
G02X1206647Y283295I800J2325D01*
G03X1205563Y284149I-1508J-799D01*
G03X1203774Y283284I-258J-1749D01*
G02X1201844Y282122I-2015J1163D01*
G01X1201715D01*
G03X1200394Y281334I44J-1575D01*
G02X1198449Y280171I-2015J1162D01*
G01X1198309D01*
G02X1196364Y281334I70J2325D01*
G03X1195043Y282122I-1365J-787D01*
G01X1194914D01*
G02X1192984Y283284I85J2325D01*
G03X1191678Y284071I-1365J-788D01*
G01X1191549D01*
G02X1189604Y285234I70J2325D01*
G03X1188283Y286022I-1365J-787D01*
G01X1188154D01*
G02X1186224Y287184I85J2325D01*
G03X1184918Y287971I-1365J-788D01*
G01X1184859D01*
X1184853Y287965D01*
X1183605D01*
G01X1169428Y289100D02*
X1168612Y289916D01*
X1167179D01*
X1165230Y291865D01*
X1163801D01*
X1161850Y293816D01*
X1159659D01*
X1158470Y292627D01*
X1157170D01*
X1155981Y293816D01*
X1154004D01*
X1151800Y296020D01*
X1150026D01*
X1148330Y297716D01*
X1146139D01*
X1144944Y296521D01*
X1143499D01*
X1142304Y297716D01*
X1139379D01*
X1138190Y296527D01*
X1136733D01*
X1135520Y297740D01*
X1133450D01*
X1130763Y300427D01*
X1130130D01*
X1129120Y301437D01*
Y312620D01*
X1128100Y313640D01*
X1125690D01*
X1124230Y315100D01*
Y317311D01*
X1121614Y319927D01*
Y321622D01*
X1115113Y328123D01*
G01X1072799Y350989D02*
X1069822D01*
X1068646Y349813D01*
X1035024D01*
X1032991Y347780D01*
X1031723D01*
X1029916Y345973D01*
X1027919D01*
X1026479Y347413D01*
X1024931D01*
X1023387Y345869D01*
X1020991D01*
X1019607Y347253D01*
X1017404D01*
X1016074Y345923D01*
X1014734D01*
X1012569Y343758D01*
X1011134D01*
X1009461Y342085D01*
X1008096D01*
X1005885Y339874D01*
X1004919D01*
X1003236Y338191D01*
X1000865D01*
X999678Y339378D01*
X997373D01*
X996186Y338191D01*
X994556D01*
X993369Y339378D01*
X991176D01*
X989989Y338191D01*
X987796D01*
X986609Y339378D01*
X983647D01*
X982460Y338191D01*
X980912D01*
X979725Y339378D01*
X977157D01*
X975970Y338191D01*
X974276D01*
X973077Y339390D01*
X962572D01*
X957927Y344035D01*
X957381D01*
X956360Y345056D01*
Y345300D01*
G01Y350314D02*
X957881Y351835D01*
X958671D01*
X959723Y352887D01*
Y353677D01*
X961406Y355360D01*
G01X1211440Y281360D02*
G02X1210834Y281710I0J699D01*
G03X1208904Y282872I-2015J-1163D01*
G01X1208162D01*
G02X1207311Y283648I657J1575D01*
G03X1205680Y284894I-2172J-1152D01*
G03X1203124Y283659I-502J-2224D01*
G02X1201818Y282872I-1365J788D01*
G01X1201689D01*
G03X1199744Y281709I70J-2325D01*
G02X1198423Y280921I-1365J787D01*
G01X1198335D01*
G02X1197014Y281709I44J1575D01*
G03X1195069Y282872I-2015J-1162D01*
G01X1194940D01*
G02X1193634Y283659I59J1575D01*
G03X1191704Y284821I-2015J-1163D01*
G01X1191575D01*
G02X1190254Y285609I44J1575D01*
G03X1188309Y286772I-2015J-1162D01*
G01X1188180D01*
G02X1186874Y287559I59J1575D01*
G03X1184944Y288721I-2015J-1163D01*
G01X1183818D01*
X1182622Y289917D01*
X1181073D01*
X1179124Y291866D01*
X1176886D01*
X1175697Y290677D01*
X1174068D01*
X1172535Y292210D01*
X1170218D01*
X1168606Y293822D01*
X1167875D01*
G02X1165945Y294984I85J2325D01*
G03X1164639Y295771I-1365J-788D01*
G01X1163043D01*
X1161850Y294578D01*
X1160550D01*
X1158601Y296527D01*
X1157083D01*
X1155132Y298478D01*
X1153372D01*
X1152185Y299665D01*
X1149517D01*
X1148330Y298478D01*
X1146632D01*
X1145445Y299665D01*
X1142875D01*
X1141688Y298478D01*
X1139377D01*
X1138184Y299671D01*
X1137470D01*
G02X1135525Y300834I70J2325D01*
G03X1134204Y301622I-1365J-787D01*
G01X1134075D01*
G02X1132145Y302784I85J2325D01*
G02X1132120Y305067I2015J1164D01*
G01X1132145Y305109D01*
X1132164Y305143D01*
G03X1132145Y306684I-1384J754D01*
G02Y309010I2015J1163D01*
G03Y310584I-1365J787D01*
G02X1132120Y312867I2015J1164D01*
G01X1132145Y312909D01*
X1132164Y312943D01*
G03X1132145Y314484I-1384J754D01*
G03X1130839Y315271I-1365J-788D01*
G01X1130710D01*
G02X1128765Y316434I70J2325D01*
G03X1127457Y317223I-1366J-786D01*
G01X1126398D01*
X1122910Y320711D01*
Y321833D01*
X1115950Y328803D01*
Y336520D01*
X1108773Y343697D01*
Y347627D01*
X1107978Y348422D01*
X1107036D01*
G02X1105106Y349584I85J2325D01*
G03X1103800Y350371I-1365J-788D01*
G01X1103671D01*
G02X1101726Y351534I70J2325D01*
G03X1100405Y352322I-1365J-787D01*
G01X1100276D01*
G02X1098346Y353484I85J2325D01*
G03X1097040Y354271I-1365J-788D01*
G01X1096922D01*
G03X1095616Y353484I59J-1575D01*
G02X1091586I-2015J1163D01*
G03X1088856I-1365J-788D01*
G01X1088831Y353442D01*
G02X1084826Y353483I-1990J1205D01*
G01X1084794Y353539D01*
G03X1082097Y353484I-1332J-843D01*
G02X1078067I-2015J1163D01*
G03X1075337I-1365J-788D01*
G01X1074962Y352834D01*
X1073947Y352247D01*
X1067448D01*
X1066663Y353032D01*
X1059443D01*
X1057495Y351084D01*
X1052662D01*
G02X1050649Y352247I0J2324D01*
G03X1047919I-1365J-787D01*
G02X1045974Y351084I-2015J1162D01*
G01X1045834D01*
G02X1043889Y352247I70J2325D01*
G03X1041173Y352270I-1365J-787D01*
G01X1041160Y352247D01*
G02X1039215Y351084I-2015J1162D01*
G01X1039075D01*
G02X1037130Y352247I70J2325D01*
G03X1034400I-1365J-787D01*
G02X1032455Y351084I-2015J1162D01*
G01X1032326D01*
G03X1031020Y350297I59J-1575D01*
G02X1029090Y349135I-2015J1163D01*
G01X1028920D01*
G02X1026990Y350297I85J2325D01*
G03X1025684Y351084I-1365J-788D01*
G01X1025566D01*
G03X1024260Y350297I59J-1575D01*
G02X1022330Y349135I-2015J1163D01*
G01X1022160D01*
G02X1020230Y350297I85J2325D01*
G03X1018924Y351084I-1365J-788D01*
G01X1018806D01*
G03X1017500Y350297I59J-1575D01*
G02X1015570Y349135I-2015J1163D01*
G01X1015441D01*
G03X1014120Y348347I44J-1575D01*
G02X1012175Y347184I-2015J1162D01*
G01X1012046D01*
G03X1010740Y346397I59J-1575D01*
G02X1008810Y345235I-2015J1163D01*
G01X1008681D01*
G03X1007360Y344447I44J-1575D01*
G02X1005415Y343284I-2015J1162D01*
G01X1005286D01*
G03X1003980Y342497I59J-1575D01*
G02X1002050Y341335I-2015J1163D01*
G01X1001198D01*
X1000003Y340140D01*
X997936D01*
X996747Y341329D01*
X994556D01*
X993367Y340140D01*
X991176D01*
X989987Y341329D01*
X987796D01*
X986607Y340140D01*
X984416D01*
X983227Y341329D01*
X981036D01*
X979847Y340140D01*
X977656D01*
X976467Y341329D01*
X973385D01*
X972196Y340140D01*
X966607D01*
X959837Y346910D01*
Y349891D01*
X961406Y351460D01*
G01X958026Y376809D02*
Y378140D01*
X957769Y378397D01*
G02X956011Y381873I256J2312D01*
G03Y383447I-1364J787D01*
G01X955976Y383507D01*
G02X956011Y385773I2050J1102D01*
G03Y387347I-1364J787D01*
G02X955976Y387407I843J532D01*
G02X956011Y389673I2050J1102D01*
G03X954695Y392034I-1364J787D01*
G01X954562D01*
G02X952632Y393196I85J2325D01*
G03X951326Y393983I-1365J-788D01*
G01X951216D01*
G02X949252Y395146I51J2326D01*
G03X947958Y395933I-1365J-787D01*
G01X947817D01*
G02X945872Y397096I70J2325D01*
G03X944578Y397883I-1365J-787D01*
G01X944422D01*
G02X942492Y399045I85J2325D01*
G01X942181Y399583D01*
X939235Y402529D01*
X937038D01*
X934846Y404721D01*
Y407401D01*
X929916Y412331D01*
X928696D01*
X928671Y412356D01*
G01X958026Y380709D02*
Y379378D01*
X957799Y379151D01*
G02X956662Y381496I227J1558D01*
G03X956697Y383762I-2015J1164D01*
G01X956662Y383822D01*
G02Y385396I1364J787D01*
G03X956697Y387662I-2015J1164D01*
G01X956662Y387722D01*
G02Y389296I1364J787D01*
G03X954717Y392785I-2015J1163D01*
G01X954647D01*
G03X954588Y392784I0J-1741D01*
G02X953282Y393571I59J1575D01*
G03X951318Y394734I-2015J-1163D01*
G01X951223D01*
G02X949902Y395522I44J1575D01*
G03X947972Y396684I-2015J-1163D01*
G01X947816D01*
G02X946522Y397471I71J1574D01*
G03X944577Y398634I-2015J-1162D01*
G01X944436D01*
G02X943142Y399421I71J1574D01*
G01X942782Y400044D01*
X939547Y403279D01*
X937346D01*
X935594Y405031D01*
Y407711D01*
X930449Y412856D01*
Y414135D01*
G01X954647Y382660D02*
Y384536D01*
G03X954269Y385996I-2247J197D01*
G02X953951Y386552I3552J2400D01*
G02X953594Y388131I3313J1579D01*
G01Y388509D01*
G03X951352Y390834I-2327J0D01*
G03X951243Y390836I-109J-2994D01*
G01X951223D01*
G02X949902Y391622I0J1503D01*
G03X947957Y392785I-2015J-1162D01*
G01X947816D01*
G02X946522Y393572I71J1574D01*
G03X944577Y394735I-2015J-1162D01*
G01X944436D01*
G02X943142Y395522I71J1574D01*
G03X941178Y396685I-2015J-1163D01*
G01X941068D01*
G02X939762Y397472I59J1575D01*
G03X937832Y398634I-2015J-1163D01*
G01X937703D01*
G02X936382Y399421I44J1576D01*
G01X936017Y400053D01*
X925554Y410516D01*
Y411866D01*
X925330Y412090D01*
G01X978306Y353409D02*
Y352078D01*
X978078Y351850D01*
G02X976941Y354197I228J1559D01*
G03X976966Y356480I-2015J1164D01*
G01X976941Y356522D01*
X976922Y356556D01*
G02X976941Y358097I1384J754D01*
G03X976966Y360380I-2015J1164D01*
G01X976941Y360422D01*
X976922Y360456D01*
G02X976941Y361997I1384J754D01*
G03X974996Y365485I-2015J1163D01*
G01X974867D01*
G02X973542Y367813I59J1575D01*
G01X973561Y367847D01*
G03X973586Y370130I-2015J1164D01*
G01X973561Y370172D01*
G02Y371746I1365J787D01*
G03Y374072I-2015J1163D01*
G02X973542Y375613I1365J787D01*
G01X973561Y375647D01*
X973586Y375689D01*
G03X973561Y377972I-2040J1119D01*
G02X973542Y379513I1365J787D01*
G01X973561Y379547D01*
G03X973716Y379871I-2029J1170D01*
G03X973406Y382119I-2185J844D01*
G01X972954Y382721D01*
Y393761D01*
X968776Y397939D01*
Y404195D01*
X968931Y404350D01*
Y404437D01*
G01X971834Y407587D02*
Y407500D01*
X971989Y407345D01*
Y401508D01*
X971780Y401146D01*
G03X971711Y398969I2001J-1153D01*
G01X972109Y398165D01*
X976550Y393725D01*
Y378422D01*
X976290Y377971D01*
G03X976266Y375689I2016J-1162D01*
G01X976291Y375647D01*
X976310Y375613D01*
G02X976291Y374072I-1384J-754D01*
G03Y371746I2015J-1163D01*
G02Y370172I-1365J-787D01*
G01X976266Y370130D01*
G03X978255Y366684I2040J-1120D01*
G01X978365D01*
G02X979690Y364356I-59J-1575D01*
G01X979688Y364352D01*
X979671Y364322D01*
G03X978313Y361224I13361J-7703D01*
G01X978306Y361209D01*
G01X967871Y404437D02*
Y404350D01*
X968026Y404195D01*
Y397628D01*
X972204Y393450D01*
Y382471D01*
X972805Y381669D01*
G02X973016Y380141I-1274J-955D01*
G02X972911Y379922I-1469J570D01*
G01X972886Y379880D01*
G03X972911Y377597I2040J-1119D01*
G02X972930Y376056I-1365J-787D01*
G01X972911Y376022D01*
X972886Y375980D01*
G03X972911Y373697I2040J-1119D01*
G02X972930Y372156I-1365J-787D01*
G01X972911Y372122D01*
G03X972886Y369839I2015J-1164D01*
G01X972911Y369797D01*
G02Y368223I-1365J-787D01*
G03X974841Y364735I2015J-1163D01*
G01X974970D01*
G02X976291Y362372I-44J-1575D01*
G03X976266Y360089I2015J-1164D01*
G01X976291Y360047D01*
X976310Y360013D01*
G02X976291Y358472I-1384J-754D01*
G03X976266Y356189I2015J-1164D01*
G01X976291Y356147D01*
X976310Y356113D01*
G02X976291Y354572I-1384J-754D01*
G03X978049Y351097I2015J-1163D01*
G01X978306Y350840D01*
Y349509D01*
G01X974926Y351460D02*
X972977Y354081D01*
X972911Y354197D01*
G02X972886Y356480I2015J1164D01*
G01X972911Y356522D01*
X972930Y356556D01*
G03X972911Y358097I-1384J754D01*
G02X972886Y360380I2015J1164D01*
G01X972911Y360422D01*
X972930Y360456D01*
G03X971605Y362784I-1384J753D01*
G01X971476D01*
G02X969531Y366272I70J2325D01*
G03X969550Y367813I-1365J787D01*
G01X969531Y367847D01*
G02X969506Y370130I2015J1164D01*
G01X969531Y370172D01*
G03Y371746I-1365J787D01*
G02Y374072I2015J1163D01*
G03X969550Y375613I-1365J787D01*
G01X969531Y375647D01*
X969506Y375689D01*
G02X969531Y377972I2040J1119D01*
G03X969550Y379513I-1365J787D01*
G01X969531Y379547D01*
X969506Y379589D01*
G02X969531Y381872I2040J1119D01*
G03Y383446I-1365J787D01*
G02Y385772I2015J1163D01*
G03X969550Y387313I-1365J787D01*
G01X969531Y387347D01*
X969506Y387389D01*
G02X969531Y389672I2040J1119D01*
G01X969534Y389676D01*
G03X968191Y392034I-1343J797D01*
G01X968096D01*
G02X966151Y393197I70J2325D01*
G01X965825Y393762D01*
X963702Y395885D01*
Y400943D01*
X962707Y401938D01*
G01X974926Y359260D02*
X973627Y362259D01*
X973561Y362372D01*
G03X971631Y363534I-2015J-1163D01*
G01X971502D01*
G02X970181Y365897I44J1575D01*
G03Y368223I-2015J1163D01*
G02Y369797I1365J787D01*
G01X970206Y369839D01*
G03X970181Y372122I-2040J1119D01*
G01X970162Y372156D01*
G02X970181Y373697I1384J754D01*
G03X970206Y375980I-2015J1164D01*
G01X970181Y376022D01*
X970162Y376056D01*
G02X970181Y377597I1384J754D01*
G03X970206Y379880I-2015J1164D01*
G01X970181Y379922D01*
X970162Y379956D01*
G02X970181Y381497I1384J754D01*
G01X970206Y381539D01*
G03X970181Y383822I-2040J1119D01*
G01X970162Y383856D01*
G02X970181Y385397I1384J754D01*
G03X970206Y387680I-2015J1164D01*
G01X970181Y387722D01*
X970162Y387756D01*
G02X970181Y389297I1384J754D01*
G01X970187Y389306D01*
G03X968258Y392785I-1929J1205D01*
G01X968095D01*
G02X966801Y393572I71J1574D01*
G01X966799Y393571D01*
X966424Y394221D01*
X964450Y396195D01*
Y400988D01*
X965276Y401814D01*
G01X971546Y353409D02*
Y354740D01*
X971289Y354997D01*
G02X969531Y358472I257J2312D01*
G03X968210Y360835I-1365J788D01*
G01X968081D01*
G02X966126Y364280I85J2325D01*
G01X966151Y364322D01*
X966170Y364356D01*
G03X966151Y365897I-1384J754D01*
G02Y368223I2015J1163D01*
G03Y369797I-1365J787D01*
G01X966126Y369839D01*
G02X966151Y372122I2040J1119D01*
G01X966170Y372156D01*
G03X966151Y373697I-1384J754D01*
G02X966126Y375980I2015J1164D01*
G01X966151Y376022D01*
X966170Y376056D01*
G03X966151Y377597I-1384J754D01*
G02X966126Y379880I2015J1164D01*
G01X966151Y379922D01*
X966170Y379956D01*
G03X966151Y381497I-1384J754D01*
G02X966126Y383780I2015J1164D01*
G01X966151Y383822D01*
X966170Y383856D01*
G03X966151Y385397I-1384J754D01*
G02X966126Y387680I2015J1164D01*
G01X966151Y387722D01*
X966170Y387756D01*
G03X964845Y390084I-1384J753D01*
G01X963213D01*
X959102Y394195D01*
Y398034D01*
X957579Y399557D01*
G01X971546Y357309D02*
Y355978D01*
X971318Y355750D01*
G02X970181Y358097I228J1559D01*
G03X968236Y361585I-2015J1163D01*
G01X968107D01*
G02X966782Y363913I59J1575D01*
G01X966801Y363947D01*
X966826Y363989D01*
G03X966801Y366272I-2040J1119D01*
G02X966782Y367813I1365J787D01*
G01X966801Y367847D01*
G03X966826Y370130I-2015J1164D01*
G01X966801Y370172D01*
G02Y371746I1365J787D01*
G03Y374072I-2015J1163D01*
G02X966782Y375613I1365J787D01*
G01X966801Y375647D01*
X966826Y375689D01*
G03X966801Y377972I-2040J1119D01*
G02X966782Y379513I1365J787D01*
G01X966801Y379547D01*
X966826Y379589D01*
G03X966801Y381872I-2040J1119D01*
G02X966782Y383413I1365J787D01*
G01X966801Y383447D01*
X966826Y383489D01*
G03X966801Y385772I-2040J1119D01*
G02X966782Y387313I1365J787D01*
G01X966801Y387347D01*
X966826Y387389D01*
G03X964858Y390835I-2040J1120D01*
G01X963525D01*
X959853Y394507D01*
Y400093D01*
X960157Y400397D01*
G01X964786Y349509D02*
X966356Y347939D01*
X972328D01*
X974276Y345991D01*
X975699D01*
X976886Y347178D01*
X979849D01*
X981036Y345991D01*
X982459D01*
X983646Y347178D01*
X986609D01*
X987796Y345991D01*
X989096D01*
X990283Y347178D01*
X993369D01*
X994556Y345991D01*
X995856D01*
X997043Y347178D01*
X999824D01*
X1001017Y345985D01*
X1002024D01*
G03X1003330Y346772I-59J1575D01*
G02X1005260Y347934I2015J-1163D01*
G01X1005389D01*
G03X1006710Y348722I-44J1575D01*
G02X1008655Y349885I2015J-1162D01*
G01X1008784D01*
G03X1010090Y350672I-59J1575D01*
G02X1012020Y351834I2015J-1163D01*
G01X1012149D01*
G03X1013470Y352622I-44J1575D01*
G02X1015415Y353785I2015J-1162D01*
G01X1015544D01*
G03X1016850Y354572I-59J1575D01*
G02X1018780Y355734I2015J-1163D01*
G01X1018950D01*
G02X1020880Y354572I-85J-2325D01*
G03X1023610I1365J788D01*
G02X1025540Y355734I2015J-1163D01*
G01X1025710D01*
G02X1027640Y354572I-85J-2325D01*
G03X1028946Y353785I1365J788D01*
G01X1029064D01*
G03X1030370Y354572I-59J1575D01*
G02X1032300Y355734I2015J-1163D01*
G01X1032429D01*
G03X1033750Y356522I-44J1575D01*
G02X1035695Y357685I2015J-1162D01*
G01X1035835D01*
G02X1037780Y356522I-70J-2325D01*
G03X1040496Y356499I1365J787D01*
G01X1040509Y356522D01*
G02X1042454Y357685I2015J-1162D01*
G01X1042594D01*
G02X1044539Y356522I-70J-2325D01*
G03X1047269I1365J787D01*
G02X1049214Y357685I2015J-1162D01*
G01X1049354D01*
G02X1051299Y356522I-70J-2325D01*
G03X1052620Y355734I1365J787D01*
G01X1056134D01*
X1058121Y357721D01*
X1067729D01*
X1070124Y360116D01*
X1074623D01*
X1075182Y359557D01*
G03X1076658Y358921I1537J1536D01*
G01X1076787D01*
G02X1078717Y357759I-85J-2325D01*
G03X1081447I1365J788D01*
G01X1081472Y357801D01*
G02X1085477Y357760I1990J-1205D01*
G01X1085509Y357704D01*
G03X1088206Y357759I1332J843D01*
G02X1092236I2015J-1163D01*
G03X1094966I1365J788D01*
G02X1098996I2015J-1163D01*
G03X1101726I1365J788D01*
G02X1105756I2015J-1163D01*
G03X1108486I1365J788D01*
G02X1112516I2015J-1163D01*
G03X1113822Y356972I1365J788D01*
G01X1115418D01*
X1116611Y358165D01*
X1117911D01*
X1119072Y357004D01*
Y353997D01*
X1119991Y353078D01*
X1121420D01*
X1123371Y351127D01*
X1123916D01*
X1125865Y349178D01*
X1128936D01*
X1130123Y350365D01*
X1131437D01*
X1132624Y349178D01*
X1135696D01*
X1136883Y350365D01*
X1138197D01*
X1139384Y349178D01*
X1142456D01*
X1143643Y350365D01*
X1144957D01*
X1146144Y349178D01*
X1149216D01*
X1150403Y350365D01*
X1151717D01*
X1152904Y349178D01*
X1169495D01*
X1170682Y350365D01*
X1171996D01*
X1173948Y352317D01*
X1176259D01*
X1177449Y351127D01*
X1178749D01*
X1179109Y351487D01*
X1179998D01*
X1180828Y352317D01*
X1182250D01*
X1184202Y350365D01*
X1185516D01*
X1186703Y349178D01*
X1189775D01*
X1190962Y350365D01*
X1192276D01*
X1193601Y349040D01*
X1195608D01*
G01X964786Y353409D02*
X963217Y351840D01*
Y348859D01*
X968036Y344040D01*
X972196D01*
X973385Y345229D01*
X976467D01*
X977656Y344040D01*
X978956D01*
X980145Y345229D01*
X983006D01*
X984195Y344040D01*
X985716D01*
X986905Y345229D01*
X989987D01*
X991176Y344040D01*
X992476D01*
X993665Y345229D01*
X996747D01*
X997936Y344040D01*
X999236D01*
X1000431Y345235D01*
X1002050D01*
G03X1003980Y346397I-85J2325D01*
G02X1005286Y347184I1365J-788D01*
G01X1005415D01*
G03X1007360Y348347I-70J2325D01*
G02X1008681Y349135I1365J-787D01*
G01X1008810D01*
G03X1010740Y350297I-85J2325D01*
G02X1012046Y351084I1365J-788D01*
G01X1012175D01*
G03X1014120Y352247I-70J2325D01*
G02X1015441Y353035I1365J-787D01*
G01X1015570D01*
G03X1017500Y354197I-85J2325D01*
G02X1018806Y354984I1365J-788D01*
G01X1018924D01*
G02X1020230Y354197I-59J-1575D01*
G03X1024260I2015J1163D01*
G02X1025566Y354984I1365J-788D01*
G01X1025684D01*
G02X1026990Y354197I-59J-1575D01*
G03X1028920Y353035I2015J1163D01*
G01X1029090D01*
G03X1031020Y354197I-85J2325D01*
G02X1032326Y354984I1365J-788D01*
G01X1032455D01*
G03X1034400Y356147I-70J2325D01*
G02X1037130I1365J-787D01*
G03X1039075Y354984I2015J1162D01*
G01X1039215D01*
G03X1041160Y356147I-70J2325D01*
G01X1041173Y356170D01*
G02X1043889Y356147I1351J-810D01*
G03X1045834Y354984I2015J1162D01*
G01X1045974D01*
G03X1047919Y356147I-70J2325D01*
G02X1050649I1365J-787D01*
G03X1052594Y354984I2015J1162D01*
G01X1056445D01*
X1058432Y356971D01*
X1074584D01*
X1075784Y358171D01*
X1076761D01*
G02X1078067Y357384I-59J-1575D01*
G03X1082097I2015J1163D01*
G02X1084794Y357439I1365J-788D01*
G01X1084826Y357383D01*
G03X1088831Y357342I2015J1164D01*
G01X1088856Y357384D01*
G02X1091586I1365J-788D01*
G03X1095616I2015J1163D01*
G02X1098346I1365J-788D01*
G03X1102376I2015J1163D01*
G02X1105106I1365J-788D01*
G03X1109136I2015J1163D01*
G02X1111866I1365J-788D01*
G03X1113796Y356222I2015J1163D01*
G01X1114525D01*
X1115692Y355055D01*
Y352046D01*
X1116611Y351127D01*
X1118042D01*
X1119991Y349178D01*
X1121420D01*
X1123371Y347227D01*
X1125561D01*
X1126750Y348416D01*
X1128941D01*
X1130130Y347227D01*
X1131430D01*
X1132619Y348416D01*
X1134810D01*
X1136012Y347214D01*
X1136578D01*
X1136579Y347215D01*
X1139069D01*
X1140282Y348428D01*
X1142331D01*
X1143106Y347653D01*
G01X1205683Y338233D02*
X1203052Y340864D01*
X1200900D01*
X1199227Y339191D01*
X1197561D01*
X1195740Y341012D01*
X1194238D01*
X1192300Y342950D01*
X1190771D01*
X1189203Y344516D01*
X1187161D01*
X1185748Y343103D01*
X1183930D01*
X1182433Y344600D01*
X1180614D01*
X1178614Y346600D01*
X1177300D01*
X1175978Y345278D01*
X1173222D01*
X1172035Y346465D01*
X1170360D01*
X1169079Y345184D01*
X1167978D01*
X1167044Y344250D01*
X1158100D01*
X1157400Y344950D01*
X1153600D01*
X1152085Y346465D01*
X1150410D01*
X1148995Y345050D01*
X1146365D01*
X1144950Y346465D01*
X1143650D01*
X1142385Y345200D01*
X1140348D01*
X1139083Y346465D01*
X1136890D01*
X1135375Y344950D01*
X1133150D01*
X1131635Y346465D01*
X1130130D01*
X1128181Y344516D01*
X1126750D01*
X1125561Y343327D01*
X1123371D01*
X1121420Y345278D01*
X1118172D01*
X1115000Y348450D01*
X1109774D01*
X1109052Y349172D01*
X1107062D01*
G02X1105756Y349959I59J1575D01*
G03X1103826Y351121I-2015J-1163D01*
G01X1103697D01*
G02X1102376Y351909I44J1575D01*
G03X1100431Y353072I-2015J-1162D01*
G01X1100302D01*
G02X1098996Y353859I59J1575D01*
G03X1097066Y355021I-2015J-1163D01*
G01X1096896D01*
G03X1094966Y353859I85J-2325D01*
G02X1092236I-1365J788D01*
G03X1088206I-2015J-1163D01*
G02X1085509Y353804I-1365J788D01*
G01X1085477Y353860D01*
G03X1081472Y353901I-2015J-1164D01*
G01X1081447Y353859D01*
G02X1078717I-1365J788D01*
G03X1074687I-2015J-1163D01*
G01X1074412Y353383D01*
X1073745Y352997D01*
X1067759D01*
X1066974Y353782D01*
X1062786D01*
X1062785Y353783D01*
X1059131D01*
X1057183Y351835D01*
X1052664D01*
X1052663Y351834D01*
X1052620D01*
G02X1051299Y352622I44J1575D01*
G03X1049354Y353785I-2015J-1162D01*
G01X1049214D01*
G03X1047269Y352622I70J-2325D01*
G02X1044539I-1365J787D01*
G03X1042594Y353785I-2015J-1162D01*
G01X1042454D01*
G03X1040509Y352622I70J-2325D01*
G01X1040496Y352599D01*
G02X1037780Y352622I-1351J810D01*
G03X1035835Y353785I-2015J-1162D01*
G01X1035695D01*
G03X1033750Y352622I70J-2325D01*
G02X1032429Y351834I-1365J787D01*
G01X1032300D01*
G03X1030370Y350672I85J-2325D01*
G02X1029064Y349885I-1365J788D01*
G01X1028946D01*
G02X1027640Y350672I59J1575D01*
G03X1025710Y351834I-2015J-1163D01*
G01X1025540D01*
G03X1023610Y350672I85J-2325D01*
G02X1022304Y349885I-1365J788D01*
G01X1022186D01*
G02X1020880Y350672I59J1575D01*
G03X1018950Y351834I-2015J-1163D01*
G01X1018780D01*
G03X1016850Y350672I85J-2325D01*
G02X1015544Y349885I-1365J788D01*
G01X1015415D01*
G03X1013470Y348722I70J-2325D01*
G02X1012149Y347934I-1365J787D01*
G01X1012020D01*
G03X1010090Y346772I85J-2325D01*
G02X1008784Y345985I-1365J788D01*
G01X1008655D01*
G03X1006710Y344822I70J-2325D01*
G02X1005389Y344034I-1365J787D01*
G01X1005260D01*
G03X1003330Y342872I85J-2325D01*
G02X1002024Y342085I-1365J788D01*
G01X1001321D01*
X1000128Y343278D01*
X997167D01*
X995980Y342091D01*
X994556D01*
X993369Y343278D01*
X990406D01*
X989219Y342091D01*
X987528D01*
X986341Y343278D01*
X984416D01*
X983229Y342091D01*
X980143D01*
X978956Y343278D01*
X976887D01*
X975700Y342091D01*
X974276D01*
X973077Y343290D01*
X965676D01*
X961406Y347560D01*
G01X978306Y357309D02*
X978313Y357324D01*
G02X979671Y360422I14719J-4605D01*
G03X979832Y361601I-1365J787D01*
G02X980321Y363946I3808J429D01*
G01X980330Y363961D01*
X980332Y363965D01*
X980334Y363968D01*
X980340Y363978D01*
X980344Y363985D01*
X980346Y363989D01*
G03X978357Y367435I-2040J1120D01*
G01X978262D01*
G02X976941Y369797I44J1575D01*
G01X976966Y369839D01*
G03X976941Y372122I-2040J1119D01*
G01X976922Y372156D01*
G02X976941Y373697I1384J754D01*
G03X976966Y375980I-2015J1164D01*
G01X976941Y376022D01*
G02Y377596I1365J787D01*
G01X977300Y378218D01*
Y394036D01*
X972727Y398609D01*
X972699Y398666D01*
X972384Y399302D01*
G02X972430Y400771I1397J691D01*
G01X972739Y401307D01*
Y407345D01*
X972894Y407500D01*
Y407587D01*
G01X985066Y353409D02*
Y352209D01*
X984346Y351489D01*
X983798D01*
X983116Y352171D01*
Y354081D01*
X984196Y355161D01*
Y355771D01*
X983346Y356621D01*
Y357742D01*
X983701Y358097D01*
G02X985007Y358884I1365J-788D01*
G01X985008D01*
G03X985812Y359349I0J928D01*
G01X985894Y359491D01*
Y359680D01*
X986380Y360334D01*
X986450Y360456D01*
G03X986431Y361997I-1384J754D01*
G02X986406Y364280I2015J1164D01*
G01X986431Y364322D01*
X986450Y364356D01*
G03X986431Y365897I-1384J754D01*
G02Y368223I2015J1163D01*
G03X985137Y370584I-1365J787D01*
G01X984981D01*
G02X983051Y374072I85J2325D01*
G03X983070Y375613I-1365J787D01*
G01X983051Y375647D01*
X983026Y375689D01*
G02X983051Y377972I2040J1119D01*
G03X983070Y379513I-1365J787D01*
G01X982688Y380197D01*
Y400109D01*
X981656Y401141D01*
Y405793D01*
X980758Y406691D01*
G01X985066Y357309D02*
X985364Y357607D01*
X986162D01*
X986870Y358315D01*
Y359736D01*
X987015Y359931D01*
X987081Y360047D01*
X987106Y360089D01*
G03X987081Y362372I-2040J1119D01*
G02X987062Y363913I1365J787D01*
G01X987081Y363947D01*
X987106Y363989D01*
G03X987081Y366272I-2040J1119D01*
G02X987062Y367813I1365J787D01*
G01X987081Y367847D01*
G03X985136Y371335I-2015J1163D01*
G01X984995D01*
G02X983701Y373697I71J1574D01*
G03X983726Y375980I-2015J1164D01*
G01X983701Y376022D01*
X983682Y376056D01*
G02X983701Y377597I1384J754D01*
G03X983726Y379880I-2015J1164D01*
G01X983436Y380396D01*
Y400419D01*
X982404Y401451D01*
Y405787D01*
X983308Y406691D01*
G01X980114Y355474D02*
X980112Y359184D01*
G02X980606Y360408I1574J77D01*
G02X982420Y361767I5140J-4970D01*
G03X983051Y362372I-723J1386D01*
G03X983070Y363913I-1365J787D01*
G01X983051Y363947D01*
X983026Y363989D01*
G02X983051Y366272I2040J1119D01*
G03X981757Y368634I-1365J788D01*
G01X981616D01*
G02X979671Y372122I70J2325D01*
G01X979690Y372156D01*
G03X979671Y373697I-1384J754D01*
G02X979646Y375980I2015J1164D01*
G01X979671Y376022D01*
X979690Y376056D01*
G03X979671Y377597I-1384J754D01*
G01X979109Y378570D01*
Y379930D01*
X979588Y380409D01*
Y396199D01*
X976638Y399149D01*
Y405711D01*
X975658Y406691D01*
G01X981686Y359260D02*
G03X983701Y361997I-11295J10426D01*
G03X983726Y364280I-2015J1164D01*
G01X983701Y364322D01*
X983682Y364356D01*
G02X983701Y365897I1384J754D01*
G03X981771Y369385I-2015J1163D01*
G01X981615D01*
G02X980321Y371746I71J1574D01*
G03Y374072I-2015J1163D01*
G02X980302Y375613I1365J787D01*
G01X980321Y375647D01*
X980346Y375689D01*
G03X980321Y377972I-2040J1119D01*
G01X979857Y378774D01*
Y379620D01*
X980336Y380099D01*
Y396510D01*
X980117Y396729D01*
Y396728D01*
X977386Y399459D01*
Y405869D01*
X978208Y406691D01*
G01X991826Y357309D02*
Y358674D01*
X989554Y360946D01*
Y361710D01*
G02X989811Y362372I2272J-501D01*
G03X989830Y363913I-1365J787D01*
G01X989811Y363947D01*
X989786Y363989D01*
G02X989811Y366272I2040J1119D01*
G03X989830Y367813I-1365J787D01*
G01X989811Y367847D01*
G02X989786Y370130I2015J1164D01*
G01X989811Y370172D01*
G03Y371746I-1365J787D01*
G02Y374072I2015J1163D01*
G03X989830Y375613I-1365J787D01*
G01X989811Y375647D01*
X989786Y375689D01*
G02X989811Y377972I2040J1119D01*
G03X989830Y379513I-1365J787D01*
G01X989811Y379547D01*
X989786Y379589D01*
G02X989811Y381872I2040J1119D01*
G03X989830Y383413I-1365J787D01*
G01X989811Y383447D01*
X989786Y383489D01*
G02X989811Y385772I2040J1119D01*
G03X989830Y387313I-1365J787D01*
G01X989811Y387347D01*
G03X989479Y387778I-1630J-912D01*
G01X989300Y387957D01*
Y390400D01*
X989100Y390600D01*
Y397100D01*
X987400Y398800D01*
Y399687D01*
G01X991826Y369010D02*
G02X992300Y370800I2254J361D01*
G03X993191Y372122I-7456J5987D01*
G01X993210Y372156D01*
G03X993191Y373697I-1384J754D01*
G02X993166Y375980I2015J1164D01*
G01X993191Y376022D01*
X993210Y376056D01*
G03X993191Y377597I-1384J754D01*
G02X993166Y379880I2015J1164D01*
G01X993191Y379922D01*
X993210Y379956D01*
G03X993191Y381497I-1384J754D01*
G02X993166Y383780I2015J1164D01*
G01X993191Y383822D01*
X993210Y383856D01*
G03X993191Y385397I-1384J754D01*
G02X993166Y387680I2015J1164D01*
G01X993191Y387722D01*
X993210Y387756D01*
G03X993191Y389297I-1384J754D01*
G02X993081Y391409I2015J1164D01*
G01Y391571D01*
G02X993300Y392100I748J0D01*
G01Y397000D01*
X991400Y398900D01*
Y399889D01*
G01X991826Y361209D02*
X990529Y364205D01*
X990442Y364356D01*
G02X990461Y365897I1384J754D01*
G03Y368223I-2015J1163D01*
G02Y369797I1365J787D01*
G01X990486Y369839D01*
G03X990461Y372122I-2040J1119D01*
G01X990442Y372156D01*
G02X990461Y373697I1384J754D01*
G03X990486Y375980I-2015J1164D01*
G01X990461Y376022D01*
X990442Y376056D01*
G02X990461Y377597I1384J754D01*
G03X990486Y379880I-2015J1164D01*
G01X990461Y379922D01*
X990442Y379956D01*
G02X990461Y381497I1384J754D01*
G03X990486Y383780I-2015J1164D01*
G01X990461Y383822D01*
X990442Y383856D01*
G02X990461Y385397I1384J754D01*
G03X990486Y387680I-2015J1164D01*
G01X990461Y387722D01*
G02X990153Y388797I1886J1122D01*
G01Y390647D01*
X989900Y390900D01*
Y398154D01*
X989400Y398654D01*
Y399607D01*
G01X995400Y398948D02*
Y393264D01*
X996590Y391213D01*
G02X996571Y389672I-1384J-754D01*
G03X996546Y387389I2015J-1164D01*
G01X996571Y387347D01*
X996590Y387313D01*
G02X996571Y385772I-1384J-754D01*
G03X996546Y383489I2015J-1164D01*
G01X996571Y383447D01*
X996590Y383413D01*
G02X996571Y381872I-1384J-754D01*
G03X996546Y379589I2015J-1164D01*
G01X996571Y379547D01*
X996590Y379513D01*
G02X996571Y377972I-1384J-754D01*
G03X996546Y375689I2015J-1164D01*
G01X996571Y375647D01*
X996590Y375613D01*
G02X996571Y374072I-1384J-754D01*
G03Y371746I2015J-1163D01*
G02Y370172I-1365J-787D01*
G01X996546Y370130D01*
G03X996571Y367847I2040J-1119D01*
G01X996590Y367813D01*
G02X996571Y366272I-1384J-754D01*
G03X996546Y363989I2015J-1164D01*
G01X996571Y363947D01*
X996590Y363913D01*
G02X996571Y362372I-1384J-754D01*
G03X996546Y360089I2015J-1164D01*
G01X996571Y360047D01*
X996590Y360013D01*
G02X996571Y358472I-1384J-754D01*
G03X996314Y357811I2015J-1164D01*
G01X995206Y355360D01*
G01Y363160D02*
X993500Y364866D01*
Y367506D01*
X993841Y367847D01*
G03X993866Y370130I-2015J1164D01*
G01X993841Y370172D01*
G02Y371746I1365J787D01*
G03Y374072I-2015J1163D01*
G02X993822Y375613I1365J787D01*
G01X993841Y375647D01*
X993866Y375689D01*
G03X993841Y377972I-2040J1119D01*
G02X993822Y379513I1365J787D01*
G01X993841Y379547D01*
X993866Y379589D01*
G03X993841Y381872I-2040J1119D01*
G02X993822Y383413I1365J787D01*
G01X993841Y383447D01*
X993866Y383489D01*
G03X993841Y385772I-2040J1119D01*
G02X993822Y387313I1365J787D01*
G01X993841Y387347D01*
X993866Y387389D01*
G03X993841Y389672I-2040J1119D01*
G02X993822Y391213I1365J787D01*
G01X994200Y391881D01*
Y397960D01*
X993400Y398760D01*
Y399647D01*
G01X998586Y240309D02*
Y239413D01*
X1000500Y237499D01*
Y235500D01*
X999500Y234500D01*
X998636D01*
X998163Y234027D01*
G03X997011Y232463I423J-1518D01*
G01X996955Y231591D01*
X996740Y230066D01*
X996546Y229730D01*
G03X996571Y227447I2040J-1119D01*
G01X996590Y227413D01*
G02X996571Y225872I-1384J-754D01*
G03X996546Y223589I2015J-1164D01*
G01X996571Y223547D01*
X996590Y223513D01*
G02X996571Y221972I-1384J-754D01*
G03X996546Y219689I2015J-1164D01*
G01X996571Y219647D01*
X996590Y219613D01*
G02X996571Y218072I-1384J-754D01*
G03X996546Y215789I2015J-1164D01*
G01X996571Y215747D01*
X996590Y215713D01*
G02X996571Y214172I-1384J-754D01*
G03X996546Y211889I2015J-1164D01*
G01X996571Y211847D01*
X996590Y211813D01*
G02X996571Y210272I-1384J-754D01*
G03Y207946I2015J-1163D01*
G02Y206372I-1365J-787D01*
G01X996546Y206330D01*
G03X996571Y204047I2040J-1119D01*
G01X996906Y203468D01*
Y201105D01*
G01X998906Y200994D02*
Y201759D01*
X997221Y204423D01*
G02Y205997I1365J787D01*
G01X997246Y206039D01*
G03X997221Y208322I-2040J1119D01*
G01X997202Y208356D01*
G02X997221Y209897I1384J754D01*
G03X997246Y212180I-2015J1164D01*
G01X997221Y212222D01*
X997202Y212256D01*
G02X997221Y213797I1384J754D01*
G03X997246Y216080I-2015J1164D01*
G01X997221Y216122D01*
X997202Y216156D01*
G02X997221Y217697I1384J754D01*
G03X997246Y219980I-2015J1164D01*
G01X997221Y220022D01*
X997202Y220056D01*
G02X997221Y221597I1384J754D01*
G03X997246Y223880I-2015J1164D01*
G01X997221Y223922D01*
X997202Y223956D01*
G02X997221Y225497I1384J754D01*
G03Y227823I-2015J1163D01*
G02Y229397I1365J787D01*
G01X997383Y229678D01*
X998421Y230516D01*
X999408Y231166D01*
G03X999950Y231722I-822J1343D01*
G01X1000013Y231832D01*
X1001965Y234460D01*
G01X1022245D02*
X1021091Y235126D01*
X1020781Y235042D01*
G03X1020670Y234488I1464J-581D01*
G03X1022201Y232886I1575J-27D01*
G01X1022330D01*
G02X1024260Y229398I-85J-2325D01*
G03Y227824I1365J-787D01*
G02Y225498I-2015J-1163D01*
G03Y223924I1365J-787D01*
G02Y221598I-2015J-1163D01*
G03Y220024I1365J-787D01*
G02Y217698I-2015J-1163D01*
G03Y216124I1365J-787D01*
G02Y213798I-2015J-1163D01*
G03Y212224I1365J-787D01*
G02Y209898I-2015J-1163D01*
G03Y208324I1365J-787D01*
G01Y208323D01*
G02X1024255Y205991I-2015J-1162D01*
G01X1024006Y205578D01*
Y204394D01*
X1026300Y202100D01*
Y192797D01*
X1027881Y191216D01*
Y189544D01*
X1028036Y189389D01*
Y189302D01*
G01X1015485Y234460D02*
X1014331Y235126D01*
X1014021Y235042D01*
G03X1013910Y234488I1464J-581D01*
G03X1015441Y232886I1575J-27D01*
G01X1015570D01*
G02X1017500Y229398I-85J-2325D01*
G03Y227824I1365J-787D01*
G02Y225498I-2015J-1163D01*
G03Y223924I1365J-787D01*
G02Y221598I-2015J-1163D01*
G03Y220024I1365J-787D01*
G02Y217698I-2015J-1163D01*
G03Y216124I1365J-787D01*
G02Y213798I-2015J-1163D01*
G03X1017289Y212992I1365J-788D01*
G01X1017288Y212983D01*
Y205771D01*
X1017900Y205159D01*
Y203197D01*
X1021231Y199866D01*
Y188930D01*
X1021386Y188775D01*
Y188688D01*
G01X1024736Y189209D02*
Y189296D01*
X1024556Y189476D01*
Y191242D01*
X1023906Y191892D01*
Y200844D01*
X1020980Y203770D01*
Y206199D01*
X1020880Y206373D01*
G02Y207949I1365J788D01*
G01Y207948D01*
G03Y210274I-2015J1163D01*
G02Y211848I1365J787D01*
G03Y214174I-2015J1163D01*
G02Y215748I1365J787D01*
G03Y218074I-2015J1163D01*
G02Y219648I1365J787D01*
G03Y221974I-2015J1163D01*
G02Y223548I1365J787D01*
G03Y225874I-2015J1163D01*
G02Y227448I1365J787D01*
G03X1021192Y228601I-2015J1164D01*
G02X1021832Y230146I2185J0D01*
G01X1022245Y230559D01*
G01X1015485D02*
X1015072Y230146D01*
G03X1014432Y228601I1545J-1545D01*
G02X1014120Y227448I-2327J11D01*
G03Y225874I1365J-787D01*
G02Y223548I-2015J-1163D01*
G03Y221974I1365J-787D01*
G02Y219648I-2015J-1163D01*
G03Y218074I1365J-787D01*
G02Y215748I-2015J-1163D01*
G03Y214174I1365J-787D01*
G01X1014637Y213281D01*
Y204939D01*
X1013866Y203608D01*
Y202390D01*
X1017931Y198325D01*
Y196461D01*
X1018086Y196306D01*
Y196219D01*
G01X1018865Y236409D02*
X1019313Y235960D01*
G02X1019918Y234501I-1459J-1460D01*
G03X1022160Y232136I2327J-40D01*
G01X1022289D01*
G02X1023610Y229774I-44J-1575D01*
G03Y227448I2015J-1163D01*
G02Y225874I-1365J-787D01*
G03Y223548I2015J-1163D01*
G02Y221974I-1365J-787D01*
G03Y219648I2015J-1163D01*
G02Y218074I-1365J-787D01*
G03Y215748I2015J-1163D01*
G02Y214174I-1365J-787D01*
G03Y211848I2015J-1163D01*
G02Y210274I-1365J-787D01*
G03Y207948I2015J-1163D01*
G02Y206374I-1365J-787D01*
G01X1023256Y205787D01*
Y204083D01*
X1025550Y201789D01*
Y192486D01*
X1027131Y190905D01*
Y189544D01*
X1026976Y189389D01*
Y189302D01*
G01X1012105Y236409D02*
X1012553Y235960D01*
G02X1013158Y234501I-1459J-1460D01*
G03X1015400Y232136I2327J-40D01*
G01X1015529D01*
G02X1016850Y229774I-44J-1575D01*
G03Y227448I2015J-1163D01*
G02Y225874I-1365J-787D01*
G03Y223548I2015J-1163D01*
G02Y221974I-1365J-787D01*
G03Y219648I2015J-1163D01*
G02Y218074I-1365J-787D01*
G03Y215748I2015J-1163D01*
G02Y214174I-1365J-787D01*
G03X1016538Y212983I2015J-1164D01*
G01Y205460D01*
X1017150Y204848D01*
Y202886D01*
X1020481Y199555D01*
Y188887D01*
X1020326Y188732D01*
Y188688D01*
G01X1023676Y189367D02*
X1023806Y189497D01*
Y190931D01*
X1023156Y191581D01*
Y200533D01*
X1020230Y203459D01*
Y205998D01*
G02Y208324I2015J1163D01*
G03Y209898I-1365J787D01*
G02Y212224I2015J1163D01*
G03Y213798I-1365J787D01*
G02Y216124I2015J1163D01*
G03Y217698I-1365J787D01*
G02Y220024I2015J1163D01*
G03Y221598I-1365J787D01*
G02Y223924I2015J1163D01*
G03Y225498I-1365J787D01*
G02Y227824I2015J1163D01*
G03X1020440Y228604I-1366J786D01*
G03X1020329Y229192I-1576J7D01*
G01X1020019Y229276D01*
X1018865Y228610D01*
G01X1012105D02*
X1013259Y229276D01*
X1013569Y229192D01*
G02X1013680Y228604I-1465J-581D01*
G02X1013470Y227824I-1576J6D01*
G03Y225498I2015J-1163D01*
G02Y223924I-1365J-787D01*
G03Y221598I2015J-1163D01*
G02Y220024I-1365J-787D01*
G03Y217698I2015J-1163D01*
G02Y216124I-1365J-787D01*
G03Y213798I2015J-1163D01*
G01X1013887Y213079D01*
Y205141D01*
X1013116Y203810D01*
Y202079D01*
X1017181Y198014D01*
Y196461D01*
X1017026Y196306D01*
Y196219D01*
G01X1008725Y242260D02*
X1010025Y239260D01*
X1010090Y239148D01*
G02Y237574I-1365J-787D01*
G03Y235248I2015J-1163D01*
G02Y233674I-1365J-787D01*
G03Y231348I2015J-1163D01*
G02Y229774I-1365J-787D01*
G03Y227448I2015J-1163D01*
G02Y225874I-1365J-787D01*
G03Y223548I2015J-1163D01*
G02Y221974I-1365J-787D01*
G03Y219648I2015J-1163D01*
G02Y218074I-1365J-787D01*
G03Y215748I2015J-1163D01*
G02Y214174I-1365J-787D01*
G03Y211848I2015J-1163D01*
G02Y210274I-1365J-787D01*
G03X1009426Y207795I4295J-2479D01*
G01Y201661D01*
X1012906Y198181D01*
Y196375D01*
G01X1012105Y240309D02*
X1010805Y237310D01*
X1010740Y237198D01*
G03Y235624I1365J-787D01*
G02Y233298I-2015J-1163D01*
G03Y231724I1365J-787D01*
G02Y229398I-2015J-1163D01*
G03Y227824I1365J-787D01*
G02Y225498I-2015J-1163D01*
G03Y223924I1365J-787D01*
G02Y221598I-2015J-1163D01*
G03Y220024I1365J-787D01*
G02Y217698I-2015J-1163D01*
G03Y216124I1365J-787D01*
G02Y213798I-2015J-1163D01*
G03Y212224I1365J-787D01*
G02Y209898I-2015J-1163D01*
G03X1010521Y209080I1419J-818D01*
G01Y202499D01*
X1014906Y198114D01*
Y196325D01*
G01X1010906Y191275D02*
Y197792D01*
X1008011Y200687D01*
Y207844D01*
G03X1007360Y210274I-4862J0D01*
G02Y211848I1365J787D01*
G03Y214174I-2017J1163D01*
G02Y215748I1365J787D01*
G03Y218074I-2015J1163D01*
G02Y219648I1365J787D01*
G03Y221974I-2015J1163D01*
G02Y223548I1365J787D01*
G03Y225874I-2015J1163D01*
G02Y227448I1365J787D01*
G01X1007425Y227560D01*
X1008725Y230559D01*
G01Y234460D02*
X1007676Y231881D01*
X1007360Y231348D01*
G03X1007160Y230379I1365J-787D01*
G02X1007028Y229289I-2329J-271D01*
G03X1006919Y228546I3470J-889D01*
G02X1006710Y227824I-1574J64D01*
G03Y225498I2015J-1163D01*
G02Y223924I-1365J-787D01*
G03Y221598I2015J-1163D01*
G02Y220024I-1365J-787D01*
G03Y217698I2015J-1163D01*
G02Y216124I-1365J-787D01*
G03Y213798I2015J-1163D01*
G02Y212224I-1364J-787D01*
G03Y209898I2015J-1163D01*
G02X1006971Y208923I-1691J-975D01*
G01Y199626D01*
X1009206Y197391D01*
Y192741D01*
X1008906Y192441D01*
Y191225D01*
G01X1005345Y228610D02*
X1004546Y226475D01*
X1003980Y225497D01*
G03X1003961Y223956I1365J-787D01*
G01X1003980Y223922D01*
X1004005Y223880D01*
G02X1003980Y221597I-2040J-1119D01*
G03X1003961Y220056I1365J-787D01*
G01X1003980Y220022D01*
X1004005Y219980D01*
G02X1003980Y217697I-2040J-1119D01*
G03X1003961Y216156I1365J-787D01*
G01X1003980Y216122D01*
X1004005Y216080D01*
G02X1003980Y213797I-2040J-1119D01*
G03X1003961Y212256I1365J-787D01*
G01X1003980Y212222D01*
X1004005Y212180D01*
G02X1003980Y209897I-2040J-1119D01*
G01X1003700Y209412D01*
Y204400D01*
X1006006Y202094D01*
Y192691D01*
X1006906Y191791D01*
Y191175D01*
G01X1005345Y236409D02*
X1006644Y233410D01*
X1006710Y233297D01*
G02X1006103Y231128I-1365J-787D01*
G01X1004818Y230293D01*
X1004142Y229678D01*
X1003980Y229397D01*
G03X1003770Y228648I1365J-787D01*
G01X1003710Y228047D01*
X1003540Y226696D01*
G02X1003330Y225872I-1575J-37D01*
G03X1003305Y223589I2015J-1164D01*
G01X1003330Y223547D01*
X1003349Y223513D01*
G02X1003330Y221972I-1384J-754D01*
G03X1003305Y219689I2015J-1164D01*
G01X1003330Y219647D01*
X1003349Y219613D01*
G02X1003330Y218072I-1384J-754D01*
G03X1003305Y215789I2015J-1164D01*
G01X1003330Y215747D01*
X1003349Y215713D01*
G02X1003330Y214172I-1384J-754D01*
G03X1003305Y211889I2015J-1164D01*
G01X1003330Y211847D01*
X1003349Y211813D01*
G02X1003330Y210273I-1384J-753D01*
G01X1002898Y209525D01*
Y203902D01*
X1004906Y201894D01*
Y190725D01*
G01X1000906Y200173D02*
Y201374D01*
X1000700Y201580D01*
Y207099D01*
G03X999950Y209896I-5592J0D01*
G02X999915Y212162I2015J1164D01*
G01X999950Y212222D01*
G03Y213796I-1364J787D01*
G02X999915Y216062I2015J1164D01*
G01X999950Y216122D01*
G03Y217696I-1364J787D01*
G02X999915Y219962I2015J1164D01*
G01X999950Y220022D01*
G03Y221596I-1364J787D01*
G02X999915Y223862I2015J1164D01*
G01X999950Y223922D01*
G03Y225496I-1364J787D01*
G02X999925Y227781I2015J1165D01*
G01X999950Y227823D01*
G03X1000063Y228063I-1363J788D01*
G01X1000172Y228364D01*
X1000390Y230566D01*
G02X1001389Y232025I1575J-7D01*
G01X1003151Y233362D01*
X1003330Y233672D01*
G03X1003349Y235213I-1365J787D01*
G01X1003330Y235247D01*
X1003305Y235289D01*
G02X1003330Y237572I2040J1119D01*
G03X1003349Y239113I-1365J787D01*
G01X1003262Y239264D01*
X1001965Y242260D01*
G01X1005345Y240309D02*
X1004046Y237310D01*
X1003980Y237197D01*
G03X1003961Y235656I1365J-787D01*
G01X1003980Y235622D01*
X1004005Y235580D01*
G02X1003980Y233297I-2040J-1119D01*
G03X1003775Y232643I1365J-787D01*
G01X1003583Y230484D01*
X1003466Y230008D01*
X1003330Y229772D01*
G02X1002852Y229248I-1430J825D01*
G01X1001136Y228035D01*
G03X1000601Y227448I1069J-1512D01*
G03Y225874I1364J-787D01*
G02Y223548I-2015J-1163D01*
G03Y221974I1364J-787D01*
G02Y219648I-2015J-1163D01*
G03Y218074I1364J-787D01*
G02Y215748I-2015J-1163D01*
G03Y214174I1364J-787D01*
G01X1000631Y214122D01*
X1000632Y214117D01*
G02X1000636Y211907I-2046J-1109D01*
G01X1000601Y211847D01*
X1000600D01*
G02X1000571Y211796I-2033J1122D01*
G03X1000599Y210272I1394J-737D01*
G01X1000850Y209837D01*
G02X1001800Y206284I-6168J-3553D01*
G01Y203600D01*
X1002906Y202494D01*
Y200493D01*
G01X1025625Y236409D02*
X1027430Y234604D01*
Y230599D01*
G03X1027640Y229772I1575J-40D01*
G01X1027665Y229730D01*
G02X1027640Y227447I-2040J-1119D01*
G01X1027621Y227413D01*
G03X1027640Y225872I1384J-754D01*
G02X1027665Y223589I-2015J-1164D01*
G01X1027640Y223547D01*
X1027621Y223513D01*
G03X1027640Y221972I1384J-754D01*
G02X1027665Y219689I-2015J-1164D01*
G01X1027640Y219647D01*
X1027621Y219613D01*
G03X1027640Y218072I1384J-754D01*
G02X1027665Y215789I-2015J-1164D01*
G01X1027640Y215747D01*
X1027621Y215713D01*
G03X1027640Y214172I1384J-754D01*
G02X1027665Y211889I-2015J-1164D01*
G01X1027640Y211847D01*
X1027621Y211813D01*
G03X1027640Y210272I1384J-754D01*
G02Y207946I-2015J-1163D01*
G03X1027621Y206407I1365J-786D01*
G01X1027640Y206373D01*
G02X1027913Y205805I-3154J-1865D01*
G01X1029300Y204418D01*
Y200201D01*
X1032240Y197261D01*
Y190375D01*
G01X1025625Y228610D02*
X1026924Y225611D01*
X1026990Y225497D01*
G02X1027009Y223956I-1365J-787D01*
G01X1026990Y223922D01*
X1026965Y223880D01*
G03X1026990Y221597I2040J-1119D01*
G02X1027009Y220056I-1365J-787D01*
G01X1026990Y220022D01*
X1026965Y219980D01*
G03X1026990Y217697I2040J-1119D01*
G02X1027009Y216156I-1365J-787D01*
G01X1026990Y216122D01*
X1026965Y216080D01*
G03X1026990Y213797I2040J-1119D01*
G02X1027009Y212256I-1365J-787D01*
G01X1026990Y212222D01*
X1026965Y212180D01*
G03X1026990Y209897I2040J-1119D01*
G02X1027009Y208356I-1365J-787D01*
G01X1026990Y208322D01*
G03X1026965Y206039I2015J-1164D01*
G01X1026990Y205997D01*
G02X1027337Y205108I-2504J-1490D01*
G01X1027422Y205022D01*
X1028098Y204347D01*
Y199399D01*
X1030238Y197259D01*
Y190273D01*
G01X1029005Y230559D02*
X1030305Y227559D01*
X1030389Y227413D01*
G02X1030370Y225872I-1384J-754D01*
G03X1030345Y223589I2015J-1164D01*
G01X1030370Y223547D01*
X1030389Y223513D01*
G02X1030370Y221972I-1384J-754D01*
G03X1030345Y219689I2015J-1164D01*
G01X1030370Y219647D01*
X1030389Y219613D01*
G02X1030370Y218072I-1384J-754D01*
G03X1030345Y215789I2015J-1164D01*
G01X1030370Y215747D01*
X1030389Y215713D01*
G02X1030370Y214172I-1384J-754D01*
G03X1030345Y211889I2015J-1164D01*
G01X1030370Y211847D01*
X1030389Y211813D01*
G02X1030370Y210272I-1384J-754D01*
G03Y207946I2015J-1163D01*
G02X1030600Y207087I-1488J-859D01*
G01Y200761D01*
X1033500Y197861D01*
Y191652D01*
X1034240Y190912D01*
Y190071D01*
G01X1032385Y228610D02*
X1032357Y228540D01*
X1033453Y226009D01*
X1033750Y225497D01*
G02X1033769Y223956I-1365J-787D01*
G01X1033750Y223922D01*
X1033725Y223880D01*
G03X1033750Y221597I2040J-1119D01*
G02X1033769Y220056I-1365J-787D01*
G01X1033750Y220022D01*
X1033725Y219980D01*
G03X1033750Y217697I2040J-1119D01*
G02X1033769Y216156I-1365J-787D01*
G01X1033750Y216122D01*
X1033725Y216080D01*
G03X1033750Y213797I2040J-1119D01*
G02X1033769Y212256I-1365J-787D01*
G01X1033750Y212222D01*
X1033725Y212180D01*
G03X1033750Y209897I2040J-1119D01*
G02X1033769Y208356I-1365J-787D01*
G01X1033750Y208322D01*
X1033234Y207498D01*
Y205467D01*
X1035600Y203101D01*
Y200601D01*
X1036556Y199645D01*
Y192744D01*
X1038240Y191060D01*
Y190084D01*
G01X1029005Y234460D02*
X1030809Y232656D01*
Y228599D01*
G03X1031020Y227823I1576J12D01*
G02Y225497I-2015J-1163D01*
G03X1031001Y223956I1365J-787D01*
G01X1031020Y223922D01*
X1031045Y223880D01*
G02X1031020Y221597I-2040J-1119D01*
G03X1031001Y220056I1365J-787D01*
G01X1031020Y220022D01*
X1031045Y219980D01*
G02X1031020Y217697I-2040J-1119D01*
G03X1031001Y216156I1365J-787D01*
G01X1031020Y216122D01*
X1031045Y216080D01*
G02X1031020Y213797I-2040J-1119D01*
G03X1031001Y212256I1365J-787D01*
G01X1031020Y212222D01*
X1031045Y212180D01*
G02X1031020Y209897I-2040J-1119D01*
G03X1031001Y208356I1365J-787D01*
G01X1031259Y207895D01*
G02X1031700Y206200I-3034J-1694D01*
G01Y205000D01*
X1034356Y202344D01*
Y200044D01*
X1035100Y199300D01*
Y192186D01*
X1036240Y191046D01*
Y190168D01*
G01X1032385Y236409D02*
X1034334Y233788D01*
X1034400Y233672D01*
G02Y231346I-2015J-1163D01*
G03Y229772I1365J-787D01*
G01X1034425Y229730D01*
G02X1034400Y227447I-2040J-1119D01*
G01X1034381Y227413D01*
G03X1034400Y225872I1384J-754D01*
G02X1034425Y223589I-2015J-1164D01*
G01X1034400Y223547D01*
X1034381Y223513D01*
G03X1034400Y221972I1384J-754D01*
G02X1034425Y219689I-2015J-1164D01*
G01X1034400Y219647D01*
X1034381Y219613D01*
G03X1034400Y218072I1384J-754D01*
G02X1034425Y215789I-2015J-1164D01*
G01X1034400Y215747D01*
X1034381Y215713D01*
G03X1034400Y214172I1384J-754D01*
G02X1034425Y211889I-2015J-1164D01*
G01X1034400Y211847D01*
X1034381Y211813D01*
G03X1034400Y210272I1384J-754D01*
G02Y207946I-2015J-1163D01*
G01X1034076Y207377D01*
Y206529D01*
X1036900Y203705D01*
Y201200D01*
X1038106Y199994D01*
Y193195D01*
X1040240Y191061D01*
Y190240D01*
G01X981686Y351460D02*
X980235Y354747D01*
G02X980114Y355474I1451J615D01*
G01X1029005Y367060D02*
X1030193Y369792D01*
G02X1030345Y370130I2191J-782D01*
G01X1030370Y370172D01*
G03Y371746I-1365J787D01*
G02Y374072I2015J1163D01*
G03X1030389Y375613I-1365J787D01*
G01X1030370Y375647D01*
X1030345Y375689D01*
G02X1030370Y377972I2040J1119D01*
G03X1030389Y379513I-1365J787D01*
G01X1030370Y379547D01*
X1030345Y379589D01*
G02X1030370Y381872I2040J1119D01*
G03X1030389Y383413I-1365J787D01*
G01X1030370Y383447D01*
X1030345Y383489D01*
G02X1030370Y385772I2040J1119D01*
G03X1030389Y387313I-1365J787D01*
G01X1030370Y387347D01*
X1030345Y387389D01*
G02X1030370Y389672I2040J1119D01*
G03X1030600Y391200I-1829J1057D01*
G01X1030585Y391215D01*
Y398529D01*
X1032800Y400744D01*
Y402828D01*
G01X995206Y351460D02*
X997060Y353954D01*
G03X997246Y356480I-1854J1406D01*
G01X997221Y356522D01*
X997202Y356556D01*
G02X997221Y358097I1384J754D01*
G03X997246Y360380I-2015J1164D01*
G01X997221Y360422D01*
X997202Y360456D01*
G02X997221Y361997I1384J754D01*
G03X997246Y364280I-2015J1164D01*
G01X997221Y364322D01*
X997202Y364356D01*
G02X997221Y365897I1384J754D01*
G03Y368223I-2015J1163D01*
G02Y369797I1365J787D01*
G01X997246Y369839D01*
G03X997221Y372122I-2040J1119D01*
G01X997202Y372156D01*
G02X997221Y373697I1384J754D01*
G03X997246Y375980I-2015J1164D01*
G01X997221Y376022D01*
X997202Y376056D01*
G02X997221Y377597I1384J754D01*
G03X997246Y379880I-2015J1164D01*
G01X997221Y379922D01*
X997202Y379956D01*
G02X997221Y381497I1384J754D01*
G03X997246Y383780I-2015J1164D01*
G01X997221Y383822D01*
X997202Y383856D01*
G02X997221Y385397I1384J754D01*
G03Y387723I-2015J1163D01*
G01Y387722D01*
X997202Y387756D01*
G02X997221Y389297I1384J754D01*
G03Y391623I-2015J1163D01*
G01X997000Y392015D01*
Y393960D01*
X997400Y394360D01*
Y395781D01*
G01X999400Y405706D02*
Y404400D01*
X999226Y404226D01*
Y399074D01*
X1000300Y398000D01*
Y389017D01*
G02X999950Y387722I-2569J0D01*
G01X999915Y387662D01*
G03X999950Y385396I2050J-1102D01*
G02Y383822I-1364J-787D01*
G01X999915Y383762D01*
G03X999950Y381496I2050J-1102D01*
G02Y379922I-1364J-787D01*
G01X999915Y379862D01*
G03X999950Y377596I2050J-1102D01*
G02Y376022I-1364J-787D01*
G01X999915Y375962D01*
G03X999950Y373696I2050J-1102D01*
G02Y372122I-1364J-787D01*
G03X999925Y369839I2015J-1164D01*
G01X999950Y369797D01*
G02Y368223I-1364J-787D01*
G01X999925Y368181D01*
G03X999950Y365896I2040J-1120D01*
G02Y364322I-1364J-787D01*
G01X999884Y364208D01*
X998586Y361209D01*
G01X1018865Y369010D02*
X1020019Y368345D01*
X1020329Y368429D01*
G03X1020440Y369008I-1465J581D01*
G03X1020230Y369797I-1576J3D01*
G01X1020205Y369839D01*
G02X1020230Y372122I2040J1119D01*
G01X1020249Y372156D01*
G03X1020230Y373697I-1384J754D01*
G02X1020205Y375980I2015J1164D01*
G01X1020230Y376022D01*
X1020249Y376056D01*
G03X1020230Y377597I-1384J754D01*
G02X1020205Y379880I2015J1164D01*
G01X1020230Y379922D01*
X1020249Y379956D01*
G03X1020230Y381497I-1384J754D01*
G02X1020205Y383780I2015J1164D01*
G01X1020230Y383822D01*
X1020249Y383856D01*
G03X1020230Y385397I-1384J754D01*
G02X1020205Y387680I2015J1164D01*
G01X1020230Y387722D01*
X1020249Y387756D01*
G03X1020230Y389297I-1384J754D01*
G02X1020294Y391730I2017J1164D01*
G01X1020295D01*
X1020750Y392431D01*
Y395011D01*
X1021230Y395491D01*
Y401171D01*
X1021020Y401381D01*
G01X1012105Y369010D02*
X1013259Y368345D01*
X1013569Y368429D01*
G03X1013680Y369004I-1465J581D01*
G03X1013470Y369797I-1576J7D01*
G01X1013445Y369839D01*
G02X1013470Y372122I2040J1119D01*
G01X1013489Y372156D01*
G03X1013470Y373697I-1384J754D01*
G02X1013445Y375980I2015J1164D01*
G01X1013470Y376022D01*
X1013489Y376056D01*
G03X1013470Y377597I-1384J754D01*
G02X1013445Y379880I2015J1164D01*
G01X1013470Y379922D01*
X1013489Y379956D01*
G03X1013470Y381497I-1384J754D01*
G02X1013445Y383780I2015J1164D01*
G01X1013498Y383870D01*
G03X1013470Y385398I-1393J739D01*
G02X1013421Y387640I2015J1166D01*
G01X1013509Y387792D01*
G03X1013470Y389298I-1404J717D01*
G02X1013416Y391531I2015J1166D01*
G01X1013430Y391554D01*
X1013508Y391691D01*
X1013700Y392056D01*
Y394861D01*
X1014504Y395665D01*
Y401097D01*
X1014324Y401277D01*
G01X1018865Y361209D02*
X1019331Y361674D01*
G03X1019919Y363095I-1421J1420D01*
G02X1022175Y365485I2325J65D01*
G01X1022304D01*
G03X1023629Y367813I-59J1575D01*
G01X1023610Y367847D01*
G02X1023585Y370130I2015J1164D01*
G01X1023610Y370172D01*
G03Y371746I-1365J787D01*
G02Y374072I2015J1163D01*
G03X1023629Y375613I-1365J787D01*
G01X1023610Y375647D01*
X1023585Y375689D01*
G02X1023610Y377972I2040J1119D01*
G03X1023629Y379513I-1365J787D01*
G01X1023610Y379547D01*
X1023585Y379589D01*
G02X1023610Y381872I2040J1119D01*
G03X1023629Y383413I-1365J787D01*
G01X1023610Y383447D01*
X1023585Y383489D01*
G02X1023610Y385772I2040J1119D01*
G03X1023629Y387313I-1365J787D01*
G01X1023610Y387347D01*
X1023585Y387389D01*
G02X1023610Y389672I2040J1119D01*
G01X1023611Y389673D01*
G03X1023628Y391216I-1366J787D01*
G01X1023300Y391804D01*
Y393661D01*
X1024600Y394961D01*
Y401432D01*
X1024420Y401612D01*
Y401699D01*
G01X1012105Y361209D02*
X1012566Y361671D01*
G03X1013159Y363101I-1430J1431D01*
G02X1015415Y365485I2325J59D01*
G01X1015544D01*
G03X1016869Y367813I-59J1575D01*
G01X1016850Y367847D01*
G02X1016825Y370130I2015J1164D01*
G01X1016850Y370172D01*
G03Y371746I-1365J787D01*
G02Y374072I2015J1163D01*
G03X1016869Y375613I-1365J787D01*
G01X1016850Y375647D01*
X1016825Y375689D01*
G02X1016850Y377972I2040J1119D01*
G03X1016869Y379513I-1365J787D01*
G01X1016850Y379547D01*
X1016825Y379589D01*
G02X1016850Y381872I2040J1119D01*
G03X1016869Y383413I-1365J787D01*
G01X1016850Y383447D01*
X1016825Y383489D01*
G02X1016850Y385772I2040J1119D01*
G03X1016869Y387313I-1365J787D01*
G01X1016850Y387347D01*
X1016825Y387389D01*
G02X1016850Y389672I2040J1119D01*
G03X1016869Y391213I-1365J787D01*
G01X1016713Y391485D01*
X1016528Y391670D01*
Y393690D01*
X1017850Y395012D01*
Y401681D01*
X1017695Y401836D01*
Y401923D01*
G01X1022245Y367060D02*
X1021824Y367481D01*
G02X1021192Y369007I1526J1526D01*
G03X1020905Y370130I-2326J4D01*
G01X1020880Y370172D01*
G02Y371746I1365J787D01*
G03Y374072I-2015J1163D01*
G02X1020861Y375613I1365J787D01*
G01X1020880Y375647D01*
X1020905Y375689D01*
G03X1020880Y377972I-2040J1119D01*
G02X1020861Y379513I1365J787D01*
G01X1020880Y379547D01*
X1020905Y379589D01*
G03X1020880Y381872I-2040J1119D01*
G02X1020861Y383413I1365J787D01*
G01X1020880Y383447D01*
X1020905Y383489D01*
G03X1020880Y385772I-2040J1119D01*
G02X1020861Y387313I1365J787D01*
G01X1020908Y387397D01*
X1020905Y387389D01*
G03X1020880Y389672I-2040J1119D01*
G02X1020924Y391321I1368J789D01*
G01X1021500Y392209D01*
Y394700D01*
X1021980Y395180D01*
Y401314D01*
X1022080Y401414D01*
Y401501D01*
G01X1015485Y367060D02*
X1015060Y367485D01*
G02X1014432Y369001I1516J1516D01*
G03X1014145Y370130I-2326J10D01*
G01X1014120Y370172D01*
G02Y371746I1365J787D01*
G03Y374072I-2015J1163D01*
G02X1014101Y375613I1365J787D01*
G01X1014120Y375647D01*
X1014145Y375689D01*
G03X1014120Y377972I-2040J1119D01*
G02X1014101Y379513I1365J787D01*
G01X1014120Y379547D01*
X1014145Y379589D01*
G03X1014120Y381872I-2040J1119D01*
G02X1014101Y383413I1365J787D01*
G01X1014162Y383520D01*
G03X1014120Y385774I-2057J1089D01*
G02X1014081Y387280I1365J789D01*
G01X1014174Y387442D01*
G03X1014120Y389675I-2069J1067D01*
G02X1014081Y391181I1365J789D01*
G01X1014167Y391332D01*
X1014450Y391871D01*
Y394550D01*
X1015254Y395354D01*
Y401180D01*
X1015384Y401310D01*
Y401397D01*
G01X1022245Y363160D02*
X1021091Y362494D01*
X1020781Y362578D01*
G02X1020670Y363116I1464J583D01*
G02X1022201Y364735I1575J44D01*
G01X1022330D01*
G03X1024260Y368223I-85J2325D01*
G02Y369797I1365J787D01*
G01X1024285Y369839D01*
G03X1024260Y372122I-2040J1119D01*
G01X1024241Y372156D01*
G02X1024260Y373697I1384J754D01*
G03X1024285Y375980I-2015J1164D01*
G01X1024260Y376022D01*
X1024241Y376056D01*
G02X1024260Y377597I1384J754D01*
G03X1024285Y379880I-2015J1164D01*
G01X1024260Y379922D01*
X1024241Y379956D01*
G02X1024260Y381497I1384J754D01*
G03X1024285Y383780I-2015J1164D01*
G01X1024260Y383822D01*
X1024241Y383856D01*
G02X1024260Y385397I1384J754D01*
G03X1024285Y387680I-2015J1164D01*
G01X1024260Y387722D01*
X1024241Y387756D01*
G02X1024260Y389297I1384J754D01*
G01X1024261Y389298D01*
G03X1024285Y391579I-2016J1162D01*
G01X1024050Y392000D01*
Y393350D01*
X1025350Y394650D01*
Y401449D01*
X1025480Y401579D01*
G01X1015485Y363160D02*
X1014331Y362494D01*
X1014021Y362578D01*
G02X1015441Y364735I1464J582D01*
G01X1015570D01*
G03X1017500Y368223I-85J2325D01*
G02Y369797I1365J787D01*
G01X1017525Y369839D01*
G03X1017500Y372122I-2040J1119D01*
G01X1017481Y372156D01*
G02X1017500Y373697I1384J754D01*
G03X1017525Y375980I-2015J1164D01*
G01X1017500Y376022D01*
X1017481Y376056D01*
G02X1017500Y377597I1384J754D01*
G03X1017525Y379880I-2015J1164D01*
G01X1017500Y379922D01*
X1017481Y379956D01*
G02X1017500Y381497I1384J754D01*
G03X1017525Y383780I-2015J1164D01*
G01X1017500Y383822D01*
X1017481Y383856D01*
G02X1017500Y385397I1384J754D01*
G03X1017525Y387680I-2015J1164D01*
G01X1017500Y387722D01*
X1017481Y387756D01*
G02X1017500Y389297I1384J754D01*
G03Y391623I-2015J1163D01*
G01X1017313Y391946D01*
X1017278Y391981D01*
Y393379D01*
X1018600Y394701D01*
Y401681D01*
X1018755Y401836D01*
Y401923D01*
G01X1032385Y369010D02*
X1033685Y372010D01*
X1033769Y372156D01*
G03X1033750Y373697I-1384J754D01*
G02X1033725Y375980I2015J1164D01*
G01X1033750Y376022D01*
X1033769Y376056D01*
G03X1033750Y377597I-1384J754D01*
G02X1033725Y379880I2015J1164D01*
G01X1033750Y379922D01*
X1033769Y379956D01*
G03X1033750Y381497I-1384J754D01*
G02X1033725Y383780I2015J1164D01*
G01X1033750Y383822D01*
X1033769Y383856D01*
G03X1033750Y385397I-1384J754D01*
G02X1033725Y387680I2015J1164D01*
G01X1033750Y387722D01*
X1033769Y387756D01*
G03X1033750Y389297I-1384J754D01*
G02X1033000Y391900I4887J2818D01*
G01X1033006Y391906D01*
Y396070D01*
X1036800Y399864D01*
Y405200D01*
G01X1032385Y361209D02*
Y362685D01*
X1034213Y364513D01*
Y366785D01*
G02X1034381Y367813I1552J274D01*
G01X1034400Y367847D01*
G03X1034425Y370130I-2015J1164D01*
G01X1034400Y370172D01*
G02Y371746I1365J787D01*
G03Y374072I-2015J1163D01*
G02X1034381Y375613I1365J787D01*
G01X1034400Y375647D01*
X1034425Y375689D01*
G03X1034400Y377972I-2040J1119D01*
G02X1034381Y379513I1365J787D01*
G01X1034400Y379547D01*
X1034425Y379589D01*
G03X1034400Y381872I-2040J1119D01*
G02X1034381Y383413I1365J787D01*
G01X1034400Y383447D01*
X1034425Y383489D01*
G03X1034400Y385772I-2040J1119D01*
G02X1034381Y387313I1365J787D01*
G01X1034400Y387347D01*
X1034425Y387389D01*
G03X1034400Y389672I-2040J1119D01*
G02X1034100Y392100I2714J1568D01*
G01X1034096Y392104D01*
Y395040D01*
X1038100Y399044D01*
Y404266D01*
X1038800Y404966D01*
Y405821D01*
G01X1025625Y361209D02*
Y362725D01*
X1027687Y364787D01*
Y366097D01*
G03X1027640Y366272I-351J0D01*
G02X1027621Y367813I1365J787D01*
G01X1027640Y367847D01*
G03X1027665Y370130I-2015J1164D01*
G01X1027640Y370172D01*
G02Y371746I1365J787D01*
G03Y374072I-2015J1163D01*
G02X1027621Y375613I1365J787D01*
G01X1027640Y375647D01*
X1027665Y375689D01*
G03X1027640Y377972I-2040J1119D01*
G02X1027621Y379513I1365J787D01*
G01X1027640Y379547D01*
X1027665Y379589D01*
G03X1027640Y381872I-2040J1119D01*
G02X1027621Y383413I1365J787D01*
G01X1027640Y383447D01*
X1027665Y383489D01*
G03X1027640Y385772I-2040J1119D01*
G02X1027621Y387313I1365J787D01*
G01X1027640Y387347D01*
X1027665Y387389D01*
G03X1027640Y389672I-2040J1119D01*
G02X1027621Y391213I1365J787D01*
G01X1027640Y391247D01*
G02X1028452Y392166I2517J-1405D01*
G01Y398556D01*
X1030800Y400904D01*
Y405204D01*
G01X1001400Y406100D02*
Y404600D01*
X1002400Y403600D01*
Y399001D01*
X1001376Y397977D01*
Y388190D01*
X1001094Y387908D01*
G03X1000601Y387347I1159J-1516D01*
G03Y385773I1364J-787D01*
G02X1000636Y383507I-2015J-1164D01*
G01X1000601Y383447D01*
G03Y381873I1364J-787D01*
G02X1000636Y379607I-2015J-1164D01*
G01X1000601Y379547D01*
G03Y377973I1364J-787D01*
G02X1000636Y375707I-2015J-1164D01*
G01X1000601Y375647D01*
G03Y374073I1364J-787D01*
G02X1000626Y371788I-2015J-1165D01*
G01X1000601Y371746D01*
G03Y370172I1364J-787D01*
G01X1000626Y370130D01*
G02X1000601Y367847I-2040J-1119D01*
G03Y366273I1364J-787D01*
G02X1000636Y364007I-2015J-1164D01*
G01X1000601Y363947D01*
G03X1000390Y363179I1364J-788D01*
G01Y354245D01*
X1001965Y351460D01*
G01X1029005Y363160D02*
X1030993Y365850D01*
G03X1031020Y368223I-1988J1209D01*
G02Y369797I1365J787D01*
G01X1031045Y369839D01*
G03X1031020Y372122I-2040J1119D01*
G01X1031001Y372156D01*
G02X1031020Y373697I1384J754D01*
G03X1031045Y375980I-2015J1164D01*
G01X1031020Y376022D01*
X1031001Y376056D01*
G02X1031020Y377597I1384J754D01*
G03X1031045Y379880I-2015J1164D01*
G01X1031020Y379922D01*
X1031001Y379956D01*
G02X1031020Y381497I1384J754D01*
G03X1031045Y383780I-2015J1164D01*
G01X1031020Y383822D01*
X1031001Y383856D01*
G02X1031020Y385397I1384J754D01*
G03X1031045Y387680I-2015J1164D01*
G01X1031020Y387722D01*
X1031001Y387756D01*
G02X1031020Y389297I1384J754D01*
G03X1031700Y391838I-4407J2541D01*
G01Y397174D01*
X1034800Y400274D01*
Y405100D01*
G01X1012140Y401713D02*
Y400739D01*
X1010526Y399125D01*
Y388115D01*
X1010740Y387722D01*
X1010765Y387680D01*
G02X1010740Y385397I-2040J-1119D01*
G03X1010721Y383856I1365J-787D01*
G01X1010740Y383822D01*
X1010765Y383780D01*
G02X1010740Y381497I-2040J-1119D01*
G03X1010721Y379956I1365J-787D01*
G01X1010740Y379922D01*
X1010765Y379880D01*
G02X1010740Y377597I-2040J-1119D01*
G03X1010721Y376056I1365J-787D01*
G01X1010740Y376022D01*
X1010765Y375980D01*
G02X1010740Y373697I-2040J-1119D01*
G03X1010721Y372156I1365J-787D01*
G01X1010740Y372122D01*
G02X1010765Y369839I-2015J-1164D01*
G01X1010740Y369797D01*
G03Y368223I1365J-787D01*
G02Y365897I-2015J-1163D01*
G03X1010516Y365060I1453J-837D01*
G01Y358951D01*
X1008725Y355360D01*
G01Y363160D02*
X1010024Y366159D01*
X1010090Y366272D01*
G03X1010109Y367813I-1365J787D01*
G01X1010090Y367847D01*
G02X1010065Y370130I2015J1164D01*
G01X1010090Y370172D01*
G03Y371746I-1365J787D01*
G02Y374072I2015J1163D01*
G03X1010109Y375613I-1365J787D01*
G01X1010090Y375647D01*
X1010065Y375689D01*
G02X1010090Y377972I2040J1119D01*
G03X1010109Y379513I-1365J787D01*
G01X1010090Y379547D01*
X1010065Y379589D01*
G02X1010090Y381872I2040J1119D01*
G03X1010109Y383413I-1365J787D01*
G01X1010090Y383447D01*
X1010065Y383489D01*
G02X1010090Y385772I2040J1119D01*
G03X1010109Y387313I-1365J787D01*
G01X1009340Y388689D01*
X1009326Y388703D01*
Y400026D01*
X1010140Y400840D01*
Y404760D01*
G01X1008109Y405305D02*
Y404539D01*
X1009300Y403348D01*
Y402000D01*
X1008126Y400826D01*
Y390209D01*
G02X1007360Y387347I-5729J0D01*
G01X1007341Y387313D01*
G03X1007360Y385772I1384J-754D01*
G02X1007385Y383489I-2015J-1164D01*
G01X1007360Y383447D01*
X1007341Y383413D01*
G03X1007360Y381872I1384J-754D01*
G02X1007385Y379589I-2015J-1164D01*
G01X1007360Y379547D01*
X1007341Y379513D01*
G03X1007360Y377972I1384J-754D01*
G02X1007385Y375689I-2015J-1164D01*
G01X1007360Y375647D01*
X1007341Y375613D01*
G03X1007360Y374072I1384J-754D01*
G02Y371746I-2015J-1163D01*
G03Y370172I1365J-787D01*
G01X1007385Y370130D01*
G02X1007360Y367847I-2040J-1119D01*
G01X1007341Y367813D01*
G03X1007360Y366272I1384J-754D01*
G02X1007385Y363989I-2015J-1164D01*
G01X1007360Y363947D01*
X1007294Y363831D01*
X1005345Y361209D01*
G01X1007400Y413816D02*
Y412759D01*
X1006320Y411679D01*
Y403820D01*
X1005800Y403300D01*
Y395586D01*
X1006926Y394460D01*
Y391500D01*
X1006921Y391495D01*
Y388501D01*
G02X1006710Y387722I-1576J9D01*
G01X1006685Y387680D01*
G03X1006710Y385397I2040J-1119D01*
G02X1006729Y383856I-1365J-787D01*
G01X1006710Y383822D01*
X1006685Y383780D01*
G03X1006710Y381497I2040J-1119D01*
G02X1006729Y379956I-1365J-787D01*
G01X1006710Y379922D01*
X1006685Y379880D01*
G03X1006710Y377597I2040J-1119D01*
G02X1006729Y376056I-1365J-787D01*
G01X1006710Y376022D01*
X1006685Y375980D01*
G03X1006710Y373697I2040J-1119D01*
G02X1006729Y372156I-1365J-787D01*
G01X1006645Y372010D01*
X1005345Y369010D01*
G01X1001965Y355360D02*
X1003264Y358359D01*
X1003330Y358472D01*
G03X1003349Y360013I-1365J787D01*
G01X1003330Y360047D01*
X1003305Y360089D01*
G02X1003330Y362372I2040J1119D01*
G03X1003349Y363913I-1365J787D01*
G01X1003330Y363947D01*
X1003305Y363989D01*
G02X1003330Y366272I2040J1119D01*
G03X1003349Y367813I-1365J787D01*
G01X1003330Y367847D01*
G02X1003305Y370130I2015J1164D01*
G01X1003330Y370172D01*
G03Y371746I-1365J787D01*
G02Y374072I2015J1163D01*
G03X1003349Y375613I-1365J787D01*
G01X1003330Y375647D01*
X1003305Y375689D01*
G02X1003330Y377972I2040J1119D01*
G03X1003349Y379513I-1365J787D01*
G01X1003330Y379547D01*
X1003305Y379589D01*
G02X1003330Y381872I2040J1119D01*
G03X1003349Y383413I-1365J787D01*
G01X1003330Y383447D01*
X1003305Y383489D01*
G02X1003330Y385772I2040J1119D01*
G03X1003349Y387313I-1365J787D01*
G01X1003330Y387347D01*
G02X1002700Y389766I4328J2419D01*
G01Y393554D01*
X1003400Y394254D01*
Y405714D01*
G01X1005345Y357309D02*
X1004048Y360305D01*
X1003961Y360456D01*
G02X1003980Y361997I1384J754D01*
G03X1004005Y364280I-2015J1164D01*
G01X1003980Y364322D01*
X1003961Y364356D01*
G02X1003980Y365897I1384J754D01*
G03Y368223I-2015J1163D01*
G02Y369797I1365J787D01*
G01X1004005Y369839D01*
G03X1003980Y372122I-2040J1119D01*
G01X1003961Y372156D01*
G02X1003980Y373697I1384J754D01*
G03X1004005Y375980I-2015J1164D01*
G01X1003980Y376022D01*
X1003961Y376056D01*
G02X1003980Y377597I1384J754D01*
G03X1004005Y379880I-2015J1164D01*
G01X1003980Y379922D01*
X1003961Y379956D01*
G02X1003980Y381497I1384J754D01*
G03X1004005Y383780I-2015J1164D01*
G01X1003980Y383822D01*
X1003961Y383856D01*
G02X1003980Y385397I1384J754D01*
G03X1004005Y387680I-2015J1164D01*
G02X1003726Y388694I1703J1014D01*
G01Y393330D01*
X1004500Y394104D01*
Y403728D01*
X1005400Y404628D01*
Y413600D01*
G01X1025625Y369010D02*
X1026925Y372010D01*
X1027009Y372156D01*
G03X1026990Y373697I-1384J754D01*
G02X1026965Y375980I2015J1164D01*
G01X1026990Y376022D01*
X1027009Y376056D01*
G03X1026990Y377597I-1384J754D01*
G02X1026965Y379880I2015J1164D01*
G01X1026990Y379922D01*
X1027009Y379956D01*
G03X1026990Y381497I-1384J754D01*
G02X1026965Y383780I2015J1164D01*
G01X1026990Y383822D01*
X1027009Y383856D01*
G03X1026990Y385397I-1384J754D01*
G02X1026965Y387680I2015J1164D01*
G01X1026990Y387722D01*
X1027009Y387756D01*
G03X1026990Y389297I-1384J754D01*
G02Y391623I2015J1163D01*
G03X1027200Y392407I-1358J784D01*
G01Y399494D01*
X1029476Y401770D01*
Y403624D01*
X1028800Y404300D01*
Y405271D01*
G01X1039145Y236409D02*
X1041099Y233781D01*
X1041160Y233673D01*
G02X1041185Y231388I-2015J-1165D01*
G01X1041160Y231346D01*
G03Y229772I1364J-787D01*
G01X1041185Y229730D01*
G02X1041160Y227447I-2040J-1119D01*
G03Y225873I1364J-787D01*
G02X1041195Y223607I-2015J-1164D01*
G01X1041160Y223547D01*
G03Y221973I1364J-787D01*
G02X1041195Y219707I-2015J-1164D01*
G01X1041160Y219647D01*
G03Y218073I1364J-787D01*
G02X1041195Y215807I-2015J-1164D01*
G01X1041160Y215747D01*
G03Y214173I1364J-787D01*
G02X1041195Y211907I-2015J-1164D01*
G01X1041160Y211847D01*
G03Y210273I1364J-787D01*
G01X1044098Y205181D01*
Y196938D01*
X1048240Y192796D01*
Y191296D01*
G01X1056240Y189743D02*
Y190860D01*
X1051076Y196024D01*
Y228767D01*
X1049284Y230559D01*
G01Y234460D02*
X1052800Y230944D01*
Y203700D01*
X1052000Y202900D01*
Y196600D01*
X1058240Y190360D01*
Y189343D01*
G01X1042524Y230559D02*
X1043724Y227798D01*
G03X1043889Y227448I2180J814D01*
G02Y225874I-1365J-787D01*
G03Y223548I2015J-1163D01*
G02Y221974I-1365J-787D01*
G03Y219648I2015J-1163D01*
G02Y218074I-1365J-787D01*
G03Y215748I2015J-1163D01*
G02Y214174I-1365J-787D01*
G03Y211848I2017J-1163D01*
G02Y210274I-1365J-787D01*
G03Y207948I2015J-1163D01*
G01X1045100Y205852D01*
Y200440D01*
X1047770Y197770D01*
Y194530D01*
X1050240Y192060D01*
Y190799D01*
G01X1057314Y224709D02*
X1054256Y221651D01*
Y203945D01*
X1055600Y202601D01*
Y194799D01*
X1060240Y190159D01*
Y188943D01*
G01X1057314Y228610D02*
X1058900Y227024D01*
Y224000D01*
X1057700Y222800D01*
X1057000D01*
X1055700Y221500D01*
Y204201D01*
X1056400Y203501D01*
Y195800D01*
X1062348Y189852D01*
Y188712D01*
G01X1035765Y230559D02*
X1037065Y227559D01*
X1037149Y227413D01*
G02X1037130Y225872I-1384J-754D01*
G03X1037105Y223589I2015J-1164D01*
G01X1037130Y223547D01*
X1037149Y223513D01*
G02X1037130Y221972I-1384J-754D01*
G03X1037105Y219689I2015J-1164D01*
G01X1037130Y219647D01*
X1037149Y219613D01*
G02X1037130Y218072I-1384J-754D01*
G03X1037105Y215789I2015J-1164D01*
G01X1037130Y215747D01*
X1037149Y215713D01*
G02X1037130Y214172I-1384J-754D01*
G03X1037105Y211889I2015J-1164D01*
G01X1037130Y211847D01*
X1037149Y211813D01*
G02X1037130Y210272I-1384J-754D01*
G03Y207946I2015J-1163D01*
G01X1037449Y207375D01*
X1037956Y205691D01*
Y201845D01*
X1039656Y200145D01*
Y193644D01*
X1042240Y191060D01*
Y190218D01*
G01X1035765Y234460D02*
X1037715Y231835D01*
X1037780Y231722D01*
G02X1037805Y229439I-2015J-1164D01*
G01X1037780Y229397D01*
G03Y227823I1365J-787D01*
G02Y225497I-2015J-1163D01*
G03X1037761Y223956I1365J-787D01*
G01X1037780Y223922D01*
X1037805Y223880D01*
G02X1037780Y221597I-2040J-1119D01*
G03X1037761Y220056I1365J-787D01*
G01X1037780Y220022D01*
X1037805Y219980D01*
G02X1037780Y217697I-2040J-1119D01*
G03X1037761Y216156I1365J-787D01*
G01X1037780Y216122D01*
X1037805Y216080D01*
G02X1037780Y213797I-2040J-1119D01*
G03X1037761Y212256I1365J-787D01*
G01X1037780Y212222D01*
X1037805Y212180D01*
G02X1037780Y209897I-2040J-1119D01*
G03X1037761Y208356I1365J-787D01*
G01X1039306Y205677D01*
Y202293D01*
X1040900Y200699D01*
Y194365D01*
X1044240Y191025D01*
Y190266D01*
G01X1042524Y234460D02*
X1044243Y232129D01*
G02X1044539Y229398I-1719J-1568D01*
G03Y227824I1365J-787D01*
G02Y225498I-2015J-1163D01*
G03Y223924I1365J-787D01*
G02Y221598I-2015J-1163D01*
G03Y220024I1365J-787D01*
G02Y217698I-2015J-1163D01*
G03Y216124I1365J-787D01*
G02Y213798I-2015J-1163D01*
G03Y212224I1364J-787D01*
G02Y209898I-2015J-1163D01*
G03Y208324I1365J-787D01*
G01X1044695Y208053D01*
X1046206Y206542D01*
Y200494D01*
X1048700Y198000D01*
Y195300D01*
X1052240Y191760D01*
Y190520D01*
G01X1039145Y228610D02*
X1040446Y225603D01*
X1040509Y225496D01*
G02Y223922I-1364J-787D01*
G01X1040474Y223862D01*
G03X1040509Y221596I2050J-1102D01*
G02Y220022I-1364J-787D01*
G01X1040474Y219962D01*
G03X1040509Y217696I2050J-1102D01*
G02Y216122I-1364J-787D01*
G01X1040474Y216062D01*
G03X1040509Y213796I2050J-1102D01*
G02Y212222I-1364J-787D01*
G01X1040474Y212162D01*
G03X1040509Y209896I2050J-1102D01*
G01X1040906Y209209D01*
Y202593D01*
X1042300Y201199D01*
Y197524D01*
X1046240Y193584D01*
Y191585D01*
G01X1045904Y236409D02*
Y236393D01*
X1047556Y234741D01*
Y200244D01*
X1050000Y197800D01*
Y195740D01*
X1054240Y191500D01*
Y190277D01*
G01X1085721Y220096D02*
X1085555Y219920D01*
G03X1083722Y217388I11333J-10134D01*
G01X1083706Y217360D01*
G03Y215034I2015J-1163D01*
G02Y213459I-1364J-788D01*
G01X1083254Y212676D01*
Y209959D01*
X1080477Y207182D01*
Y202811D01*
X1076084Y198418D01*
Y189269D01*
X1075756Y188941D01*
Y186756D01*
X1074300Y185300D01*
G01X1085721Y227896D02*
X1084356Y224784D01*
G03X1085117Y222542I1365J-787D01*
G02X1086971Y221056I-1636J-3940D01*
G02X1086295Y218630I-1250J-959D01*
G03X1084356Y216984I1328J-3530D01*
G03Y215410I1365J-787D01*
G02Y213084I-2017J-1163D01*
G01X1084354Y213085D01*
X1084004Y212478D01*
Y209648D01*
X1081227Y206871D01*
Y202500D01*
X1076834Y198107D01*
Y185633D01*
X1076200Y184999D01*
G01X1095861Y222047D02*
Y223378D01*
X1096089Y223606D01*
G02X1097226Y221259I-228J-1559D01*
G03X1097201Y218976I2015J-1164D01*
G03X1097245Y218900I1668J915D01*
G02X1097226Y217359I-1384J-754D01*
G01X1096916Y216822D01*
Y208361D01*
X1097436Y207841D01*
Y205751D01*
X1093565Y201880D01*
Y197356D01*
X1088626Y192417D01*
Y187674D01*
X1089700Y186600D01*
G01X1082341Y222047D02*
X1080390Y219422D01*
X1080326Y219309D01*
G03X1080209Y219081I1790J-1062D01*
G03X1080326Y216983I2132J-933D01*
G02Y215409I-1364J-787D01*
G01X1080284Y215336D01*
G03X1080326Y213082I2057J-1089D01*
G01X1080576Y212652D01*
Y211311D01*
X1077627Y208362D01*
Y203992D01*
X1073134Y199499D01*
Y189469D01*
X1069200Y185535D01*
G01X1082341Y225947D02*
X1083638Y222951D01*
X1083725Y222800D01*
G02X1083706Y221259I-1384J-754D01*
G01X1083594Y221064D01*
G02X1081948Y219672I-2267J1011D01*
G03X1081105Y219122I394J-1525D01*
G03X1080878Y218728I1244J-979D01*
G03X1080977Y217360I1463J-582D01*
G02X1081012Y215094I-2015J-1164D01*
G01X1080977Y215034D01*
X1080958Y215000D01*
G03X1080977Y213459I1383J-754D01*
G01X1081326Y212858D01*
Y211000D01*
X1078377Y208051D01*
Y203681D01*
X1073884Y199188D01*
Y187284D01*
X1071300Y184700D01*
G01X1092481Y220096D02*
X1093696Y217296D01*
G03X1093846Y216984I2166J849D01*
G02X1094057Y216196I-1365J-788D01*
G01Y208614D01*
X1089026Y203583D01*
Y196848D01*
X1085368Y193190D01*
Y186432D01*
X1085900Y185900D01*
G01X1094807Y216241D02*
Y208298D01*
X1089776Y203267D01*
Y196537D01*
X1086118Y192879D01*
Y187882D01*
X1087800Y186200D01*
G01X1089101Y218147D02*
X1088488Y216874D01*
X1088043Y215549D01*
X1087724Y215015D01*
X1087716Y215001D01*
X1087717Y215000D01*
G03X1087736Y213460I1384J-753D01*
G02Y211134I-2017J-1163D01*
G01X1086989Y209839D01*
Y208573D01*
X1084077Y205661D01*
Y201319D01*
X1079910Y197152D01*
Y185442D01*
X1080065Y185287D01*
G01X1089101Y229847D02*
G02X1087393Y227526I-11194J6449D01*
G03X1089016Y223622I1708J-1579D01*
G01X1089145D01*
G02X1090466Y221260I-44J-1575D01*
G03Y218934I2015J-1163D01*
G02Y217360I-1365J-787D01*
G01X1090465Y217358D01*
G03X1090154Y216197I2013J-1161D01*
G03X1090466Y215035I2326J2D01*
G01X1090706Y214620D01*
Y209291D01*
X1086177Y204762D01*
Y198029D01*
X1082318Y194170D01*
Y185442D01*
X1082251Y185375D01*
X1082207D01*
X1082163Y185331D01*
Y185287D01*
G01X1089101Y222047D02*
X1089094Y222032D01*
G02X1087736Y218934I-14719J4605D01*
G03X1087575Y217755I1365J-787D01*
G02X1087086Y215410I-3808J-429D01*
G01X1087080Y215400D01*
X1087071Y215384D01*
X1087067Y215378D01*
X1087061Y215367D01*
G03X1087086Y213084I2040J-1119D01*
G02Y211509I-1364J-787D01*
G01X1086239Y210040D01*
Y208884D01*
X1083327Y205972D01*
Y201630D01*
X1079160Y197463D01*
Y185442D01*
X1079093Y185375D01*
X1079049D01*
X1079005Y185331D01*
Y185287D01*
G01X1089101Y225947D02*
X1089900Y226746D01*
Y227096D01*
G03X1089565Y227432I-535J-199D01*
G03X1088873Y227506I-490J-1308D01*
G03X1087944Y227017I228J-1559D01*
G03X1089057Y224372I1157J-1070D01*
G01X1089186D01*
G02X1091116Y220884I-85J-2325D01*
G03Y219310I1365J-787D01*
G02Y216984I-2015J-1163D01*
G03X1090905Y216197I1365J-788D01*
G03X1091116Y215411I1575J2D01*
G01X1091456Y214822D01*
Y208980D01*
X1086927Y204451D01*
Y197718D01*
X1083068Y193859D01*
Y185442D01*
X1083223Y185287D01*
G01X1095861Y225947D02*
Y224616D01*
X1096118Y224359D01*
G02X1097876Y223209I-257J-2312D01*
G01X1097901Y223167D01*
G02X1097876Y220884I-2040J-1119D01*
G03X1097857Y219343I1365J-787D01*
G01X1097876Y219309D01*
X1097901Y219267D01*
G02X1097876Y216984I-2040J-1119D01*
G01X1097666Y216609D01*
Y208673D01*
X1098186Y208153D01*
Y205437D01*
X1094315Y201566D01*
Y197045D01*
X1089376Y192106D01*
Y189321D01*
X1091600Y187097D01*
G01X1092481Y227896D02*
X1093939D01*
X1094187Y227648D01*
Y226523D01*
X1093714Y226050D01*
G03X1093846Y224784I1487J-485D01*
G02X1094033Y223727I-1365J-787D01*
G03X1094496Y221260I3741J-575D01*
G02Y218934I-2015J-1163D01*
G03Y217360I1365J-787D01*
G02X1094807Y216241I-2015J-1163D01*
G01X1102621Y222047D02*
X1102536Y222034D01*
X1100919Y219860D01*
X1100606Y219309D01*
X1100581Y219267D01*
G03X1100606Y216984I2040J-1119D01*
G02X1100625Y215443I-1365J-787D01*
G01X1100606Y215409D01*
X1100581Y215367D01*
G03X1100606Y213084I2040J-1119D01*
G01X1100860Y212644D01*
Y205005D01*
X1100154Y204299D01*
Y201659D01*
X1099384Y200889D01*
Y197213D01*
X1097764Y195593D01*
Y194374D01*
X1096826Y193436D01*
G01X1145207Y261207D02*
G03X1146240Y261848I-96J1307D01*
G02X1149045Y261834I1398J-825D01*
G03X1150990Y260671I2015J1162D01*
G01X1151119D01*
G02X1152425Y259884I-59J-1575D01*
G03X1154355Y258722I2015J1163D01*
G01X1155316D01*
G02X1157300Y257900I0J-2806D01*
G01X1157772Y257428D01*
G03X1159650Y256650I1878J1878D01*
G02X1160293Y256383I-1J-910D01*
G01X1160638Y256039D01*
X1162315Y254362D01*
G02X1162565Y254034I-1118J-1111D01*
G03X1164510Y252871I2015J1162D01*
G01X1164650D01*
G03X1166595Y254034I-70J2325D01*
G02X1167916Y254822I1365J-787D01*
G01X1168058D01*
G03X1169834Y255766I-97J2325D01*
G01X1170186Y255861D01*
X1171339Y255196D01*
G01X1127400Y278221D02*
X1127444D01*
G02X1128765Y277433I-44J-1575D01*
G03X1130695Y276271I2015J1163D01*
G01X1130865D01*
G03X1132795Y277433I-85J2325D01*
G02X1134116Y278221I1365J-787D01*
G01X1134204D01*
G02X1135525Y277433I-44J-1575D01*
G03X1137455Y276271I2015J1163D01*
G01X1137625D01*
G03X1139555Y277433I-85J2325D01*
G02X1140876Y278221I1365J-787D01*
G01X1140964D01*
G02X1142285Y277433I-44J-1575D01*
G03X1144215Y276271I2015J1163D01*
G01X1144344D01*
G02X1145665Y275483I-44J-1575D01*
G03X1147595Y274321I2015J1163D01*
G01X1147751D01*
G02X1149045Y273534I-71J-1574D01*
G03X1150990Y272371I2015J1162D01*
G01X1151130D02*
G03X1153075Y273534I-70J2325D01*
G02X1154369Y274321I1365J-787D01*
G01X1154584D01*
X1157820Y274696D01*
G01X1118765Y280165D02*
X1120235D01*
G01X1124311Y278972D02*
X1127451D01*
G02X1129415Y277809I-51J-2326D01*
G03X1130736Y277021I1365J787D01*
G01X1130824D01*
G03X1132145Y277809I-44J1575D01*
G02X1134109Y278972I2015J-1163D01*
G01X1134211D01*
G02X1136175Y277809I-51J-2326D01*
G03X1137496Y277021I1365J787D01*
G01X1137584D01*
G03X1138905Y277809I-44J1575D01*
G02X1140869Y278972I2015J-1163D01*
G01X1140971D01*
G02X1142935Y277809I-51J-2326D01*
G03X1144256Y277021I1365J787D01*
G01X1144385D01*
G02X1146315Y275859I-85J-2325D01*
G03X1147609Y275072I1365J787D01*
G01X1149217D01*
X1150410Y276265D01*
X1154058D01*
X1154440Y276647D01*
G01X1093601Y381947D02*
X1091652Y384568D01*
X1091586Y384684D01*
G02X1091561Y386967I2015J1164D01*
G01X1091586Y387009D01*
X1091605Y387043D01*
G03X1091586Y388584I-1384J754D01*
G02X1091561Y390867I2015J1164D01*
G01X1091586Y390909D01*
G03X1090292Y393270I-1365J787D01*
G01X1090151D01*
G02X1088871Y393701I70J2325D01*
G02X1087737Y394896I2503J3511D01*
G01X1087724Y394916D01*
X1084775Y400019D01*
Y405482D01*
X1076990Y413267D01*
Y416403D01*
X1076106Y417287D01*
G01X1093601Y389747D02*
X1092302Y392745D01*
X1092236Y392858D01*
G03X1090291Y394021I-2015J-1162D01*
G01X1090162D01*
G02X1089074Y394516I59J1574D01*
G02X1087875Y396160I5957J5604D01*
G01X1086426Y398666D01*
X1085523Y400229D01*
Y405792D01*
X1077738Y413577D01*
Y416369D01*
X1078656Y417287D01*
G01X1090221Y383896D02*
Y385227D01*
X1089964Y385484D01*
G02X1088206Y388959I257J2312D01*
G03X1086885Y391322I-1365J788D01*
G01X1086743D01*
G02X1084826Y392483I98J2325D01*
G01X1084824Y392485D01*
X1081355Y398486D01*
Y400330D01*
X1071876Y409809D01*
Y415968D01*
X1070657Y417187D01*
G01X1090221Y387796D02*
Y386465D01*
X1089993Y386237D01*
G02X1088856Y388584I228J1559D01*
G03X1086911Y392072I-2015J1163D01*
G01X1086841D01*
G02X1085490Y392837I0J1575D01*
G01X1082121Y398666D01*
X1082105Y398693D01*
Y400638D01*
X1072624Y410119D01*
Y416255D01*
X1073556Y417187D01*
G01X1096981Y383896D02*
X1097339D01*
X1098027Y383208D01*
Y382713D01*
X1097615Y382301D01*
X1096789D01*
X1096753Y382337D01*
G02X1096572Y382374I225J1560D01*
G02X1095616Y384684I408J1522D01*
G03X1095641Y386967I-2015J1164D01*
G01X1095616Y387009D01*
X1095597Y387043D01*
G02X1095616Y388584I1384J754D01*
G03X1095641Y390867I-2015J1164D01*
G01X1095616Y390909D01*
X1095597Y390943D01*
G02X1095616Y392484I1384J754D01*
G02X1095641Y392525I847J-488D01*
G03X1093686Y395970I-2040J1120D01*
G01X1093530D01*
G02X1092236Y396757I71J1574D01*
G01X1091134Y398666D01*
X1088645Y402980D01*
Y407212D01*
X1082156Y413701D01*
Y417945D01*
X1082311Y418100D01*
Y418187D01*
G01X1096981Y391696D02*
G02X1098346Y394811I14713J-4591D01*
G03X1098557Y395598I-1365J788D01*
G01Y396040D01*
X1096456Y398141D01*
Y400941D01*
X1094376Y403021D01*
X1092637D01*
X1091193Y404465D01*
Y409304D01*
X1088606Y411891D01*
Y418245D01*
X1088451Y418400D01*
Y418487D01*
G01X1096981Y379996D02*
X1096378Y381649D01*
G02X1094966Y385059I603J2247D01*
G03X1094985Y386600I-1365J787D01*
G01X1094966Y386634D01*
X1094941Y386676D01*
G02X1094966Y388959I2040J1119D01*
G03X1094985Y390500I-1365J787D01*
G01X1094966Y390534D01*
X1094941Y390576D01*
G02X1094966Y392859I2040J1119D01*
G01X1094985Y392892D01*
G03X1093682Y395219I-1384J753D01*
G01X1093663Y395220D01*
X1093514D01*
G02X1091586Y396382I87J2324D01*
G01X1087895Y402779D01*
Y406901D01*
X1081406Y413390D01*
Y417945D01*
X1081251Y418100D01*
Y418187D01*
G01X1039145Y361209D02*
X1041096Y363834D01*
X1041195Y364007D01*
G03X1041160Y366273I-2050J1102D01*
G02Y367847I1364J787D01*
G03X1041185Y370130I-2015J1164D01*
G01X1041160Y370172D01*
G02Y371746I1364J787D01*
G01X1041185Y371788D01*
G03X1041160Y374073I-2040J1120D01*
G02Y375647I1364J787D01*
G01X1041195Y375707D01*
G03X1041160Y377973I-2050J1102D01*
G02Y379547I1364J787D01*
G01X1041195Y379607D01*
G03X1041160Y381873I-2050J1102D01*
G02Y383447I1364J787D01*
G01X1041195Y383507D01*
G03X1041160Y385773I-2050J1102D01*
G02Y387347I1364J787D01*
G01X1041195Y387407D01*
G03X1041160Y389673I-2050J1102D01*
G01X1041128Y389729D01*
G02X1041159Y391248I1396J731D01*
G02X1042694Y392422I2178J-1257D01*
G01X1044800Y394528D01*
Y403301D01*
X1046900Y405401D01*
Y406829D01*
G01X1042524Y367060D02*
X1043719Y369810D01*
G02X1043864Y370130I2186J-798D01*
G01X1043889Y370172D01*
G03Y371746I-1365J787D01*
G02Y374072I2015J1163D01*
G03X1043908Y375613I-1365J787D01*
G01X1043889Y375647D01*
X1043864Y375689D01*
G02X1043889Y377972I2040J1119D01*
G03X1043908Y379513I-1365J787D01*
G01X1043889Y379547D01*
X1043864Y379589D01*
G02X1043889Y381872I2040J1119D01*
G03X1043908Y383413I-1365J787D01*
G01X1043889Y383447D01*
X1043864Y383489D01*
G02X1043889Y385772I2040J1119D01*
G03X1043908Y387313I-1365J787D01*
G01X1043889Y387347D01*
X1043864Y387389D01*
G02X1043889Y389672I2040J1119D01*
G01X1044449Y390642D01*
X1045700Y391893D01*
Y402672D01*
X1048900Y405872D01*
Y407111D01*
G01X1035765Y367060D02*
X1037063Y370057D01*
X1037130Y370172D01*
G03Y371746I-1365J787D01*
G02Y374072I2015J1163D01*
G03X1037149Y375613I-1365J787D01*
G01X1037130Y375647D01*
X1037105Y375689D01*
G02X1037130Y377972I2040J1119D01*
G03X1037149Y379513I-1365J787D01*
G01X1037130Y379547D01*
X1037105Y379589D01*
G02X1037130Y381872I2040J1119D01*
G03X1037149Y383413I-1365J787D01*
G01X1037130Y383447D01*
X1037105Y383489D01*
G02X1037130Y385772I2040J1119D01*
G03X1037149Y387313I-1365J787D01*
G01X1037130Y387347D01*
X1037105Y387389D01*
G02X1037130Y389672I2040J1119D01*
G03X1036900Y391800I-1570J907D01*
G01X1036286Y392414D01*
Y395086D01*
X1039700Y398500D01*
Y403719D01*
X1040866Y404885D01*
Y405606D01*
G01X1042900Y405741D02*
Y404300D01*
X1043000Y404200D01*
Y399584D01*
X1038100Y394684D01*
Y392400D01*
X1038200Y392300D01*
G02X1037780Y389297I-3926J-982D01*
G03X1037761Y387756I1365J-787D01*
G01X1037780Y387722D01*
X1037805Y387680D01*
G02X1037780Y385397I-2040J-1119D01*
G03X1037761Y383856I1365J-787D01*
G01X1037780Y383822D01*
X1037805Y383780D01*
G02X1037780Y381497I-2040J-1119D01*
G03X1037761Y379956I1365J-787D01*
G01X1037780Y379922D01*
X1037805Y379880D01*
G02X1037780Y377597I-2040J-1119D01*
G03X1037761Y376056I1365J-787D01*
G01X1037780Y376022D01*
X1037805Y375980D01*
G02X1037780Y373697I-2040J-1119D01*
G03X1037761Y372156I1365J-787D01*
G01X1037780Y372122D01*
G02X1037805Y369839I-2015J-1164D01*
G01X1037780Y369797D01*
G03X1037629Y368580I1365J-787D01*
G01Y366329D01*
X1035765Y364465D01*
Y363160D01*
G01X1042524D02*
X1044438Y365737D01*
G03X1044539Y368223I-1914J1323D01*
G02Y369797I1365J787D01*
G01X1044564Y369839D01*
G03X1044539Y372122I-2040J1119D01*
G01X1044520Y372156D01*
G02X1044539Y373697I1384J754D01*
G03X1044564Y375980I-2015J1164D01*
G01X1044539Y376022D01*
X1044520Y376056D01*
G02X1044539Y377597I1384J754D01*
G03X1044564Y379880I-2015J1164D01*
G01X1044539Y379922D01*
X1044520Y379956D01*
G02X1044539Y381497I1384J754D01*
G03X1044564Y383780I-2015J1164D01*
G01X1044539Y383822D01*
X1044520Y383856D01*
G02X1044539Y385397I1384J754D01*
G03X1044692Y385715I-2014J1165D01*
G01X1045767Y386790D01*
X1046636D01*
X1047700Y387854D01*
Y400200D01*
X1049900Y402400D01*
Y405128D01*
X1050900Y406128D01*
Y407111D01*
G01X1039145Y369010D02*
X1040446Y372014D01*
X1040509Y372122D01*
G03Y373696I-1364J787D01*
G02X1040474Y375962I2015J1164D01*
G01X1040509Y376022D01*
G03Y377596I-1364J787D01*
G02X1040474Y379862I2015J1164D01*
G01X1040509Y379922D01*
G03Y381496I-1364J787D01*
G02X1040474Y383762I2015J1164D01*
G01X1040509Y383822D01*
G03Y385396I-1364J787D01*
G02X1040474Y387662I2015J1164D01*
G01X1040509Y387722D01*
G03Y389296I-1364J787D01*
G02X1040466Y391546I2015J1164D01*
G02X1042300Y393900I7524J-3970D01*
G01X1043800Y395400D01*
Y404000D01*
X1044900Y405100D01*
Y406265D01*
G01X1100361Y381947D02*
X1099062Y384946D01*
X1098996Y385059D01*
G02X1098977Y386600I1365J787D01*
G01X1098996Y386634D01*
X1099021Y386676D01*
G03X1098996Y388959I-2040J1119D01*
G02X1098977Y390500I1365J787D01*
G01X1099644Y391658D01*
G02X1100361Y392072I717J-414D01*
G01X1100420D01*
G03X1101726Y392859I-59J1575D01*
G01X1101936Y393222D01*
Y399657D01*
X1098608Y402985D01*
Y408185D01*
X1093304Y413489D01*
Y416269D01*
X1092106Y417467D01*
G01X1100361Y389747D02*
X1102310Y392368D01*
X1102684Y393020D01*
Y399967D01*
X1099356Y403295D01*
Y408495D01*
X1094052Y413799D01*
Y416423D01*
X1095036Y417407D01*
G01X1099307Y396351D02*
X1097206Y398452D01*
Y401252D01*
X1094687Y403771D01*
X1092948D01*
X1091943Y404776D01*
Y409615D01*
X1089356Y412202D01*
Y418245D01*
X1089511Y418400D01*
Y418487D01*
G01X1106001Y220096D02*
X1104052Y217475D01*
X1103986Y217359D01*
G03X1103961Y215076I2015J-1164D01*
G01X1103986Y215034D01*
X1104005Y215000D01*
G02X1103986Y213459I-1384J-754D01*
G03X1103674Y212296I2015J-1164D01*
G01Y211263D01*
X1103880Y211057D01*
Y203994D01*
X1103002Y203116D01*
Y200479D01*
X1102413Y199890D01*
Y196592D01*
X1102706Y196299D01*
Y189716D01*
X1101926Y188936D01*
G01X1107200Y221172D02*
X1107366Y220884D01*
G02X1107385Y219343I-1365J-787D01*
G01X1107122Y218887D01*
X1105171Y217536D01*
G03X1104617Y215443I830J-1340D01*
G01X1104636Y215409D01*
X1104661Y215367D01*
G02X1104636Y213084I-2040J-1119D01*
G03X1104425Y212296I1365J-788D01*
G01Y211575D01*
X1104630Y211370D01*
Y203683D01*
X1103752Y202805D01*
Y200167D01*
X1103163Y199578D01*
Y196904D01*
X1103456Y196611D01*
Y189956D01*
X1104476Y188936D01*
G01X1116141Y222047D02*
X1117328Y219317D01*
G03X1117481Y218976I2193J779D01*
G01X1117506Y218934D01*
X1117525Y218900D01*
G02X1117506Y217359I-1384J-754D01*
G01X1117152Y216745D01*
Y211075D01*
X1117806Y210421D01*
Y203367D01*
X1119463Y201710D01*
Y197484D01*
X1121466Y195481D01*
Y194346D01*
X1120716Y193596D01*
G01X1116141Y225947D02*
X1117843Y223633D01*
G02X1118156Y220884I-1702J-1586D01*
G03X1118137Y219343I1365J-787D01*
G01X1118156Y219309D01*
X1118181Y219267D01*
G02X1118156Y216984I-2040J-1119D01*
G01X1117902Y216544D01*
Y211386D01*
X1118556Y210732D01*
Y203679D01*
X1120213Y202022D01*
Y197796D01*
X1122216Y195793D01*
Y194646D01*
X1123266Y193596D01*
G01X1102621Y225947D02*
X1103918Y222951D01*
X1104005Y222800D01*
G02X1103264Y220608I-1384J-753D01*
G01X1102448Y220278D01*
X1101833Y219724D01*
X1101418Y219215D01*
X1101237Y218900D01*
G03X1101256Y217359I1384J-754D01*
G02X1101281Y215076I-2015J-1164D01*
G01X1101256Y215034D01*
X1101237Y215000D01*
G03X1101256Y213459I1384J-754D01*
G01X1101610Y212901D01*
Y204694D01*
X1100904Y203988D01*
Y201347D01*
X1100134Y200577D01*
Y196901D01*
X1098514Y195281D01*
Y194298D01*
X1099376Y193436D01*
G01X1112761Y220096D02*
X1113999Y217238D01*
G03X1114126Y216984I2141J912D01*
G02X1114337Y216196I-1365J-788D01*
G01Y211038D01*
X1113815Y210516D01*
Y203056D01*
X1116443Y200428D01*
Y191423D01*
X1115616Y190596D01*
G01X1112761Y227896D02*
X1114126Y224784D01*
G02X1114313Y223727I-1365J-787D01*
G03X1114776Y221260I3741J-575D01*
G02Y218934I-2015J-1163D01*
G03Y217360I1365J-787D01*
G02X1114850Y217219I-1738J-1002D01*
G02X1115088Y216196I-2097J-1027D01*
G01Y210635D01*
X1114566Y210113D01*
Y203397D01*
X1117193Y200770D01*
Y191569D01*
X1118166Y190596D01*
G01X1109381Y218147D02*
X1108768Y216874D01*
X1108323Y215549D01*
X1108004Y215015D01*
X1107996Y215001D01*
G03X1108016Y213460I1385J-753D01*
G01X1108346Y212886D01*
Y203718D01*
X1106602Y201974D01*
Y199698D01*
X1107955Y198345D01*
Y189968D01*
X1108110Y189813D01*
Y189726D01*
G01X1109381Y229847D02*
Y228516D01*
X1109124Y228259D01*
G03X1107366Y227109I257J-2312D01*
G01X1107341Y227067D01*
G03X1107366Y224784I2040J-1119D01*
G03X1109296Y223622I2015J1163D01*
G01X1109425D01*
G02X1110746Y221260I-44J-1575D01*
G03Y218934I2015J-1163D01*
G02Y217360I-1365J-787D01*
G03Y215034I2015J-1163D01*
G01X1111261Y214147D01*
Y213497D01*
X1110795Y213031D01*
Y202460D01*
X1110150Y201815D01*
Y200211D01*
X1109250Y199311D01*
Y197389D01*
X1112136Y194503D01*
Y190855D01*
X1111981Y190700D01*
Y190613D01*
G01X1109381Y222047D02*
X1109374Y222032D01*
G02X1108016Y218934I-14719J4605D01*
G03X1107855Y217755I1365J-787D01*
G02X1107366Y215410I-3808J-429D01*
G01X1107361Y215401D01*
X1107337Y215360D01*
G03X1107365Y213087I2044J-1111D01*
G01X1107596Y212685D01*
Y204029D01*
X1105852Y202285D01*
Y199387D01*
X1107205Y198034D01*
Y189968D01*
X1107050Y189813D01*
Y189726D01*
G01X1109381Y225947D02*
Y227278D01*
X1109153Y227506D01*
G03X1108016Y226734I228J-1559D01*
G01X1107997Y226700D01*
G03X1108016Y225159I1384J-754D01*
G03X1109322Y224372I1365J788D01*
G01X1109466D01*
G02X1111396Y220884I-85J-2325D01*
G03Y219310I1365J-787D01*
G02Y216985I-2016J-1162D01*
G03Y215409I1365J-788D01*
G01X1112011Y214349D01*
Y213186D01*
X1111545Y212720D01*
Y202149D01*
X1110900Y201504D01*
Y199900D01*
X1110000Y199000D01*
Y197700D01*
X1112886Y194814D01*
Y190855D01*
X1113041Y190700D01*
Y190613D01*
G01X1126280Y220096D02*
X1126219Y220087D01*
X1124508Y217786D01*
X1124265Y217359D01*
G03X1124240Y215076I2015J-1164D01*
G01X1124265Y215034D01*
X1124284Y215000D01*
G02X1124265Y213459I-1384J-754D01*
G01X1123900Y212752D01*
Y211313D01*
X1127323Y207890D01*
Y205174D01*
X1133000Y199497D01*
Y197701D01*
G01X1126280Y227896D02*
X1127579Y224897D01*
X1127645Y224784D01*
G02X1127664Y223243I-1365J-787D01*
G01X1127645Y223209D01*
X1127620Y223167D01*
G03X1127645Y220884I2040J-1119D01*
G02X1126853Y218628I-1365J-788D01*
G01X1126366Y218423D01*
X1125644Y217889D01*
X1125099Y217303D01*
X1124915Y216984D01*
G03X1124896Y215443I1365J-787D01*
G01X1124915Y215409D01*
X1124940Y215367D01*
G02X1124915Y213084I-2040J-1119D01*
G01X1124650Y212570D01*
Y211625D01*
X1128073Y208202D01*
Y205489D01*
X1134600Y198962D01*
G01X1133040Y227896D02*
X1134109Y225679D01*
G03X1136335Y223622I2311J268D01*
G01X1138645D01*
X1141066Y221201D01*
Y212128D01*
X1147094Y206100D01*
X1149899D01*
X1150705Y205294D01*
G01X1151900Y206900D02*
X1147356D01*
X1141816Y212440D01*
Y221512D01*
X1138956Y224372D01*
X1136361D01*
G02X1135036Y226700I59J1575D01*
G01X1135055Y226734D01*
X1135080Y226776D01*
G03X1135055Y229059I-2040J1119D01*
G03X1133297Y230209I-2015J-1162D01*
G01X1133040Y230466D01*
Y231797D01*
G01X1122900Y222047D02*
X1121492D01*
X1121281Y221836D01*
Y220171D01*
G02X1121198Y219860I-636J3D01*
G01X1120885Y219309D01*
X1120860Y219267D01*
G03X1120885Y216984I2040J-1119D01*
G02X1120904Y215443I-1365J-787D01*
G01X1120885Y215409D01*
X1120860Y215367D01*
G03X1120885Y213084I2040J-1119D01*
G01X1121100Y212712D01*
Y210156D01*
X1124469Y206787D01*
Y203668D01*
X1128203Y199934D01*
Y196500D01*
X1129300Y195403D01*
Y194501D01*
G01X1122900Y225947D02*
X1124197Y222951D01*
X1124284Y222800D01*
G02X1123543Y220608I-1384J-753D01*
G01X1122727Y220278D01*
X1122112Y219724D01*
X1121697Y219215D01*
X1121516Y218900D01*
G03X1121535Y217359I1384J-754D01*
G02X1121560Y215076I-2015J-1164D01*
G01X1121535Y215034D01*
X1121516Y215000D01*
G03X1121535Y213459I1384J-754D01*
G01X1121850Y212963D01*
Y210467D01*
X1125219Y207098D01*
Y203981D01*
X1129000Y200200D01*
Y197301D01*
X1130000Y196301D01*
X1130800D01*
G01X1133040Y216196D02*
Y217527D01*
X1133297Y217784D01*
G03X1135055Y218934I-257J2312D01*
G02X1136376Y219722I1365J-787D01*
G01X1137095D01*
X1138046Y218771D01*
Y210881D01*
X1145200Y203727D01*
Y202900D01*
G01X1147000Y203900D02*
X1146088D01*
X1138796Y211192D01*
Y219081D01*
X1137407Y220470D01*
X1136422D01*
X1136420Y220472D01*
X1136350D01*
G03X1134405Y219309I70J-2325D01*
G02X1134224Y219057I-1380J800D01*
G02X1133268Y218537I-1184J1039D01*
G01X1133040Y218765D01*
Y220096D01*
G01X1129660Y218147D02*
X1128456Y217441D01*
X1128368Y217236D01*
X1128435Y217073D01*
G02X1128320Y215076I-2155J-878D01*
G01X1128295Y215034D01*
X1128276Y215000D01*
G03X1129601Y212672I1384J-753D01*
G01X1129711D01*
G02X1131675Y209183I-51J-2326D01*
G01X1131656Y209149D01*
G03X1131675Y207608I1384J-754D01*
G01X1132225Y206656D01*
X1137530Y201351D01*
X1137750D01*
X1137812Y201289D01*
G01X1129660Y225947D02*
Y227278D01*
X1129888Y227506D01*
G02X1131025Y226734I-228J-1559D01*
G01X1131044Y226700D01*
G02X1131025Y225159I-1384J-754D01*
G03X1131000Y222876I2015J-1164D01*
G01X1131025Y222834D01*
X1131044Y222800D01*
G02X1131025Y221259I-1384J-754D01*
G03X1131000Y218976I2015J-1164D01*
G01X1131025Y218934D01*
X1131044Y218900D01*
G02X1131025Y217359I-1384J-754D01*
G03X1130997Y215084I2015J-1162D01*
G03X1131184Y214794I2043J1112D01*
G03X1132970Y213871I1856J1402D01*
G01X1133099D01*
G02X1134424Y211543I-59J-1575D01*
G03X1134405Y209183I1998J-1196D01*
G03X1135293Y208313I2003J1156D01*
G01X1135295Y208312D01*
X1139787Y203820D01*
Y203600D01*
X1139849Y203538D01*
G01X1129660Y222047D02*
X1128806Y220522D01*
G02X1128320Y218976I-4113J444D01*
G01X1128295Y218934D01*
X1127556Y217541D01*
X1127645Y216984D01*
G02X1127740Y216790I-1364J-788D01*
G02X1127664Y215443I-1459J-593D01*
G02X1127620Y215367I-1486J809D01*
G03X1129609Y211921I2040J-1120D01*
G01X1129704D01*
G02X1131025Y209559I-44J-1575D01*
G03Y207233I2015J-1163D01*
G01X1131625Y206195D01*
X1137004Y200816D01*
Y200604D01*
X1137066Y200542D01*
G01X1129660Y229847D02*
Y228516D01*
X1129917Y228259D01*
G02X1131675Y227109I-257J-2312D01*
G01X1131700Y227067D01*
G02X1131675Y224784I-2040J-1119D01*
G03X1131656Y223243I1365J-787D01*
G01X1131675Y223209D01*
X1131700Y223167D01*
G02X1131675Y220884I-2040J-1119D01*
G03X1131656Y219343I1365J-787D01*
G01X1131675Y219309D01*
X1131700Y219267D01*
G02X1131675Y216984I-2040J-1119D01*
G03X1131656Y215443I1365J-787D01*
G03X1131783Y215246I1396J761D01*
G03X1132996Y214621I1257J950D01*
G01X1133125D01*
G02X1135055Y211133I-85J-2325D01*
G03Y209558I1364J-788D01*
G03X1135655Y208970I1353J781D01*
G01X1135750Y208918D01*
Y208919D01*
X1140319Y204350D01*
X1140537D01*
X1140599Y204288D01*
G01X1106001Y227896D02*
X1104702Y224897D01*
X1104636Y224784D01*
G03X1105071Y222724I1365J-788D01*
G01X1106476Y221774D01*
X1107200Y221172D01*
G01X1160075Y274696D02*
X1158481Y276290D01*
X1157051D01*
X1155041Y278300D01*
X1153839D01*
X1152566Y277027D01*
X1149451D01*
X1149045Y277433D01*
G03X1147724Y278221I-1365J-787D01*
G01X1147629D01*
G02X1145665Y279384I51J2326D01*
G03X1144359Y280171I-1365J-788D01*
G01X1144230D01*
G02X1142285Y281334I70J2325D01*
G03X1140964Y282122I-1365J-787D01*
G01X1140876D01*
G03X1139555Y281334I44J-1575D01*
G02X1137610Y280171I-2015J1162D01*
G01X1137470D01*
G02X1135525Y281334I70J2325D01*
G03X1134204Y282122I-1365J-787D01*
G01X1134116D01*
G03X1132795Y281334I44J-1575D01*
G02X1130850Y280171I-2015J1162D01*
G01X1130710D01*
G02X1128765Y281334I70J2325D01*
G03X1127444Y282122I-1365J-787D01*
G01X1127315D01*
G02X1125493Y282916I99J2715D01*
G01X1125049Y283360D01*
X1123280D01*
X1121820Y284820D01*
X1115760D01*
X1113240Y287340D01*
Y289410D01*
X1113661Y289831D01*
Y289902D01*
X1114630Y290871D01*
Y290981D01*
X1114701Y291052D01*
Y291877D01*
X1114702Y291878D01*
G01X1148652Y266700D02*
G02X1149497Y264673I-649J-1460D01*
G03X1149695Y262209I2697J-1023D01*
G03X1151016Y261421I1365J787D01*
G01X1151145D01*
G02X1153075Y260259I-85J-2325D01*
G03X1154381Y259472I1365J788D01*
G01X1155317D01*
G02X1157830Y258431I-1J-3556D01*
G01X1158303Y257958D01*
G03X1158752Y257772I449J449D01*
G01X1159055D01*
G02X1161088Y256930I0J-2875D01*
G01X1161607Y256411D01*
G02X1163111Y254574I-10656J-10258D01*
G02X1163215Y254409I-1914J-1322D01*
G01X1163216D01*
G03X1164523Y253621I1365J787D01*
G01X1164637D01*
G03X1165945Y254409I-57J1575D01*
G02X1167890Y255572I2015J-1162D01*
G01X1167960D01*
G03X1169196Y256172I-1J1575D01*
G01X1169113Y256482D01*
X1167960Y257147D01*
G01X1116096Y294005D02*
Y290684D01*
X1118810Y287970D01*
X1120169D01*
X1123859Y284280D01*
X1125415D01*
X1126035Y283660D01*
G03X1127356Y282872I1365J787D01*
G01X1127470D01*
G02X1129415Y281709I-70J-2325D01*
G03X1130736Y280921I1365J787D01*
G01X1130824D01*
G03X1132145Y281709I-44J1575D01*
G02X1134090Y282872I2015J-1162D01*
G01X1134230D01*
G02X1136175Y281709I-70J-2325D01*
G03X1137496Y280921I1365J787D01*
G01X1137584D01*
G03X1138905Y281709I-44J1575D01*
G02X1140850Y282872I2015J-1162D01*
G01X1140990D01*
G02X1142935Y281709I-70J-2325D01*
G03X1144256Y280921I1365J787D01*
G01X1144385D01*
G02X1146315Y279759I-85J-2325D01*
G03X1147621Y278972I1365J788D01*
G01X1150684D01*
X1151060Y278596D01*
G01X1147680Y261047D02*
X1146526Y260381D01*
X1146443Y260071D01*
G03X1147621Y259472I1238J976D01*
G01X1147750D01*
G02X1149695Y258309I-70J-2325D01*
G03X1151016Y257521I1365J787D01*
G01X1151145D01*
G02X1153075Y256359I-85J-2325D01*
G03X1154381Y255572I1365J788D01*
G01X1154440D01*
G02X1156455Y254410I0J-2328D01*
G03X1157801Y253622I1365J788D01*
G01X1157871D01*
G02X1159835Y252459I-51J-2326D01*
G03X1161141Y251672I1365J788D01*
G01X1161270D01*
G02X1163215Y250509I-70J-2325D01*
G03X1164533Y249721I1365J787D01*
G03X1164627I47J1575D01*
G03X1165945Y250509I-47J1575D01*
G02X1167890Y251672I2015J-1162D01*
G01X1167960D01*
G03X1169292Y252404I0J1578D01*
G01X1169322Y252456D01*
X1169324Y252460D01*
G02X1171241Y253621I2015J-1164D01*
G01X1171383D01*
G03X1172704Y255984I-44J1575D01*
G02X1172679Y258267I2015J1164D01*
G01X1172704Y258309D01*
X1172723Y258343D01*
G03X1172704Y259884I-1384J754D01*
G02X1174649Y263372I2015J1163D01*
G01X1174778D01*
G03X1176084Y264159I-59J1575D01*
G02X1178014Y265321I2015J-1163D01*
G01X1178143D01*
G03X1179464Y266109I-44J1575D01*
G02X1181479Y267272I2015J-1164D01*
G01X1181549D01*
G02X1183494Y266109I0J-2208D01*
G03X1184812Y265321I1365J787D01*
G03X1184906I47J1575D01*
G03X1186224Y266109I-47J1575D01*
G02X1188169Y267272I2015J-1162D01*
G01X1188309D01*
G02X1190254Y266109I-70J-2325D01*
G03X1191572Y265321I1365J787D01*
G03X1191666I47J1575D01*
G03X1192984Y266109I-47J1575D01*
G02X1194929Y267272I2015J-1162D01*
G01X1195069D01*
G02X1197014Y266109I-70J-2325D01*
G03X1198332Y265321I1365J787D01*
G03X1198426I47J1575D01*
G03X1199744Y266109I-47J1575D01*
G02X1201689Y267272I2015J-1162D01*
G01X1201759D01*
G02X1203774Y266109I0J-2327D01*
G03X1205095Y265321I1365J787D01*
G01X1205224D01*
G02X1207154Y264159I-85J-2325D01*
G03X1207405Y263833I1363J790D01*
G01X1207781Y263509D01*
X1208665Y262328D01*
X1208667Y262325D01*
X1208769Y262311D01*
X1208821Y262241D01*
G01X1144300Y259096D02*
X1145454Y259762D01*
X1145806Y259667D01*
G03X1147595Y258722I1873J1380D01*
G01X1147724D01*
G02X1149045Y257934I-44J-1575D01*
G03X1150990Y256771I2015J1162D01*
G01X1151119D01*
G02X1152425Y255984I-59J-1575D01*
G03X1154355Y254822I2015J1163D01*
G01X1154440D01*
G02X1155805Y254035I0J-1577D01*
G03X1157769Y252872I2015J1163D01*
G01X1157839D01*
G02X1159185Y252084I-19J-1576D01*
G03X1161115Y250922I2015J1163D01*
G01X1161244D01*
G02X1162565Y250134I-44J-1575D01*
G03X1164510Y248971I2015J1162D01*
G01X1164650D01*
G03X1166595Y250134I-70J2325D01*
G02X1167916Y250922I1365J-787D01*
G01X1168058D01*
G03X1169975Y252083I-98J2325D01*
G01X1169988Y252106D01*
G02X1171339Y252871I1351J-810D01*
G01X1171409D01*
G03X1173354Y256359I-70J2325D01*
G02X1173335Y257900I1365J787D01*
G01X1173354Y257934D01*
X1173379Y257976D01*
G03X1173354Y260259I-2040J1119D01*
G02X1174675Y262622I1365J788D01*
G01X1174804D01*
G03X1176734Y263784I-85J2325D01*
G02X1178040Y264571I1365J-788D01*
G01X1178169D01*
G03X1180114Y265734I-70J2325D01*
G02X1181479Y266522I1365J-788D01*
G01X1181523D01*
G02X1182844Y265734I0J-1501D01*
G03X1184789Y264571I2015J1162D01*
G01X1184929D01*
G03X1186874Y265734I-70J2325D01*
G02X1188192Y266522I1365J-787D01*
G02X1188286I47J-1575D01*
G02X1189604Y265734I-47J-1575D01*
G03X1191549Y264571I2015J1162D01*
G01X1191689D01*
G03X1193634Y265734I-70J2325D01*
G02X1194952Y266522I1365J-787D01*
G02X1195046I47J-1575D01*
G02X1196364Y265734I-47J-1575D01*
G03X1198309Y264571I2015J1162D01*
G01X1198449D01*
G03X1200394Y265734I-70J2325D01*
G02X1201759Y266522I1365J-788D01*
G02X1203124Y265734I0J-1576D01*
G03X1205069Y264571I2015J1162D01*
G01X1205198D01*
G02X1206503Y263785I-59J-1575D01*
G03X1206874Y263302I2015J1164D01*
G01X1207984Y261818D01*
X1207968Y261712D01*
X1208020Y261642D01*
G01X1165983Y318625D02*
X1167546Y317978D01*
X1168326D01*
X1169835Y318603D01*
G01X1103741Y383896D02*
X1102444Y386892D01*
X1102357Y387043D01*
G02X1102376Y388584I1384J754D01*
G01X1103024Y389707D01*
G02X1103741Y390121I717J-414D01*
G01X1103785D01*
G03X1105316Y391740I-44J1575D01*
G01Y393718D01*
X1104989Y394045D01*
Y401473D01*
X1101626Y404836D01*
Y409289D01*
X1098556Y412359D01*
Y416285D01*
X1097700Y417141D01*
G01X1103741Y387796D02*
X1105690Y390418D01*
X1105755Y390533D01*
X1105758D01*
X1105786Y390584D01*
G03X1106068Y391750I-2045J1112D01*
G01X1106064Y391754D01*
Y394028D01*
X1105737Y394355D01*
Y401783D01*
X1102374Y405146D01*
Y409599D01*
X1099304Y412669D01*
Y416171D01*
X1100274Y417141D01*
G01X1112325Y386097D02*
G03X1111866Y388586I-3743J597D01*
G02Y390912I2015J1163D01*
G03Y392484I-1362J786D01*
G02X1111765Y394614I2015J1163D01*
G02X1111866Y394808I1938J-886D01*
G03Y396382I-1365J787D01*
G01X1111841Y396424D01*
G02X1111866Y398707I2040J1119D01*
G03X1111885Y400248I-1365J787D01*
G01X1111866Y400282D01*
G02Y402608I2015J1163D01*
G01X1111885Y402642D01*
G03X1111866Y404183I-1384J754D01*
G02X1111554Y405347I2015J1164D01*
G01Y411578D01*
X1109544Y413588D01*
Y414682D01*
X1108776Y415450D01*
G01X1112325Y386097D02*
G03X1112391Y385338I1556J-247D01*
G01Y384076D01*
X1112106Y383791D01*
Y382301D01*
X1112460Y381947D01*
X1113881D01*
G01Y389747D02*
X1112728Y392368D01*
G03X1112516Y392859I-2227J-670D01*
G02X1112432Y394265I1377J788D01*
G02X1112516Y394432I1308J-553D01*
G03X1112541Y396715I-2015J1164D01*
G01X1112516Y396757D01*
X1112497Y396791D01*
G02X1112516Y398332I1384J754D01*
G03Y400658I-2015J1163D01*
G02Y402232I1365J787D01*
G01X1112541Y402274D01*
G03X1112516Y404559I-2040J1120D01*
G02X1112305Y405346I1365J788D01*
G01Y411890D01*
X1110295Y413900D01*
Y414454D01*
X1111326Y415485D01*
G01X1124021Y383896D02*
X1122724Y386892D01*
X1122637Y387043D01*
G02X1123538Y389296I1384J753D01*
G01X1123637Y389340D01*
G03X1125218Y390648I-1546J3478D01*
G03X1125385Y390910I-3270J2269D01*
G03Y392483I-1363J787D01*
G02X1125350Y394749I2015J1164D01*
G01X1125385Y394809D01*
G03Y396383I-1364J787D01*
G02X1125350Y398649I2015J1164D01*
G01X1125360Y398666D01*
X1125385Y398709D01*
G03Y400283I-1364J787D01*
G02X1125350Y402549I2015J1164D01*
G01X1125385Y402609D01*
G03Y404183I-1364J787D01*
G02X1125350Y406449I2015J1164D01*
G01X1125385Y406509D01*
G03Y408083I-1364J787D01*
G02X1125350Y410349I2015J1164D01*
G01X1125749Y411218D01*
Y417374D01*
X1127122Y418747D01*
Y420136D01*
G01X1124021Y387796D02*
G03X1125903Y390309I-11321J10439D01*
G01X1125906Y390314D01*
G03X1126071Y390595I-3642J2328D01*
G03X1126036Y392860I-2049J1101D01*
G02Y394434I1364J787D01*
G01X1126071Y394494D01*
G03X1126036Y396760I-2050J1102D01*
G02Y398334I1364J787D01*
G01X1126071Y398394D01*
G03X1126036Y400660I-2050J1102D01*
G02Y402234I1364J787D01*
G01X1126071Y402294D01*
G03X1126036Y404560I-2050J1102D01*
G02Y406134I1364J787D01*
G01X1126071Y406194D01*
G03X1126036Y408460I-2050J1102D01*
G02Y410034I1364J787D01*
G01X1126499Y411047D01*
Y417064D01*
X1127712Y418277D01*
X1128700D01*
G01X1110501Y383896D02*
X1109046D01*
X1108696Y384246D01*
Y386426D01*
X1108486Y386636D01*
G02X1108369Y386866I1906J1114D01*
G02X1108486Y388962I2132J932D01*
G03Y390536I-1365J787D01*
G02X1108285Y392408I2015J1163D01*
G02X1108486Y392859I2266J-740D01*
G03X1108513Y394385I-1365J787D01*
G01X1108451Y394493D01*
G02X1108486Y396759I2050J1102D01*
G03X1108513Y398285I-1365J787D01*
G01X1108451Y398393D01*
G02X1108486Y400659I2050J1102D01*
G03X1108513Y402185I-1365J787D01*
G01X1108451Y402293D01*
G02X1108173Y403395I2049J1103D01*
G01Y407012D01*
X1104574Y410611D01*
Y413838D01*
X1103676Y414736D01*
G01X1110501Y387796D02*
G03X1109136Y390912I-14773J-4615D01*
G02X1109000Y392178I1365J787D01*
G02X1109136Y392484I1462J-467D01*
G03X1109161Y394767I-2015J1164D01*
G01X1109136Y394809D01*
X1109109Y394857D01*
G02X1109136Y396383I1392J739D01*
G03X1109171Y398649I-2015J1164D01*
G01X1109161Y398666D01*
X1109109Y398757D01*
G02X1109136Y400283I1392J739D01*
G03X1109171Y402549I-2015J1164D01*
G01X1109109Y402657D01*
X1109108D01*
G02X1108924Y403396I1392J739D01*
G01Y407319D01*
X1105324Y410919D01*
Y413804D01*
X1106226Y414706D01*
G01X1120641Y381947D02*
X1121940Y384946D01*
X1122006Y385059D01*
G03X1121154Y387337I-1365J788D01*
G02X1119276Y388959I1394J3512D01*
G02X1119526Y390861I1364J788D01*
G01X1119562Y390896D01*
G02X1121376Y392255I5140J-4970D01*
G03X1121611Y392407I-735J1394D01*
G03X1122006Y392859I-981J1255D01*
G03X1122025Y394400I-1365J787D01*
G01X1122006Y394434D01*
X1121981Y394476D01*
G02X1122006Y396759I2040J1119D01*
G03X1122025Y398300I-1365J787D01*
G01X1122006Y398334D01*
X1121981Y398376D01*
G02X1122006Y400659I2040J1119D01*
G03X1122025Y402200I-1365J787D01*
G01X1122006Y402234D01*
X1121981Y402276D01*
G02X1122006Y404559I2040J1119D01*
G03X1122025Y406100I-1365J787D01*
G01X1122006Y406134D01*
X1121981Y406176D01*
G02X1122006Y408459I2040J1119D01*
G03X1122025Y410000I-1365J787D01*
G01X1121931Y410169D01*
Y417736D01*
X1121276Y418391D01*
G01X1120641Y389747D02*
X1122590Y392368D01*
X1122656Y392484D01*
G03X1122681Y394767I-2015J1164D01*
G01X1122656Y394809D01*
X1122637Y394843D01*
G02X1122656Y396384I1384J754D01*
G03X1122681Y398667I-2015J1164D01*
G01X1122656Y398709D01*
X1122637Y398743D01*
G02X1122656Y400284I1384J754D01*
G03X1122681Y402567I-2015J1164D01*
G01X1122656Y402609D01*
X1122637Y402643D01*
G02X1122656Y404184I1384J754D01*
G03X1122681Y406467I-2015J1164D01*
G01X1122656Y406509D01*
X1122637Y406543D01*
G02X1122656Y408084I1384J754D01*
G03X1122681Y410367I-2015J1164D01*
G01Y418079D01*
X1123826Y419224D01*
G01X1134160Y381947D02*
X1132211Y384568D01*
X1132145Y384684D01*
G02X1132120Y386967I2015J1164D01*
G01X1132145Y387009D01*
X1132164Y387043D01*
G03X1132145Y388584I-1384J754D01*
G02X1132120Y390867I2015J1164D01*
G01X1132145Y390909D01*
X1132164Y390943D01*
G03X1132145Y392484I-1384J754D01*
G02X1132120Y394767I2015J1164D01*
G01X1132355Y395173D01*
Y403864D01*
X1131837Y404382D01*
Y406586D01*
X1145400Y420149D01*
Y421150D01*
G01X1134160Y389747D02*
X1132861Y392746D01*
X1132795Y392859D01*
G02X1132776Y394400I1365J787D01*
G01X1133105Y394972D01*
Y404175D01*
X1132585Y404695D01*
Y406273D01*
X1145862Y419550D01*
X1147062D01*
G01X1144300Y395597D02*
Y396901D01*
X1143496Y397705D01*
X1142916Y398743D01*
G02X1142935Y400284I1384J754D01*
G01X1143077Y400504D01*
X1145256Y402683D01*
Y402684D01*
X1145260D01*
X1147924Y405348D01*
X1160640D01*
X1166392Y411100D01*
X1171199D01*
X1172099Y412000D01*
G01X1144300Y399496D02*
X1145787Y400983D01*
Y402149D01*
X1148236Y404598D01*
X1160952D01*
X1166704Y410350D01*
X1171250D01*
X1172100Y409500D01*
G01X1130780Y383896D02*
Y385227D01*
X1130523Y385484D01*
G02X1128765Y388959I257J2312D01*
G03X1128784Y390500I-1365J787D01*
G01X1128765Y390534D01*
X1128740Y390576D01*
G02X1128765Y392859I2040J1119D01*
G03X1128784Y394400I-1365J787D01*
G01X1128765Y394434D01*
X1128740Y394476D01*
G02X1128765Y396759I2040J1119D01*
G01X1129505Y398042D01*
Y402783D01*
X1128987Y403301D01*
Y409998D01*
X1134819Y415830D01*
G01X1130780Y387796D02*
Y386465D01*
X1130552Y386237D01*
G02X1129415Y388584I228J1559D01*
G03X1129440Y390867I-2015J1164D01*
G01X1129415Y390909D01*
X1129396Y390943D01*
G02X1129415Y392484I1384J754D01*
G03X1129440Y394767I-2015J1164D01*
G01X1129415Y394809D01*
X1129396Y394843D01*
G02X1129415Y396384I1384J754D01*
G01X1130255Y397840D01*
Y403094D01*
X1129737Y403612D01*
Y409687D01*
X1142000Y421950D01*
X1143300D01*
G01X1140920Y401447D02*
X1142187Y402714D01*
Y403651D01*
X1146736Y408200D01*
X1159288D01*
X1166488Y415400D01*
X1171800D01*
X1172400Y416000D01*
G01X1140920Y393647D02*
X1141776Y395801D01*
X1142285Y396759D01*
G03Y398333I-1365J787D01*
G02Y400659I2015J1163D01*
G01X1142937Y401788D01*
Y403339D01*
X1147048Y407450D01*
X1159600D01*
X1166800Y414650D01*
X1171800D01*
X1172350Y414100D01*
G01X1117261Y379996D02*
G02X1118961Y382310I10709J-6086D01*
G03X1117346Y386221I-1701J1586D01*
G01X1117217D01*
G02X1115921Y386967I0J1499D01*
G01X1115896Y387009D01*
X1115877Y387043D01*
G02X1115896Y388584I1384J754D01*
G03X1115921Y390867I-2015J1164D01*
G01X1115896Y390909D01*
G02Y392483I1365J787D01*
G01X1115921Y392525D01*
G03X1115896Y394808I-2040J1119D01*
G02X1115869Y396334I1365J787D01*
G01X1115931Y396442D01*
G03X1115896Y398708I-2050J1102D01*
G02X1115877Y400249I1365J787D01*
G01X1115896Y400283D01*
X1115921Y400325D01*
G03X1115896Y402608I-2040J1119D01*
G02Y404184I1365J788D01*
G03X1115922Y406463I-2015J1163D01*
G01X1115403Y407390D01*
Y412675D01*
X1114851Y413227D01*
Y416145D01*
X1115006Y416300D01*
Y416387D01*
G01X1137540Y379996D02*
Y381327D01*
X1137797Y381584D01*
G03X1137625Y386221I-257J2312D01*
G01X1137496D01*
G02X1136175Y388584I44J1575D01*
G03X1136200Y390867I-2015J1164D01*
G01X1136175Y390909D01*
X1136156Y390943D01*
G02X1136175Y392484I1384J754D01*
G03Y394810I-2015J1163D01*
G02Y396384I1365J787D01*
G01X1136200Y396426D01*
G03X1136175Y398709I-2040J1119D01*
G01X1136156Y398743D01*
G02X1136175Y400284I1384J754D01*
G03X1136200Y402567I-2015J1164D01*
G01X1136175Y402609D01*
X1136156Y402643D01*
G02X1136175Y404184I1384J754D01*
G01X1137084Y405759D01*
X1137237Y406025D01*
X1144462Y413250D01*
X1151300D01*
X1155339Y417289D01*
X1155559D01*
X1155621Y417351D01*
G01X1117261Y391696D02*
G02X1118518Y394622I14708J-4585D01*
G02X1118645Y394843I9038J-5047D01*
G03X1118626Y396384I-1384J754D01*
G02X1118601Y398667I2015J1164D01*
G01X1118626Y398709D01*
X1118645Y398743D01*
G03X1118626Y400284I-1384J754D01*
G02X1118601Y402567I2015J1164D01*
G01X1118626Y402609D01*
X1118645Y402643D01*
G03X1118626Y404184I-1384J754D01*
G02X1118601Y406467I2015J1164D01*
G01X1118626Y406509D01*
X1118645Y406543D01*
G03X1118626Y408084I-1384J754D01*
G02X1118314Y409248I2014J1164D01*
G01Y417088D01*
X1117791Y417611D01*
Y419645D01*
X1117636Y419800D01*
Y419887D01*
G01X1137540Y391696D02*
Y390365D01*
X1137768Y390137D01*
G03X1138847Y390816I-228J1559D01*
G03X1138905Y392484I-1307J880D01*
G02Y394810I2015J1163D01*
G03Y396384I-1365J787D01*
G01X1138880Y396426D01*
G02X1138905Y398709I2040J1119D01*
G01X1138924Y398743D01*
G03X1138905Y400284I-1384J754D01*
G02X1138880Y402567I2015J1164D01*
G01X1138930Y402651D01*
G03X1139337Y404253I-2955J1603D01*
G01Y404901D01*
X1145512Y411076D01*
X1152415D01*
X1156251Y414912D01*
X1156250Y415130D01*
G01X1117261Y383896D02*
X1115930D01*
X1115702Y383668D01*
G03X1118414Y382821I1559J228D01*
G03X1117320Y385471I-1153J1075D01*
G01X1117191D01*
G02X1115265Y386600I-2J2204D01*
G01X1115246Y386634D01*
X1115221Y386676D01*
G02X1115246Y388959I2040J1119D01*
G03X1115265Y390500I-1365J787D01*
G01X1115246Y390534D01*
G02Y392858I2015J1162D01*
G01X1115265Y392892D01*
G03X1115246Y394433I-1384J754D01*
G02X1115221Y396716I2015J1164D01*
G01X1115246Y396758D01*
X1115273Y396806D01*
G03X1115246Y398332I-1392J739D01*
G02X1115211Y400598I2015J1164D01*
G01X1115246Y400658D01*
X1115265Y400692D01*
G03X1115246Y402233I-1384J754D01*
G02Y404559I2015J1163D01*
G03X1115265Y406100I-1365J787D01*
G01X1114653Y407194D01*
Y412364D01*
X1114101Y412916D01*
Y416145D01*
X1113946Y416300D01*
Y416387D01*
G01X1137540Y383896D02*
Y382565D01*
X1137768Y382337D01*
G03X1137599Y385471I-227J1559D01*
G01X1137470D01*
G02X1135525Y388959I70J2325D01*
G03X1135544Y390500I-1365J787D01*
G01X1135525Y390534D01*
X1135500Y390576D01*
G02X1135525Y392859I2040J1119D01*
G03X1135544Y394400I-1365J787D01*
G01X1135525Y394434D01*
G02X1135500Y396717I2015J1164D01*
G01X1135525Y396759D01*
G03Y398333I-1365J787D01*
G02Y400659I2015J1163D01*
G03X1135544Y402200I-1365J787D01*
G01X1135525Y402234D01*
X1135500Y402276D01*
G02X1135525Y404559I2040J1119D01*
G01X1136218Y405759D01*
X1136487Y406226D01*
Y406337D01*
X1144150Y414000D01*
X1150989D01*
X1154810Y417821D01*
X1154809Y418039D01*
X1154870Y418100D01*
G01X1096981Y387796D02*
G02X1098346Y390912I14845J-4646D01*
G03X1098543Y391903I-1365J786D01*
G02X1098996Y394436I4215J553D01*
G03X1099307Y395597I-2015J1162D01*
G01D02*
Y396351D01*
G01X1117261Y387796D02*
G02X1118626Y390912I14845J-4646D01*
G03X1118823Y391903I-1365J786D01*
G02X1119162Y394203I4215J554D01*
G02X1119301Y394476I2929J-1319D01*
G03X1119276Y396759I-2040J1119D01*
G02X1119257Y398300I1365J787D01*
G01X1119276Y398334D01*
X1119301Y398376D01*
G03X1119276Y400659I-2040J1119D01*
G02X1119257Y402200I1365J787D01*
G01X1119276Y402234D01*
X1119301Y402276D01*
G03X1119276Y404559I-2040J1119D01*
G02X1119257Y406100I1365J787D01*
G01X1119286Y406151D01*
X1119301Y406179D01*
X1119304Y406184D01*
G03X1119276Y408459I-2043J1113D01*
G02X1119064Y409247I1364J790D01*
G01Y417399D01*
X1118541Y417922D01*
Y419645D01*
X1118696Y419800D01*
Y419887D01*
G01X1137540Y387796D02*
G03X1139470Y390396I-27406J22360D01*
G03X1139555Y392859I-1930J1300D01*
G02X1139536Y394400I1365J787D01*
G01X1139555Y394434D01*
G03X1139580Y396717I-2015J1164D01*
G01X1139555Y396759D01*
G02Y398333I1365J787D01*
G03Y400659I-2015J1163D01*
G02X1139536Y402200I1365J787D01*
G01X1139555Y402234D01*
X1139580Y402276D01*
G03X1140087Y404254I-3605J1978D01*
G01Y404590D01*
X1145823Y410326D01*
X1152726D01*
X1156900Y414500D01*
X1157120D01*
G01X1134819Y415830D02*
X1141600Y422611D01*
Y423500D01*
G01X1209993Y267272D02*
X1208460D01*
G02X1207154Y268059I59J1575D01*
G03X1205224Y269221I-2015J-1163D01*
G01X1205095D01*
G02X1203774Y270009I44J1575D01*
G03X1201829Y271172I-2015J-1162D01*
G01X1201700D01*
G02X1200394Y271959I59J1575D01*
G03X1198464Y273121I-2015J-1163D01*
G01X1198294D01*
G03X1196364Y271959I85J-2325D01*
G02X1195011Y271178I-1353J782D01*
G01X1193722D01*
X1192188Y272712D01*
X1190700D01*
X1189009Y274403D01*
X1187222D01*
X1185619Y272800D01*
X1184365D01*
X1182781Y274384D01*
X1180590D01*
X1178953Y272747D01*
X1174719D01*
G01X1233902Y173337D02*
X1231640Y175599D01*
X1225681D01*
X1223100Y178180D01*
G01X1210897Y262880D02*
Y264928D01*
X1209303Y266522D01*
X1208434D01*
G02X1206504Y267684I85J2325D01*
G03X1205198Y268471I-1365J-788D01*
G01X1205069D01*
G02X1203124Y269634I70J2325D01*
G03X1201803Y270422I-1365J-787D01*
G01X1201674D01*
G02X1199744Y271584I85J2325D01*
G03X1198438Y272371I-1365J-788D01*
G01X1198320D01*
G03X1197014Y271584I59J-1575D01*
G02X1195006Y270424I-2008J1158D01*
G01X1194021D01*
X1192726Y269129D01*
X1190407D01*
X1188966Y270570D01*
X1187464D01*
X1185792Y268898D01*
X1183793D01*
X1182781Y269910D01*
Y270126D01*
X1182252Y270655D01*
X1180898D01*
X1179053Y268810D01*
X1177150D01*
X1176679Y269281D01*
X1176553D01*
X1175113Y270721D01*
X1173900D01*
X1171728Y268549D01*
X1170171D01*
X1168345Y266723D01*
X1166520D01*
X1164578Y264781D01*
Y264359D01*
X1163419Y263200D01*
X1160130D01*
X1159390Y262460D01*
G01X1210691Y295707D02*
X1210628Y295770D01*
X1203054D01*
X1200645Y293361D01*
G03X1200394Y293034I1114J-1115D01*
G02X1198636Y291884I-2015J1162D01*
G01X1198379Y291627D01*
Y290296D01*
G01X1210691Y296607D02*
X1210604Y296520D01*
X1202743D01*
X1200114Y293892D01*
G03X1199744Y293409I1646J-1644D01*
G02X1198607Y292637I-1365J787D01*
G01X1198379Y292865D01*
Y294196D01*
G01X1209754Y291791D02*
X1209674Y291871D01*
X1204782D01*
G03X1203931Y291095I657J-1575D01*
G02X1202559Y289922I-2172J1152D01*
G01X1201715D01*
G03X1200394Y289134I44J-1575D01*
G02X1198449Y287971I-2015J1162D01*
G01X1198309D01*
G02X1196364Y289134I70J2325D01*
G03X1195043Y289922I-1365J-787D01*
G01X1194914D01*
G02X1192984Y291084I85J2325D01*
G03X1191678Y291871I-1365J-788D01*
G01X1191549D01*
G02X1189604Y293034I70J2325D01*
G03X1188283Y293822I-1365J-787D01*
G01X1188154D01*
G02X1186224Y294984I85J2325D01*
G03X1184918Y295771I-1365J-788D01*
G01X1184789D01*
G02X1182844Y296934I70J2325D01*
G03X1181523Y297722I-1365J-787D01*
G01X1181394D01*
G02X1179464Y298884I85J2325D01*
G03X1178158Y299671I-1365J-788D01*
G01X1178040D01*
G03X1176734Y298884I59J-1575D01*
G02X1174804Y297722I-2015J1163D01*
G01X1174634D01*
G02X1172704Y298884I85J2325D01*
G03X1171398Y299671I-1365J-788D01*
G01X1171269D01*
G02X1169324Y300834I70J2325D01*
G01X1169311Y300857D01*
G03X1166595Y300834I-1351J-810D01*
G02X1164650Y299671I-2015J1162D01*
G01X1164510D01*
G02X1162565Y300834I70J2325D01*
G03X1161428Y301606I-1365J-787D01*
G01X1161200Y301378D01*
Y300047D01*
G01X1209754Y292791D02*
X1209584Y292621D01*
X1204639D01*
G03X1203267Y291448I800J-2325D01*
G02X1202416Y290672I-1508J799D01*
G01X1201689D01*
G03X1199744Y289509I70J-2325D01*
G02X1197014I-1365J787D01*
G03X1195069Y290672I-2015J-1162D01*
G01X1194940D01*
G02X1193634Y291459I59J1575D01*
G03X1191704Y292621I-2015J-1163D01*
G01X1191575D01*
G02X1190254Y293409I44J1575D01*
G03X1188309Y294572I-2015J-1162D01*
G01X1188180D01*
G02X1186874Y295359I59J1575D01*
G03X1184944Y296521I-2015J-1163D01*
G01X1184815D01*
G02X1183494Y297309I44J1575D01*
G03X1181549Y298472I-2015J-1162D01*
G01X1181420D01*
G02X1180114Y299259I59J1575D01*
G03X1178184Y300421I-2015J-1163D01*
G01X1178014D01*
G03X1176084Y299259I85J-2325D01*
G02X1174778Y298472I-1365J788D01*
G01X1174660D01*
G02X1173354Y299259I59J1575D01*
G03X1171424Y300421I-2015J-1163D01*
G01X1171339D01*
G02X1169988Y301186I0J1575D01*
G01X1169975Y301209D01*
G03X1168030Y302372I-2015J-1162D01*
G01X1167890D01*
G03X1165945Y301209I70J-2325D01*
G02X1163215I-1365J787D01*
G03X1161457Y302359I-2015J-1162D01*
G01X1161200Y302616D01*
Y303947D01*
G01X1213777Y390900D02*
X1213690D01*
X1213490Y391100D01*
X1210710D01*
X1210360Y390750D01*
X1209260D01*
X1208910Y391100D01*
X1207810D01*
X1207032Y391878D01*
X1206537D01*
X1205759Y392656D01*
Y393151D01*
X1204930Y393980D01*
X1203606D01*
X1203256Y393630D01*
X1202156D01*
X1201806Y393980D01*
X1200706D01*
X1199788Y393062D01*
X1198688D01*
X1198338Y392712D01*
X1197238D01*
X1196888Y393062D01*
X1195788D01*
X1195438Y392712D01*
X1194338D01*
X1193988Y393062D01*
X1191500D01*
X1189328Y395234D01*
X1188259D01*
G03X1186874Y394434I0J-1599D01*
G02X1184929Y393271I-2015J1162D01*
G01X1184800D01*
G03X1183494Y392484I59J-1575D01*
G02X1181564Y391322I-2015J1163D01*
G01X1181435D01*
G03X1180114Y390534I44J-1575D01*
G02X1178169Y389371I-2015J1162D01*
G01X1178040D01*
G03X1176635Y387215I60J-1575D01*
G01X1176945Y387131D01*
X1177100Y387220D01*
X1177250Y387307D01*
X1178099Y387796D01*
G01X1209534Y389030D02*
X1209334Y388830D01*
X1206640D01*
X1203342Y392128D01*
X1199918D01*
X1199061Y391271D01*
X1190418D01*
X1189617Y392072D01*
X1188169D01*
G03X1186224Y390909I70J-2325D01*
G02X1184903Y390121I-1365J787D01*
G01X1184774D01*
G03X1182844Y388959I85J-2325D01*
G02X1181538Y388172I-1365J788D01*
G01X1181409D01*
G03X1179464Y387009I70J-2325D01*
G02X1178143Y386221I-1365J787D01*
G01X1178014D01*
G03X1176084Y385059I85J-2325D01*
G02X1174778Y384272I-1365J788D01*
G01X1174660D01*
G02X1173354Y385059I59J1575D01*
G03X1171595Y386209I-2015J-1162D01*
G01X1171339Y386465D01*
Y387796D01*
G01X1205296Y398121D02*
X1205209D01*
X1205009Y397921D01*
X1200425D01*
X1198416Y395912D01*
X1195859D01*
X1193850Y397921D01*
X1184790D01*
X1184789Y397922D01*
G03X1182844Y396759I70J-2325D01*
G02X1181550Y395972I-1365J787D01*
G01X1181394D01*
G03X1179464Y394810I85J-2325D01*
G02X1178143Y394022I-1365J787D01*
G01X1178048D01*
G03X1176084Y392859I51J-2326D01*
G02X1174778Y392072I-1365J788D01*
G01X1174649D01*
G03X1172845Y391126I69J-2325D01*
G01X1172493Y391031D01*
X1171339Y391696D01*
G01X1204732Y400766D02*
X1204645D01*
X1204445Y400966D01*
X1201375D01*
X1200249Y399840D01*
X1187614D01*
X1186382Y401072D01*
X1184818D01*
G03X1184800Y401071I78J-1574D01*
G03X1183494Y400284I59J-1575D01*
G02X1181530Y399121I-2015J1163D01*
G01X1181435D01*
G03X1180114Y398333I44J-1575D01*
G02X1178184Y397171I-2015J1163D01*
G01X1178055D01*
G03X1176734Y396383I44J-1575D01*
G02X1174804Y395221I-2015J1163D01*
G01X1174648D01*
G03X1173354Y394434I71J-1574D01*
G02X1171409Y393271I-2015J1162D01*
G01X1171269D01*
G02X1169465Y394217I69J2325D01*
G01X1169113Y394312D01*
X1167960Y393647D01*
G01X1164580Y395597D02*
Y394266D01*
X1164352Y394038D01*
G02X1163215Y394809I227J1559D01*
G02X1163199Y396355I1365J787D01*
G02X1164509Y397171I1381J-758D01*
G01X1164650D01*
G03X1166595Y398334I-70J2325D01*
G02X1167916Y399122I1365J-787D01*
G01X1168058D01*
G03X1169975Y400283I-98J2325D01*
G01X1169988Y400306D01*
G02X1171339Y401071I1351J-810D01*
G01X1171409D01*
G03X1173354Y402234I-70J2325D01*
G02X1174675Y403022I1365J-787D01*
G01X1174804D01*
G03X1176734Y404184I-85J2325D01*
G02X1178080Y404972I1365J-788D01*
G01X1178149D01*
G03X1180114Y406134I-50J2326D01*
G01X1180205Y406293D01*
X1181138Y407226D01*
X1183174D01*
X1184951Y405449D01*
X1188714D01*
X1189730Y405870D01*
X1190188Y405681D01*
X1191204Y406102D01*
X1191393Y406559D01*
X1193834Y407571D01*
X1196063Y409800D01*
X1198177D01*
X1198527Y409450D01*
X1199577D01*
X1199927Y409800D01*
X1200977D01*
X1201327Y409450D01*
X1202377D01*
X1202727Y409800D01*
X1203777D01*
X1204127Y409450D01*
X1205177D01*
X1205527Y409800D01*
X1208306D01*
X1209178Y410381D01*
Y410382D01*
X1209663Y410285D01*
X1210537Y410868D01*
X1210634Y411353D01*
X1211508Y411936D01*
X1211993Y411839D01*
X1212867Y412421D01*
X1212964Y412906D01*
X1217490Y415925D01*
X1217494Y415928D01*
X1217841Y415921D01*
G01X1205798Y405525D02*
X1205711D01*
X1205511Y405725D01*
X1202300D01*
X1200088Y403513D01*
X1198903Y403022D01*
X1181435D01*
G03X1180114Y402234I44J-1575D01*
G02X1178169Y401071I-2015J1162D01*
G01X1178040D01*
G03X1176734Y400284I59J-1575D01*
G02X1174770Y399121I-2015J1163D01*
G01X1174675D01*
G03X1173354Y398333I44J-1575D01*
G02X1171424Y397171I-2015J1163D01*
G01X1171291D01*
G03X1169975Y396384I48J-1574D01*
G02X1168030Y395221I-2015J1162D01*
G01X1167889D01*
G03X1166595Y392859I71J-1574D01*
G02X1166620Y390576I-2015J-1164D01*
G01X1166595Y390534D01*
X1166576Y390500D01*
G03X1166595Y388959I1384J-754D01*
G02X1166620Y386676I-2015J-1164D01*
G01X1166595Y386634D01*
G02X1164650Y385471I-2015J1162D01*
G01X1164510D01*
G02X1162565Y386634I70J2325D01*
G01X1162540Y386676D01*
G02X1162448Y388729I2039J1120D01*
G01X1162354Y389081D01*
X1161200Y389747D01*
G01X1210128Y380490D02*
X1210041D01*
X1209841Y380290D01*
X1208107D01*
X1204322Y384075D01*
X1201586D01*
X1199211Y386450D01*
X1197490D01*
X1196725Y385686D01*
X1196364Y385059D01*
G02X1195068Y384272I-1365J788D01*
G01X1194940D01*
G02X1193634Y385059I59J1575D01*
G03X1191704Y386221I-2015J-1163D01*
G01X1191534D01*
G03X1189604Y385059I85J-2325D01*
G02X1188298Y384272I-1365J788D01*
G01X1188169D01*
G03X1186224Y383109I70J-2325D01*
G02X1184903Y382321I-1365J787D01*
G01X1184774D01*
G03X1182844Y381159I85J-2325D01*
G02X1181538Y380372I-1365J788D01*
G01X1181409D01*
G03X1179464Y379209I70J-2325D01*
G02X1178327Y378437I-1365J787D01*
G01X1178099Y378665D01*
Y379996D01*
G01X1212490Y384416D02*
X1212403D01*
X1212203Y384216D01*
X1207545D01*
X1204911Y386850D01*
X1201911D01*
X1199741Y389020D01*
X1190409D01*
X1189561Y388172D01*
X1188185D01*
G03X1186224Y387009I54J-2325D01*
G02X1184903Y386221I-1365J787D01*
G01X1184774D01*
G03X1182844Y385059I85J-2325D01*
G02X1181538Y384272I-1365J788D01*
G01X1181409D01*
G03X1179605Y383326I69J-2325D01*
G01X1179253Y383231D01*
X1178099Y383896D01*
G01X1213777Y392050D02*
X1213690D01*
X1213490Y391850D01*
X1208121D01*
X1205241Y394730D01*
X1200395D01*
X1199477Y393812D01*
X1191811D01*
X1189639Y395984D01*
X1188258D01*
G03X1186224Y394809I1J-2349D01*
G02X1184916Y394021I-1365J787D01*
G01X1184774D01*
G03X1182844Y392859I85J-2325D01*
G02X1181538Y392072I-1365J788D01*
G01X1181409D01*
G03X1179464Y390909I70J-2325D01*
G02X1178143Y390121I-1365J787D01*
G01X1178014D01*
G03X1175967Y386863I85J-2325D01*
G01X1175873Y386512D01*
X1174719Y385847D01*
G01X1209621Y387880D02*
X1209534D01*
X1209334Y388080D01*
X1206329D01*
X1203031Y391378D01*
X1200229D01*
X1199372Y390521D01*
X1190107D01*
X1189306Y391322D01*
X1188195D01*
G03X1186874Y390534I44J-1575D01*
G02X1184929Y389371I-2015J1162D01*
G01X1184800D01*
G03X1183494Y388584I59J-1575D01*
G02X1181564Y387422I-2015J1163D01*
G01X1181435D01*
G03X1180114Y386634I44J-1575D01*
G02X1178169Y385471I-2015J1162D01*
G01X1178040D01*
G03X1176734Y384684I59J-1575D01*
G02X1174804Y383522I-2015J1163D01*
G01X1174634D01*
G02X1172704Y384684I85J2325D01*
G03X1171567Y385455I-1365J-789D01*
G01X1171339Y385227D01*
Y383896D01*
G01X1174719Y389747D02*
X1173565Y390412D01*
X1173482Y390722D01*
G02X1174675Y391322I1238J-975D01*
G01X1174804D01*
G03X1176734Y392484I-85J2325D01*
G02X1178040Y393271I1365J-788D01*
G01X1178150D01*
G03X1180114Y394434I-51J2326D01*
G02X1181408Y395221I1365J-787D01*
G01X1181549D01*
G03X1183494Y396384I-70J2325D01*
G02X1184788Y397171I1365J-787D01*
G01X1185838D01*
X1186188Y396821D01*
X1187238D01*
X1187588Y397171D01*
X1190639D01*
X1190989Y396821D01*
X1192089D01*
X1192439Y397171D01*
X1193539D01*
X1195548Y395162D01*
X1198727D01*
X1200736Y397171D01*
X1205009D01*
X1205209Y396971D01*
X1205296D01*
G01X1204732Y401916D02*
X1204645D01*
X1204445Y401716D01*
X1201064D01*
X1199938Y400590D01*
X1193725D01*
X1193375Y400940D01*
X1192275D01*
X1191925Y400590D01*
X1190825D01*
X1190475Y400940D01*
X1189375D01*
X1189025Y400590D01*
X1187925D01*
X1186693Y401822D01*
X1184808D01*
G03X1182844Y400659I51J-2326D01*
G02X1181538Y399872I-1365J788D01*
G01X1181428D01*
G03X1179464Y398709I51J-2326D01*
G02X1178143Y397921I-1365J787D01*
G01X1178014D01*
G03X1176084Y396759I85J-2325D01*
G02X1174790Y395972I-1365J787D01*
G01X1174649D01*
G03X1172704Y394809I70J-2325D01*
G02X1171387Y394022I-1364J787D01*
G02X1171292I-48J1574D01*
G02X1170103Y394621I48J1574D01*
G01X1170186Y394931D01*
X1171339Y395596D01*
G01X1164580Y391696D02*
G02X1162565Y394434I11319J10441D01*
G02X1162540Y396717I2015J1164D01*
G02X1164510Y397922I2039J-1120D01*
G01X1164651D01*
G03X1165945Y398709I-71J1574D01*
G02X1167890Y399872I2015J-1162D01*
G01X1167960D01*
G03X1169311Y400637I0J1575D01*
G01X1169324Y400660D01*
G02X1171241Y401821I2015J-1164D01*
G01X1171383D01*
G03X1172704Y402609I-44J1575D01*
G02X1174649Y403772I2015J-1162D01*
G01X1174778D01*
G03X1176084Y404559I-59J1575D01*
G02X1178048Y405722I2015J-1163D01*
G01X1178139D01*
X1178140Y405723D01*
G03X1179463Y406509I-41J1575D01*
G01X1179603Y406753D01*
X1180827Y407976D01*
X1183485D01*
X1185262Y406199D01*
X1188564D01*
X1193409Y408207D01*
X1195752Y410550D01*
X1208078D01*
X1217073Y416550D01*
X1217074D01*
X1217129Y416829D01*
X1217201Y416877D01*
G01X1205798Y406675D02*
X1205711D01*
X1205511Y406475D01*
X1201989D01*
X1199663Y404149D01*
X1198753Y403772D01*
X1195825D01*
X1195475Y404122D01*
X1194425D01*
X1194075Y403772D01*
X1193025D01*
X1192675Y404122D01*
X1191575D01*
X1191225Y403772D01*
X1190125D01*
X1189775Y404122D01*
X1188675D01*
X1188325Y403772D01*
X1187225D01*
X1186875Y404122D01*
X1185775D01*
X1185425Y403772D01*
X1184325D01*
X1183975Y404122D01*
X1182875D01*
X1182525Y403772D01*
X1181425D01*
G03X1179464Y402609I54J-2325D01*
G02X1178143Y401821I-1365J787D01*
G01X1178014D01*
G03X1176084Y400659I85J-2325D01*
G02X1174778Y399872I-1365J788D01*
G01X1174668D01*
G03X1172704Y398709I51J-2326D01*
G02X1171410Y397922I-1365J787D01*
G01X1171269D01*
G03X1169324Y396759I70J-2325D01*
G02X1168008Y395972I-1364J787D01*
G01X1167875D01*
G03X1165945Y392484I85J-2325D01*
G02X1165964Y390943I-1365J-787D01*
G01X1165945Y390909D01*
X1165920Y390867D01*
G03X1165945Y388584I2040J-1119D01*
G02X1165964Y387043I-1365J-787D01*
G01X1165945Y387009D01*
G02X1164624Y386221I-1365J787D01*
G01X1164536D01*
G02X1163215Y387009I44J1575D01*
G01X1163196Y387043D01*
G02X1163116Y388378I1385J753D01*
G01X1163426Y388462D01*
X1164580Y387796D01*
G01X1210128Y379340D02*
X1210041D01*
X1209841Y379540D01*
X1207796D01*
X1204011Y383325D01*
X1201275D01*
X1198900Y385700D01*
X1197801D01*
X1197327Y385227D01*
X1197326Y385225D01*
X1197014Y384684D01*
G02X1195084Y383522I-2015J1163D01*
G01X1194914D01*
G02X1192984Y384684I85J2325D01*
G03X1191678Y385471I-1365J-788D01*
G01X1191560D01*
G03X1190254Y384684I59J-1575D01*
G02X1188324Y383522I-2015J1163D01*
G01X1188195D01*
G03X1186874Y382734I44J-1575D01*
G02X1184929Y381571I-2015J1162D01*
G01X1184800D01*
G03X1183494Y380784I59J-1575D01*
G02X1181564Y379622I-2015J1163D01*
G01X1181435D01*
G03X1180114Y378834I44J-1575D01*
G02X1178356Y377684I-2015J1162D01*
G01X1178099Y377427D01*
Y376096D01*
G01X1212490Y383266D02*
X1212403D01*
X1212203Y383466D01*
X1207234D01*
X1204600Y386100D01*
X1201600D01*
X1199430Y388270D01*
X1197472D01*
X1197122Y387920D01*
X1196022D01*
X1195672Y388270D01*
X1194572D01*
X1194222Y387920D01*
X1193122D01*
X1192772Y388270D01*
X1190720D01*
X1189872Y387422D01*
X1188195D01*
G03X1186874Y386634I44J-1575D01*
G02X1184929Y385471I-2015J1162D01*
G01X1184800D01*
G03X1183494Y384684I59J-1575D01*
G02X1181564Y383522I-2015J1163D01*
G01X1181435D01*
G03X1180242Y382922I45J-1575D01*
G01X1180325Y382612D01*
X1181479Y381947D01*
G01X1188239Y354647D02*
Y353316D01*
X1188467Y353088D01*
G03X1189604Y353859I-228J1560D01*
G02X1191534Y355021I2015J-1163D01*
G01X1191704D01*
G02X1193634Y353859I-85J-2325D01*
G03X1194940Y353072I1365J788D01*
G01X1195058D01*
G03X1196364Y353859I-59J1575D01*
G02X1198294Y355021I2015J-1163D01*
G01X1199479D01*
X1201000Y353500D01*
X1202350D01*
X1202550Y353700D01*
X1202637D01*
G01X1214487Y355220D02*
X1214400D01*
X1214200Y355020D01*
X1211779D01*
X1209378Y355950D01*
X1202050D01*
X1200917Y357083D01*
G02X1200407Y357736I2400J2400D01*
G01Y357738D01*
G03X1198463Y358921I-2027J-1142D01*
G01X1198307D01*
G03X1196364Y357759I72J-2325D01*
G02X1195058Y356972I-1365J788D01*
G01X1194940D01*
G02X1193634Y357759I59J1575D01*
G03X1191704Y358921I-2015J-1163D01*
G01X1191534D01*
G03X1189745Y357976I84J-2325D01*
G01X1189393Y357881D01*
X1188239Y358547D01*
G01X1211497Y360250D02*
X1211410D01*
X1211210Y360050D01*
X1209802D01*
X1209452Y360400D01*
X1208402D01*
X1208052Y360050D01*
X1207002D01*
X1205743Y358791D01*
X1204579D01*
X1203928Y359443D01*
X1203774Y359709D01*
G03X1201829Y360872I-2015J-1162D01*
G01X1201690D01*
G02X1200394Y361659I69J1575D01*
G03X1198451Y362821I-2015J-1163D01*
G01X1198307D01*
G03X1196364Y361659I72J-2325D01*
G02X1195068Y360872I-1365J788D01*
G01X1194930D01*
G02X1193634Y361659I69J1575D01*
G03X1191691Y362821I-2015J-1163D01*
G01X1191547D01*
G03X1189604Y361659I72J-2325D01*
G02X1188308Y360872I-1365J788D01*
G01X1188169D01*
G02X1187002Y361471I71J1574D01*
G01X1187001Y361470D01*
X1187085Y361781D01*
X1188239Y362447D01*
G01X1200187Y366921D02*
X1200100D01*
X1199900Y366721D01*
X1198294D01*
G03X1196364Y365559I85J-2325D01*
G02X1195058Y364772I-1365J788D01*
G01X1194940D01*
G02X1193634Y365559I59J1575D01*
G03X1191704Y366721I-2015J-1163D01*
G01X1191534D01*
G03X1189604Y365559I85J-2325D01*
G02X1188298Y364772I-1365J788D01*
G01X1188169D01*
G03X1186224Y363609I70J-2325D01*
G02X1184903Y362821I-1365J787D01*
G01X1184774D01*
G03X1182844Y361659I85J-2325D01*
G02X1181707Y360888I-1365J789D01*
G01X1181479Y361116D01*
Y362447D01*
G01X1207479Y365929D02*
X1207392D01*
X1207192Y365729D01*
X1206481D01*
X1202570Y369640D01*
X1197770D01*
X1197080Y369130D01*
X1195290Y368672D01*
X1194940D01*
G02X1193634Y369459I59J1575D01*
G03X1191706Y370621I-2015J-1163D01*
G03X1191532I-87J-2325D01*
G03X1189604Y369459I87J-2325D01*
G02X1188298Y368672I-1365J788D01*
G01X1188169D01*
G03X1186224Y367509I70J-2325D01*
G02X1184903Y366721I-1365J787D01*
G01X1184774D01*
G03X1182985Y365776I84J-2325D01*
G01X1182633Y365681D01*
X1181479Y366347D01*
G01X1184859Y372197D02*
Y370866D01*
X1185087Y370638D01*
G03X1186224Y371410I-228J1559D01*
G02X1188154Y372572I2015J-1163D01*
G01X1188310D01*
G03X1189604Y373359I-71J1574D01*
G02X1191549Y374522I2015J-1162D01*
G01X1191689D01*
G02X1193634Y373359I-70J-2325D01*
G03X1194928Y372572I1365J787D01*
G01X1195070D01*
G03X1196364Y373359I-71J1574D01*
G02X1198309Y374522I2015J-1162D01*
G01X1198449D01*
G02X1200394Y373359I-70J-2325D01*
G03X1201500Y372400I1938J1118D01*
G01X1204161D01*
X1208298Y368263D01*
X1212153D01*
X1212353Y368463D01*
X1212440D01*
G01X1184859Y376096D02*
X1186013Y375431D01*
X1186365Y375526D01*
G02X1188188Y376472I1873J-1380D01*
G01X1188298D01*
G03X1189604Y377259I-59J1575D01*
G02X1191534Y378421I2015J-1163D01*
G01X1191704D01*
G02X1193634Y377259I-85J-2325D01*
G03X1194940Y376472I1365J788D01*
G01X1195058D01*
G03X1196364Y377259I-59J1575D01*
G02X1198294Y378421I2015J-1163D01*
G01X1198464D01*
G02X1200394Y377259I-85J-2325D01*
G03X1201700Y376472I1365J788D01*
G03X1201718Y376471I96J1573D01*
G01X1204410D01*
X1208309Y372572D01*
X1211720D01*
X1211920Y372772D01*
X1212007D01*
G01X1184859Y379996D02*
X1183705Y379331D01*
X1183622Y379021D01*
G03X1186224Y379209I1237J974D01*
G02X1188169Y380372I2015J-1162D01*
G01X1188298D01*
G03X1189604Y381159I-59J1575D01*
G02X1191534Y382321I2015J-1163D01*
G01X1191704D01*
G02X1193634Y381159I-85J-2325D01*
G03X1194940Y380372I1365J788D01*
G01X1195058D01*
G03X1196364Y381159I-59J1575D01*
G02X1198294Y382321I2015J-1163D01*
G01X1198423D01*
G03X1198727Y382359I-42J1575D01*
G01X1199602D01*
X1200061Y381900D01*
X1201462D01*
X1202204Y381158D01*
X1202699D01*
X1203442Y380415D01*
Y379920D01*
X1204184Y379178D01*
X1204679D01*
X1205422Y378435D01*
Y377940D01*
X1206648Y376714D01*
X1210887D01*
X1211087Y376914D01*
X1211174D01*
G01X1188239Y350747D02*
Y352078D01*
X1188495Y352334D01*
G03X1190254Y353484I-256J2312D01*
G02X1191560Y354271I1365J-788D01*
G01X1191678D01*
G02X1192984Y353484I-59J-1575D01*
G03X1194914Y352322I2015J1163D01*
G01X1195084D01*
G03X1197014Y353484I-85J2325D01*
G02X1198320Y354271I1365J-788D01*
G01X1199168D01*
X1200689Y352750D01*
X1202350D01*
X1202550Y352550D01*
X1202637D01*
G01X1214487Y354070D02*
X1214400D01*
X1214200Y354270D01*
X1211638D01*
X1209237Y355200D01*
X1207409D01*
X1207059Y354850D01*
X1206009D01*
X1205659Y355200D01*
X1204609D01*
X1204259Y354850D01*
X1203209D01*
X1202859Y355200D01*
X1201739D01*
X1200386Y356552D01*
G02X1199797Y357295I2932J2929D01*
G02X1199747Y357378I2070J1304D01*
G01X1199744Y357384D01*
G03X1198448Y358171I-1365J-788D01*
G01X1198320D01*
G03X1197014Y357384I59J-1575D01*
G02X1195084Y356222I-2015J1163D01*
G01X1194914D01*
G02X1192984Y357384I85J2325D01*
G03X1191678Y358171I-1365J-788D01*
G01X1191560D01*
G03X1190382Y357572I60J-1575D01*
G01X1190465Y357262D01*
X1191619Y356596D01*
G01X1184859Y360496D02*
G03X1185762Y360122I903J903D01*
G01X1188324D01*
G03X1190254Y361284I-85J2325D01*
G02X1191560Y362071I1365J-788D01*
G01X1191678D01*
G02X1192984Y361284I-59J-1575D01*
G03X1194914Y360122I2015J1163D01*
G01X1195084D01*
G03X1197014Y361284I-85J2325D01*
G02X1198320Y362071I1365J-788D01*
G01X1198438D01*
G02X1199744Y361284I-59J-1575D01*
G03X1201674Y360122I2015J1163D01*
G01X1201816D01*
G02X1203124Y359334I-57J-1575D01*
G01X1203327Y358982D01*
X1204268Y358041D01*
X1206054D01*
X1207313Y359300D01*
X1211210D01*
X1211410Y359100D01*
X1211497D01*
G01X1200187Y365771D02*
X1200100D01*
X1199900Y365971D01*
X1198320D01*
G03X1197014Y365184I59J-1575D01*
G02X1195084Y364022I-2015J1163D01*
G01X1194914D01*
G02X1192984Y365184I85J2325D01*
G03X1191678Y365971I-1365J-788D01*
G01X1191560D01*
G03X1190254Y365184I59J-1575D01*
G02X1188324Y364022I-2015J1163D01*
G01X1188195D01*
G03X1186874Y363234I44J-1575D01*
G02X1184929Y362071I-2015J1162D01*
G01X1184800D01*
G03X1183494Y361284I59J-1575D01*
G02X1181735Y360134I-2015J1162D01*
G01X1181479Y359878D01*
Y358547D01*
G01X1207479Y364779D02*
X1207392D01*
X1207192Y364979D01*
X1206170D01*
X1204411Y366738D01*
X1203916D01*
X1203138Y367516D01*
Y368011D01*
X1202259Y368890D01*
X1201159D01*
X1200809Y368540D01*
X1199709D01*
X1199359Y368890D01*
X1198018D01*
X1197408Y368439D01*
X1195385Y367922D01*
X1194914D01*
G02X1192984Y369084I85J2325D01*
G03X1191678Y369871I-1365J-788D01*
G01X1191560D01*
G03X1190254Y369084I59J-1575D01*
G02X1188324Y367922I-2015J1163D01*
G01X1188195D01*
G03X1186874Y367134I44J-1575D01*
G02X1184929Y365971I-2015J1162D01*
G01X1184800D01*
G03X1183622Y365372I60J-1575D01*
G01X1183705Y365062D01*
X1184859Y364396D01*
G01X1212440Y367313D02*
X1212353D01*
X1212153Y367513D01*
X1207987D01*
X1203850Y371650D01*
X1201366D01*
G02X1199744Y372984I966J2828D01*
G03X1198450Y373771I-1365J-787D01*
G01X1198308D01*
G03X1197014Y372984I71J-1574D01*
G02X1195069Y371821I-2015J1162D01*
G01X1194929D01*
G02X1192984Y372984I70J2325D01*
G03X1191690Y373771I-1365J-787D01*
G01X1191548D01*
G03X1190254Y372984I71J-1574D01*
G02X1188309Y371821I-2015J1162D01*
G01X1188168D01*
G03X1186874Y371034I71J-1574D01*
G02X1185116Y369884I-2015J1162D01*
G01X1184859Y369627D01*
Y368296D01*
G01X1212007Y371622D02*
X1211920D01*
X1211720Y371822D01*
X1207998D01*
X1204099Y375721D01*
X1201708D01*
G02X1199744Y376884I51J2326D01*
G03X1198438Y377671I-1365J-788D01*
G01X1198320D01*
G03X1197014Y376884I59J-1575D01*
G02X1195086Y375722I-2015J1163D01*
G02X1194912I-87J2325D01*
G02X1192984Y376884I87J2325D01*
G03X1191678Y377671I-1365J-788D01*
G01X1191560D01*
G03X1190254Y376884I59J-1575D01*
G02X1188290Y375721I-2015J1163D01*
G01X1188195D01*
G03X1187002Y375121I45J-1575D01*
G03X1188239Y374146I619J-487D01*
G01X1181479Y378047D02*
X1182633Y378712D01*
X1182985Y378617D01*
G03X1186874Y378834I1874J1378D01*
G02X1188182Y379622I1365J-787D01*
G01X1188311D01*
G03X1190254Y380784I-72J2325D01*
G02X1191550Y381571I1365J-788D01*
G01X1191688D01*
G02X1192984Y380784I-69J-1575D01*
G03X1194927Y379622I2015J1163D01*
G01X1195071D01*
G03X1197014Y380784I-72J2325D01*
G02X1198310Y381571I1365J-788D01*
G01X1198433D01*
G03X1198803Y381609I-52J2325D01*
G01X1199291D01*
X1199750Y381150D01*
X1201151D01*
X1206337Y375964D01*
X1210887D01*
X1211087Y375764D01*
X1211174D01*
G01X1446813Y454250D02*
X1446900D01*
X1447100Y454050D01*
X1448650D01*
X1451179Y451521D01*
X1451674D01*
X1452452Y450743D01*
Y450248D01*
X1453229Y449471D01*
X1453724D01*
X1454502Y448693D01*
Y448198D01*
X1455180Y447520D01*
X1457879D01*
X1458229Y447870D01*
X1459329D01*
X1459679Y447520D01*
X1460779D01*
X1461129Y447870D01*
X1462229D01*
X1462579Y447520D01*
X1463679D01*
X1464029Y447870D01*
X1465129D01*
X1465479Y447520D01*
X1466579D01*
X1466929Y447870D01*
X1468029D01*
X1468379Y447520D01*
X1469479D01*
X1469829Y447870D01*
X1470929D01*
X1471279Y447520D01*
X1472379D01*
X1473407Y448548D01*
Y449043D01*
X1474184Y449820D01*
X1474679D01*
X1475457Y450598D01*
Y451093D01*
X1476235Y451871D01*
X1476730D01*
X1477508Y452649D01*
Y453144D01*
X1478286Y453922D01*
X1478781D01*
X1479558Y454699D01*
Y455194D01*
X1480336Y455972D01*
X1480831D01*
X1481609Y456750D01*
X1484389D01*
X1485050Y457411D01*
Y461391D01*
X1486746Y463087D01*
X1487607D01*
X1488688Y462460D01*
G03X1490263Y462461I787J1366D01*
G02X1492587I1162J-2015D01*
G03X1494163I788J1365D01*
G02X1496487I1162J-2015D01*
G03X1498850Y463757I788J1365D01*
G01Y463880D01*
G02X1500013Y465841I2325J-54D01*
G03X1500800Y467137I-788J1365D01*
G01Y467275D01*
G03X1497666Y467434I-1575J-71D01*
G01X1497894Y467206D01*
X1499225D01*
G01X1460772Y457648D02*
X1460859D01*
X1461059Y457448D01*
X1473546D01*
X1482287Y466189D01*
X1486434D01*
X1487367Y465256D01*
G01X1458010Y463250D02*
X1458097D01*
X1458297Y463050D01*
X1462230D01*
X1462580Y463400D01*
X1463680D01*
X1464030Y463050D01*
X1465130D01*
X1465480Y463400D01*
X1466580D01*
X1466930Y463050D01*
X1468030D01*
X1469570Y461510D01*
X1471050D01*
X1471400Y461860D01*
X1472500D01*
X1472850Y461510D01*
X1473950D01*
X1474578Y462138D01*
Y462633D01*
X1475356Y463411D01*
X1475851D01*
X1476629Y464189D01*
Y464684D01*
X1477407Y465462D01*
X1477902D01*
X1478679Y466239D01*
Y466734D01*
X1479457Y467512D01*
X1479952D01*
X1480730Y468290D01*
X1487151D01*
X1489718Y466373D01*
X1490638Y465841D01*
G03X1492212I787J1365D01*
G03X1493000Y467162I-787J1365D01*
G01Y467250D01*
G03X1492400Y468443I-1575J-45D01*
G01X1492090Y468360D01*
X1491425Y467206D01*
G01X1460883Y472450D02*
X1460970D01*
X1461170Y472250D01*
X1487707D01*
X1488312Y472601D01*
G02X1490638I1163J-2015D01*
G03X1493000Y473922I787J1365D01*
G01Y474051D01*
G02X1494162Y475981I2325J-85D01*
G02X1496488I1163J-2015D01*
G02X1497650Y474051I-1163J-2015D01*
G01Y473881D01*
G02X1496705Y472092I-2325J84D01*
G01X1496610Y471740D01*
X1497275Y470586D01*
G01X1468200Y476364D02*
X1468287D01*
X1468487Y476164D01*
X1486031D01*
X1486217Y476350D01*
X1488050D01*
X1488688Y475981D01*
G03X1491050Y477302I787J1365D01*
G01Y477431D01*
G02X1495688Y477602I2325J-85D01*
G01X1495944Y477346D01*
X1497275D01*
G01X1489475D02*
X1490140Y478500D01*
X1490056Y478810D01*
G03X1488688Y478711I-582J-1464D01*
G02X1487525Y478399I-1164J2015D01*
G01X1486190D01*
X1485201Y479388D01*
X1481064D01*
X1480296Y478620D01*
X1479143D01*
X1478793Y478270D01*
X1477693D01*
X1477343Y478620D01*
X1475860D01*
X1475660Y478420D01*
X1475573D01*
G01X1460194Y482620D02*
X1460281D01*
X1460481Y482420D01*
X1478320D01*
X1480000Y484100D01*
X1485404D01*
X1487099Y485795D01*
G03X1488312Y486121I0J2420D01*
G02X1490637I1162J-2015D01*
G01X1490638D01*
G03X1492212I787J1365D01*
G02X1494538I1163J-2015D01*
G02X1495700Y484191I-1163J-2015D01*
G01Y484062D01*
G03X1496488Y482741I1575J44D01*
G02X1497650Y480811I-1163J-2015D01*
G01Y480682D01*
G03X1498438Y479361I1575J44D01*
G03X1500012I787J1365D01*
G02X1502338I1163J-2015D01*
G02X1503500Y477431I-1163J-2015D01*
G01Y477261D01*
G02X1502338Y475331I-2325J85D01*
G02X1500242Y475214I-1164J2015D01*
G01X1499890Y475120D01*
X1499225Y473966D01*
G01X1446900Y453100D02*
X1447100Y453300D01*
X1448339D01*
X1454869Y446770D01*
X1472690D01*
X1481920Y456000D01*
X1484700D01*
X1485800Y457100D01*
Y461080D01*
X1487057Y462337D01*
X1487405D01*
X1488312Y461811D01*
G03X1490638I1163J2015D01*
G02X1492212I787J-1365D01*
G03X1494538I1163J2015D01*
G02X1496112I787J-1365D01*
G03X1499600Y463741I1163J2015D01*
G01Y463870D01*
G02X1500388Y465191I1575J-44D01*
G03X1501550Y467121I-1163J2015D01*
G01Y467291D01*
G03X1496912Y467462I-2325J-85D01*
G01X1496656Y467206D01*
X1495325D01*
G01X1460772Y456498D02*
X1460859D01*
X1461059Y456698D01*
X1465457D01*
X1465807Y456348D01*
X1466857D01*
X1467207Y456698D01*
X1468257D01*
X1468607Y456348D01*
X1469657D01*
X1470007Y456698D01*
X1471057D01*
X1471407Y456348D01*
X1472457D01*
X1472807Y456698D01*
X1473857D01*
X1474599Y457440D01*
X1475094D01*
X1475837Y458183D01*
Y458678D01*
X1476579Y459420D01*
X1477074D01*
X1477817Y460163D01*
Y460658D01*
X1478559Y461400D01*
X1479054D01*
X1479797Y462143D01*
Y462638D01*
X1482595Y465436D01*
X1486123D01*
G01X1458010Y462100D02*
X1458097D01*
X1458297Y462300D01*
X1467719D01*
X1469259Y460760D01*
X1474261D01*
X1481041Y467540D01*
X1486901D01*
X1489307Y465743D01*
X1489308D01*
X1490260Y465192D01*
X1490262Y465191D01*
G03X1492588I1163J2015D01*
G03X1493750Y467121I-1163J2015D01*
G01Y467291D01*
G03X1492805Y469080I-2325J-84D01*
G01X1492710Y469432D01*
X1493375Y470586D01*
G01X1495325Y473966D02*
X1495990Y472812D01*
X1496300Y472729D01*
G03X1496900Y473922I-975J1238D01*
G01Y474010D01*
G03X1496112Y475331I-1575J-44D01*
G03X1494538I-787J-1365D01*
G03X1493750Y474010I787J-1365D01*
G01Y473881D01*
G02X1490262Y471951I-2325J85D01*
G03X1488688I-787J-1365D01*
G01X1488038Y471575D01*
X1487963Y471500D01*
X1480087D01*
X1479737Y471150D01*
X1478637D01*
X1478287Y471500D01*
X1477187D01*
X1476837Y471150D01*
X1475737D01*
X1475387Y471500D01*
X1474287D01*
X1473937Y471150D01*
X1472837D01*
X1472487Y471500D01*
X1471387D01*
X1471037Y471150D01*
X1469937D01*
X1469587Y471500D01*
X1468487D01*
X1468137Y471150D01*
X1467037D01*
X1466687Y471500D01*
X1465587D01*
X1465237Y471150D01*
X1464137D01*
X1463787Y471500D01*
X1461170D01*
X1460970Y471300D01*
X1460883D01*
G01X1493375Y477346D02*
X1494706D01*
X1494934Y477574D01*
G03X1491800Y477390I-1559J-228D01*
G01Y477261D01*
G02X1488312Y475331I-2325J85D01*
G01X1487848Y475600D01*
X1486528D01*
X1486342Y475414D01*
X1480087D01*
X1479737Y475064D01*
X1478637D01*
X1478287Y475414D01*
X1477187D01*
X1476837Y475064D01*
X1475737D01*
X1475387Y475414D01*
X1474287D01*
X1473937Y475064D01*
X1472837D01*
X1472487Y475414D01*
X1471387D01*
X1471037Y475064D01*
X1469937D01*
X1469587Y475414D01*
X1468487D01*
X1468287Y475214D01*
X1468200D01*
G01X1491425Y480726D02*
X1490760Y479572D01*
X1490408Y479478D01*
G03X1488312Y479361I-932J-2132D01*
G02X1487524Y479149I-790J1364D01*
G01X1486501D01*
X1485512Y480138D01*
X1480753D01*
X1479985Y479370D01*
X1475860D01*
X1475660Y479570D01*
X1475573D01*
G01X1460194Y481470D02*
X1460281D01*
X1460481Y481670D01*
X1461331D01*
X1461681Y481320D01*
X1462731D01*
X1463081Y481670D01*
X1464131D01*
X1464481Y481320D01*
X1465581D01*
X1465931Y481670D01*
X1467031D01*
X1467381Y481320D01*
X1468481D01*
X1468831Y481670D01*
X1469931D01*
X1470281Y481320D01*
X1471381D01*
X1471731Y481670D01*
X1472831D01*
X1473181Y481320D01*
X1474281D01*
X1474631Y481670D01*
X1475731D01*
X1476081Y481320D01*
X1477181D01*
X1477531Y481670D01*
X1478631D01*
X1480311Y483350D01*
X1482815D01*
X1483165Y483000D01*
X1484265D01*
X1484615Y483350D01*
X1485715D01*
X1487427Y485062D01*
G03X1488688Y485471I-326J3154D01*
G02X1490262I787J-1365D01*
G03X1492588I1163J2015D01*
G02X1494163I788J-1365D01*
G02X1494950Y484150I-788J-1364D01*
G01Y484021D01*
G03X1496112Y482091I2325J85D01*
G02X1496900Y480770I-787J-1365D01*
G01Y480641D01*
G03X1498063Y478710I2325J85D01*
G03X1500388Y478711I1162J2016D01*
G02X1501963I788J-1365D01*
G02X1502750Y477404I-787J-1365D01*
G02Y477289I-1574J-58D01*
G02X1501963Y475982I-1574J58D01*
G02X1500594Y475882I-788J1364D01*
G01X1500271Y476330D01*
X1500995Y477318D01*
X1501175Y477346D01*
G01X1446313Y450400D02*
X1446400D01*
X1446600Y450600D01*
X1448140D01*
X1453970Y444770D01*
X1474799D01*
X1482079Y452050D01*
X1484355D01*
X1485838Y453533D01*
Y454685D01*
X1486587Y455434D01*
X1487655D01*
X1487662Y455427D01*
X1488312Y455051D01*
G03X1490638I1163J2015D01*
G03X1491800Y456981I-1163J2015D01*
G01Y457151D01*
G03X1490638Y459081I-2325J-85D01*
G02X1489866Y460218I787J1365D01*
G01X1490094Y460446D01*
X1491425D01*
G01X1446313Y451550D02*
X1446400D01*
X1446600Y451350D01*
X1448451D01*
X1454281Y445520D01*
X1474488D01*
X1475266Y446298D01*
Y446793D01*
X1476044Y447571D01*
X1476539D01*
X1477316Y448348D01*
Y448843D01*
X1478094Y449621D01*
X1478589D01*
X1479367Y450399D01*
Y450894D01*
X1480145Y451672D01*
X1480640D01*
X1481768Y452800D01*
X1484044D01*
X1485088Y453844D01*
Y454996D01*
X1486276Y456184D01*
X1487966D01*
X1488123Y456027D01*
X1488688Y455701D01*
G03X1490262I787J1365D01*
G03X1491050Y457022I-787J1365D01*
G01Y457110D01*
G03X1490262Y458431I-1575J-44D01*
G02X1489112Y460190I1162J2015D01*
G01X1488856Y460446D01*
X1487525D01*
G01X1472849Y437479D02*
X1472910Y437540D01*
X1473192D01*
X1480437Y444786D01*
X1482687D01*
G03X1483501Y445007I0J1609D01*
G01X1484224Y445657D01*
G02X1486617Y445520I1076J-2173D01*
G03X1487823Y445280I907J1406D01*
G01X1488312Y445561D01*
G02X1491487Y444716I1164J-2015D01*
G03X1493375Y443546I2043J1189D01*
G01X1489475D02*
X1489867Y443153D01*
G03X1491013Y444035I516J515D01*
G01X1490837Y444338D01*
G03X1488688Y444911I-1362J-792D01*
G01X1488687Y444910D01*
X1488096Y444569D01*
G02X1486208Y444890I-571J2357D01*
G03X1484642Y445023I-908J-1406D01*
G01X1483951Y444403D01*
G02X1482687Y444036I-1264J1992D01*
G01X1480748D01*
X1480006Y443293D01*
Y442798D01*
X1479263Y442056D01*
X1478768D01*
X1478026Y441313D01*
Y440818D01*
X1477284Y440076D01*
X1476789D01*
X1476046Y439333D01*
Y438838D01*
X1475304Y438096D01*
X1474809Y438095D01*
X1473724Y437010D01*
Y436726D01*
X1473663Y436665D01*
G01X1474310Y428099D02*
Y428188D01*
X1474560Y428438D01*
Y432896D01*
X1482314Y440650D01*
X1484698D01*
X1485418Y441370D01*
Y441371D01*
X1486138Y442091D01*
G02X1486203Y442137I1403J-1913D01*
G02X1488282Y442416I1323J-1971D01*
G01X1488688Y442181D01*
G02X1489539Y441331I-1163J-2015D01*
G03X1491425Y440166I2027J1173D01*
G01X1487525D02*
G03X1489084Y440394I779J114D01*
G03X1488889Y440955I-1559J-228D01*
G03X1488312Y441531I-1364J-789D01*
G01X1487980Y441722D01*
G03X1486622Y441513I-456J-1556D01*
G01X1485009Y439900D01*
X1482625D01*
X1481250Y438525D01*
Y438030D01*
X1480507Y437287D01*
X1480012D01*
X1479270Y436545D01*
Y436050D01*
X1478527Y435307D01*
X1478032D01*
X1477290Y434565D01*
Y434070D01*
X1476547Y433327D01*
X1476052D01*
X1475310Y432585D01*
Y431535D01*
X1475660Y431185D01*
Y430135D01*
X1475310Y429785D01*
Y428293D01*
X1475460Y428143D01*
Y428099D01*
G01X1472470Y423600D02*
X1472557D01*
X1472757Y423400D01*
X1473710D01*
X1475326Y425016D01*
X1483419D01*
X1485438Y427035D01*
X1487500D01*
G02X1488667Y426737I0J-2436D01*
G02X1489779Y425458I-1167J-2138D01*
G02X1489825Y425325I-2278J-862D01*
G03X1490811Y424600I986J308D01*
G01X1491400D01*
G01X1472470Y422450D02*
X1472557D01*
X1472757Y422650D01*
X1474021D01*
X1475637Y424266D01*
X1476309D01*
X1476659Y423916D01*
X1477759D01*
X1478109Y424266D01*
X1479209D01*
X1479559Y423916D01*
X1480659D01*
X1481009Y424266D01*
X1483730D01*
X1485749Y426285D01*
X1487500D01*
G02X1488307Y426077I-4J-1684D01*
G02X1489075Y425193I-807J-1477D01*
G02X1488777Y424375I-625J-235D01*
G02X1487500Y424600I-501J893D01*
G01X1476073Y417321D02*
X1476160D01*
X1476360Y417121D01*
X1477410D01*
X1477760Y417471D01*
X1478810D01*
X1479160Y417121D01*
X1482990D01*
X1486270Y420401D01*
X1487525D01*
G02X1488688Y420089I2J-2317D01*
G03X1490807Y420612I787J1365D01*
G03X1491034Y421226I-1332J841D01*
G03X1489475Y421454I-780J114D01*
G01X1480313Y413384D02*
X1480400D01*
X1480600Y413184D01*
X1482993D01*
X1486306Y416497D01*
X1487525D01*
G03X1488312Y416709I0J1567D01*
G02X1490638I1163J-2015D01*
G02X1493375Y414694I-7658J-13269D01*
G01X1476073Y416171D02*
X1476160D01*
X1476360Y416371D01*
X1483301D01*
X1486581Y419651D01*
X1487525D01*
G02X1488312Y419439I0J-1567D01*
G03X1491442Y420210I1164J2015D01*
G01X1491616Y420486D01*
G02X1493375Y421454I1758J-1113D01*
G01X1480313Y412234D02*
X1480400D01*
X1480600Y412434D01*
X1483304D01*
X1486617Y415747D01*
X1487525D01*
G03X1488688Y416059I2J2317D01*
G02X1490262I787J-1365D01*
G02X1491034Y414922I-787J-1365D01*
G02X1489475Y414694I-780J-114D01*
G01X1542125Y397794D02*
G03X1538615Y394749I-336J-3158D01*
G01X1538600Y394329D01*
G02X1535112Y392399I-2325J85D01*
G03X1533538I-787J-1365D01*
G03X1532738Y390778I812J-1409D01*
G02X1531588Y389019I-2312J256D01*
G03X1530800Y387698I787J-1365D01*
G01Y387569D01*
G02X1527312Y385639I-2325J85D01*
G03X1525738I-787J-1365D01*
G02X1523412I-1163J2015D01*
G03X1521838I-787J-1365D01*
G02X1519512I-1163J2015D01*
G03X1517938I-787J-1365D01*
G02X1515612I-1163J2015D01*
G03X1514038I-787J-1365D01*
G02X1511712I-1163J2015D01*
G03X1510138I-787J-1365D01*
G02X1507812I-1163J2015D01*
G03X1506238I-787J-1365D01*
G02X1503912I-1163J2015D01*
G03X1502338I-787J-1365D01*
G02X1500012I-1163J2015D01*
G03X1498438I-787J-1365D01*
G02X1496112I-1163J2015D01*
G03X1494538I-787J-1365D01*
G02X1492212I-1163J2015D01*
G03X1490638I-787J-1365D01*
G02X1488312I-1163J2015D01*
G03X1486738I-787J-1365D01*
G03X1486420Y385396I753J-1315D01*
G01X1485909Y384885D01*
G01X1530425Y391034D02*
G03X1530050Y387739I14289J-3295D01*
G01Y387610D01*
G02X1527688Y386289I-1575J44D01*
G03X1525362I-1163J-2015D01*
G02X1523788I-787J1365D01*
G03X1521462I-1163J-2015D01*
G02X1519888I-787J1365D01*
G03X1517562I-1163J-2015D01*
G02X1515988I-787J1365D01*
G03X1513662I-1163J-2015D01*
G02X1512088I-787J1365D01*
G03X1509762I-1163J-2015D01*
G02X1508188I-787J1365D01*
G03X1505862I-1163J-2015D01*
G02X1504288I-787J1365D01*
G03X1501962I-1163J-2015D01*
G02X1500388I-787J1365D01*
G03X1498062I-1163J-2015D01*
G02X1496488I-787J1365D01*
G03X1494162I-1163J-2015D01*
G02X1492588I-787J1365D01*
G03X1490262I-1163J-2015D01*
G02X1488688I-787J1365D01*
G03X1486041Y386066I-1163J-2015D01*
G03X1485880Y385920I1480J-1794D01*
G01X1485156Y385196D01*
G01X1503625Y487249D02*
Y487162D01*
X1503500Y487037D01*
Y484062D01*
G03X1504288Y482741I1575J44D01*
G02X1505450Y480811I-1163J-2015D01*
G01Y480682D01*
G03X1506238Y479361I1575J44D01*
G02X1507400Y477431I-1163J-2015D01*
G01Y477261D01*
G02X1506238Y475331I-2325J85D01*
G03X1505450Y474010I787J-1365D01*
G01Y473881D01*
G02X1504288Y471951I-2325J85D01*
G03X1503500Y470644I787J-1365D01*
G03Y470529I1575J-57D01*
G03X1504288Y469221I1575J57D01*
G02X1505450Y467291I-1163J-2015D01*
G01Y467121D01*
G02X1504288Y465191I-2325J85D01*
G03X1503500Y463870I787J-1365D01*
G01Y463782D01*
G03X1504311Y462368I1638J0D01*
G02X1505450Y460490I-1164J-1990D01*
G01Y460402D01*
G03X1506238Y459081I1575J44D01*
G02X1507200Y457415I-962J-1666D01*
G01Y453364D01*
X1508257Y452307D01*
Y448636D01*
X1510769Y446124D01*
Y434627D01*
X1512795Y432601D01*
X1523031D01*
X1524950Y430682D01*
Y429350D01*
G01X1502625Y487249D02*
Y487162D01*
X1502750Y487037D01*
Y484021D01*
G03X1503912Y482091I2325J85D01*
G02X1504700Y480770I-787J-1365D01*
G01Y480641D01*
G03X1505862Y478711I2325J85D01*
G02X1506650Y477404I-787J-1365D01*
G02Y477289I-1575J-58D01*
G02X1505862Y475981I-1575J57D01*
G03X1504700Y474051I1163J-2015D01*
G01Y473922D01*
G02X1503912Y472601I-1575J44D01*
G03X1502750Y470671I1163J-2015D01*
G01Y470501D01*
G03X1503912Y468571I2325J85D01*
G02X1504700Y467264I-787J-1365D01*
G02Y467149I-1575J-58D01*
G02X1503912Y465841I-1575J57D01*
G03X1502750Y463911I1163J-2015D01*
G01Y463741D01*
G02X1502231Y462431I-1913J0D01*
G03X1501175Y460381I3054J-2870D01*
G02X1500200Y458756I-1950J65D01*
G03X1499225Y457131I975J-1690D01*
G01Y457001D01*
G03X1500200Y455376I1950J65D01*
G02X1501173Y453778I-976J-1689D01*
G01X1501175Y453736D01*
G02X1500778Y452505I-1950J-51D01*
G01X1500022Y452021D01*
G03X1499238Y450453I921J-1441D01*
G01X1499290Y449762D01*
G03X1500212Y448763I1910J838D01*
G02X1501175Y447666I-987J-1837D01*
G01Y446861D01*
G02X1500200Y445236I-1950J65D01*
G03X1499225Y443611I975J-1690D01*
G01Y443481D01*
G03X1500200Y441856I1950J65D01*
G02X1501175Y440231I-975J-1690D01*
G01Y440101D01*
G03X1502150Y438476I1950J65D01*
G01X1503345Y437103D01*
Y436285D01*
X1505000Y434630D01*
X1505462D01*
G01X1489053Y103325D02*
X1487770Y104608D01*
Y107036D01*
X1492200Y111466D01*
Y113961D01*
X1489223Y116938D01*
Y137671D01*
X1488560Y138334D01*
Y144760D01*
X1488800Y145000D01*
G01X1575750Y443000D02*
X1575242Y442492D01*
X1573325D01*
G03X1572162Y442181I-1J-2327D01*
G02X1570588I-787J1365D01*
G03X1568262I-1163J-2015D01*
G02X1566688I-787J1365D01*
G03X1564362I-1163J-2015D01*
G02X1562788I-787J1365D01*
G03X1559300Y440251I-1163J-2015D01*
G01Y440122D01*
G02X1558512Y438801I-1575J44D01*
G03X1557346Y436782I1164J-2019D01*
G01Y435488D01*
G03X1558512Y432959I3326J0D01*
G02Y430229I-787J-1365D01*
G03X1557350Y428299I1163J-2015D01*
G01Y428170D01*
G02X1556562Y426849I-1575J44D01*
G03X1556105Y426504I1163J-2015D01*
G01X1554835D01*
X1550139Y421808D01*
Y419207D01*
X1550978Y418368D01*
Y416016D01*
X1550306Y415344D01*
Y414044D01*
X1552256Y412094D01*
Y410664D01*
X1553450Y409470D01*
Y407890D01*
G02X1551088Y406569I-1575J44D01*
G03X1548762I-1163J-2015D01*
G02X1547188I-787J1365D01*
G03X1544862I-1163J-2015D01*
G02X1543288I-787J1365D01*
G03X1540962I-1163J-2015D01*
G02X1539388I-787J1365D01*
G03X1535900Y404639I-1163J-2015D01*
G01Y404510D01*
G02X1535112Y403189I-1575J44D01*
G03X1533950Y401259I1163J-2015D01*
G01Y401130D01*
G02X1533162Y399809I-1575J44D01*
G03X1532000Y397879I1163J-2015D01*
G01Y397750D01*
G02X1531212Y396429I-1575J44D01*
G03X1530050Y394499I1163J-2015D01*
G01Y394370D01*
G02X1529262Y393049I-1575J44D01*
G03X1528100Y391119I1163J-2015D01*
G01Y390990D01*
G02X1525738Y389669I-1575J44D01*
G03X1523412I-1163J-2015D01*
G02X1521838I-787J1365D01*
G03X1519512I-1163J-2015D01*
G02X1517938I-787J1365D01*
G03X1515612I-1163J-2015D01*
G02X1514038I-787J1365D01*
G03X1511712I-1163J-2015D01*
G02X1510138I-787J1365D01*
G03X1507812I-1163J-2015D01*
G02X1506238I-787J1365D01*
G03X1503912I-1163J-2015D01*
G02X1502338I-787J1365D01*
G01X1500617Y390662D01*
G03X1499225Y391034I-1391J-2414D01*
G01X1489475Y387654D02*
G03X1490867Y388026I1J2786D01*
G01X1492588Y389019D01*
G02X1494162I787J-1365D01*
G03X1496488I1163J2015D01*
G02X1498062I787J-1365D01*
G03X1500388I1163J2015D01*
G02X1501962I787J-1365D01*
G03X1504288I1163J2015D01*
G02X1505862I787J-1365D01*
G03X1508188I1163J2015D01*
G02X1509762I787J-1365D01*
G03X1512088I1163J2015D01*
G02X1513662I787J-1365D01*
G03X1515988I1163J2015D01*
G02X1517562I787J-1365D01*
G03X1519888I1163J2015D01*
G02X1521462I787J-1365D01*
G03X1523788I1163J2015D01*
G02X1525362I787J-1365D01*
G03X1528850Y390949I1163J2015D01*
G01Y391078D01*
G02X1529638Y392399I1575J-44D01*
G03X1530800Y394329I-1163J2015D01*
G01Y394458D01*
G02X1531588Y395779I1575J-44D01*
G03X1532750Y397709I-1163J2015D01*
G01Y397838D01*
G02X1533538Y399159I1575J-44D01*
G03X1534700Y401089I-1163J2015D01*
G01Y401218D01*
G02X1535488Y402539I1575J-44D01*
G03X1536650Y404469I-1163J2015D01*
G01Y404598D01*
G02X1539012Y405919I1575J-44D01*
G03X1541338I1163J2015D01*
G02X1542912I787J-1365D01*
G03X1545238I1163J2015D01*
G02X1546812I787J-1365D01*
G03X1549138I1163J2015D01*
G02X1550712I787J-1365D01*
G03X1554200Y407849I1163J2015D01*
G01Y407978D01*
G02X1554988Y409299I1575J-44D01*
G03X1556151Y411231I-1162J2016D01*
G01X1556150Y411278D01*
Y411280D01*
X1556216Y411828D01*
Y412034D01*
X1554206Y414044D01*
Y414794D01*
X1551727Y417273D01*
Y418630D01*
X1553765Y420668D01*
Y423035D01*
X1556372Y425642D01*
G02X1556938Y426199I1353J-808D01*
G03X1558100Y428129I-1163J2015D01*
G01Y428258D01*
G02X1558888Y429579I1575J-44D01*
G03X1560050Y431509I-1163J2015D01*
G01Y431679D01*
G03X1559106Y433466I-2325J-85D01*
G02X1558100Y435490I1533J2024D01*
G01Y436787D01*
G02X1558888Y438151I1574J0D01*
G03X1560050Y440081I-1163J2015D01*
G01Y440210D01*
G02X1562412Y441531I1575J-44D01*
G03X1564738I1163J2015D01*
G02X1566312I787J-1365D01*
G03X1568638I1163J2015D01*
G02X1570212I787J-1365D01*
G03X1572163Y441008I1951J3376D01*
G01X1574858D01*
X1576425Y442575D01*
G01X1528994Y488813D02*
G03X1528475Y487551I1431J-1326D01*
G01Y487421D01*
G02X1527500Y485796I-1950J65D01*
G03X1526525Y484171I975J-1690D01*
G01Y484041D01*
G03X1527500Y482416I1950J65D01*
G02X1528475Y480791I-975J-1690D01*
G01Y480661D01*
G02X1527500Y479036I-1950J65D01*
G03X1526525Y477411I975J-1690D01*
G01Y477281D01*
G02X1525550Y475656I-1950J65D01*
G03X1524575Y474031I975J-1690D01*
G01Y473901D01*
G02X1523600Y472276I-1950J65D01*
G03X1522625Y470651I975J-1690D01*
G01X1523788Y465190D02*
G03X1524950Y467121I-1023J1931D01*
G01Y467250D01*
G02X1525738Y468571I1575J-44D01*
G03X1526900Y470501I-1163J2015D01*
G01Y470630D01*
G02X1527688Y471951I1575J-44D01*
G03X1528850Y473881I-1163J2015D01*
G01Y474010D01*
G02X1529638Y475331I1575J-44D01*
G03X1530800Y477261I-1163J2015D01*
G01Y477390D01*
G02X1531588Y478711I1575J-44D01*
G03X1532750Y480641I-1163J2015D01*
G03X1532643Y481428I-2327J84D01*
G03X1531588Y482741I-2218J-702D01*
G02Y485471I787J1365D01*
G03X1532750Y487401I-1163J2015D01*
G01Y487530D01*
G02X1533159Y488546I1466J0D01*
G01X1523412Y465842D02*
G03X1524200Y467162I-712J1320D01*
G01Y467291D01*
G02X1525362Y469221I2325J-85D01*
G03X1526150Y470542I-787J1365D01*
G01Y470671D01*
G02X1527312Y472601I2325J-85D01*
G03X1528100Y473922I-787J1365D01*
G01Y474051D01*
G02X1529262Y475981I2325J-85D01*
G03X1530050Y477302I-787J1365D01*
G01Y477431D01*
G02X1531212Y479361I2325J-85D01*
G03Y482091I-787J1365D01*
G02X1530160Y483393I1163J2015D01*
G02X1530050Y484191I2209J711D01*
G02X1531212Y486121I2325J-85D01*
G03X1532000Y487442I-787J1365D01*
G01Y487571D01*
G02X1532675Y489126I2129J0D01*
G01X1559160Y403275D02*
G03X1558512Y405919I-1590J1012D01*
G02X1557672Y409118I1163J2015D01*
G01X1558106Y410166D01*
Y415516D01*
X1559822Y417232D01*
Y418490D01*
X1561545Y420213D01*
Y422695D01*
X1560056Y424184D01*
Y426386D01*
X1560315Y426645D01*
X1560325D01*
X1561244Y427564D01*
Y428164D01*
X1561250Y428170D01*
Y428299D01*
G02X1562412Y430229I2325J-85D01*
G03X1563200Y431550I-787J1365D01*
G01Y435590D01*
X1566049Y438439D01*
X1570359D01*
X1571091Y439171D01*
X1582771D01*
X1587573Y443973D01*
Y445300D01*
G01X1563950Y433402D02*
Y431509D01*
G02X1562788Y429579I-2325J85D01*
G03X1562000Y428258I787J-1365D01*
G01Y426678D01*
X1563867Y424811D01*
Y423381D01*
X1565144Y422104D01*
Y420377D01*
X1563365Y418598D01*
Y417401D01*
X1561244Y415280D01*
Y413085D01*
X1560838Y412679D01*
G03X1560050Y411358I787J-1365D01*
G01Y411229D01*
G02X1558888Y409299I-2325J85D01*
G03Y406569I787J-1365D01*
G03X1560265Y406323I1029J1786D01*
G01X1560709D01*
X1565145Y401887D01*
G01X1547600Y489251D02*
Y487442D01*
G02X1546812Y486121I-1575J44D01*
G03X1545650Y484191I1163J-2015D01*
G01Y484021D01*
G03X1546812Y482091I2325J85D01*
G02Y479361I-787J-1365D01*
G03X1545650Y477431I1163J-2015D01*
G01Y477302D01*
G02X1544862Y475981I-1575J44D01*
G03X1543700Y474051I1163J-2015D01*
G01Y473922D01*
G02X1542912Y472601I-1575J44D01*
G03X1541750Y470671I1163J-2015D01*
G01Y470542D01*
G02X1540962Y469221I-1575J44D01*
G03X1539812Y467462I1162J-2015D01*
G03X1539880Y466503I2653J-294D01*
G02X1539513Y465652I-733J-189D01*
G03X1536275Y463826I106685J-192966D01*
G01X1532375D02*
X1533040Y464980D01*
X1533392Y465074D01*
G03X1536650Y467121I933J2132D01*
G01Y467291D01*
G02X1537494Y469587I3545J0D01*
G03X1537850Y470542I-1219J998D01*
G01Y470671D01*
G02X1539012Y472601I2325J-85D01*
G03X1539800Y473922I-787J1365D01*
G01Y474051D01*
G02X1540962Y475981I2325J-85D01*
G03X1541750Y477302I-787J1365D01*
G01Y477431D01*
G02X1542912Y479361I2325J-85D01*
G03X1543700Y480682I-787J1365D01*
G01Y480770D01*
G03X1542912Y482091I-1575J-44D01*
G02X1541750Y484021I1163J2015D01*
G01Y484191D01*
G02X1542912Y486121I2325J-85D01*
G03X1543700Y487442I-787J1365D01*
G01Y488770D01*
G01X1571949Y453325D02*
X1570212Y452321D01*
G02X1568638I-787J1365D01*
G03X1566312I-1163J-2015D01*
G02X1564944Y452222I-786J1365D01*
G01X1564860Y452532D01*
X1565192Y453108D01*
X1565525Y453686D01*
G01X1563575Y450306D02*
X1564240Y451460D01*
X1564592Y451554D01*
G03X1566688Y451671I932J2132D01*
G02X1568262I787J-1365D01*
G03X1570588I1163J2015D01*
G01X1571165Y452005D01*
X1572556D01*
X1574126Y453575D01*
G01X1573317Y449250D02*
G03X1572162Y448941I0J-2312D01*
G02X1570588I-787J1365D01*
G03X1568262I-1163J-2015D01*
G02X1566688I-787J1365D01*
G03X1564362I-1163J-2015D01*
G02X1562000Y450262I-787J1365D01*
G01Y450391D01*
G03X1561929Y450882I-2325J-86D01*
G01Y453368D01*
X1561927Y453370D01*
G03X1558888Y455701I-10359J-10358D01*
G02X1558100Y457022I787J1365D01*
G01Y457151D01*
G03X1557155Y458940I-2325J-84D01*
G01Y459457D01*
X1557725Y460446D01*
G01X1531063Y472030D02*
G02X1531400Y472276I1312J-1444D01*
G03X1532375Y473901I-975J1690D01*
G01Y474031D01*
G02X1533350Y475656I1950J-65D01*
G03X1534325Y477281I-975J1690D01*
G01Y477411D01*
G02X1535300Y479036I1950J-65D01*
G03X1536275Y480661I-975J1690D01*
G01Y480791D01*
G03X1535300Y482416I-1950J-65D01*
G02X1534325Y484041I975J1690D01*
G01Y484171D01*
G02X1535300Y485796I1950J-65D01*
G03X1536275Y487421I-975J1690D01*
G01Y487551D01*
G02X1536794Y488813I1950J-64D01*
G01X1535179Y471718D02*
G02X1535488Y471951I1096J-1132D01*
G03X1536650Y473881I-1163J2015D01*
G01Y474010D01*
G02X1537438Y475331I1575J-44D01*
G03X1538600Y477261I-1163J2015D01*
G01Y477390D01*
G02X1539388Y478711I1575J-44D01*
G03X1540550Y480641I-1163J2015D01*
G01Y480811D01*
G03X1539388Y482741I-2325J-85D01*
G02Y485471I787J1365D01*
G03X1540550Y487401I-1163J2015D01*
G01Y489417D01*
X1541215Y490082D01*
G01X1538225Y467206D02*
G02X1538330Y469495I2470J1034D01*
G03X1538600Y470501I-2055J1091D01*
G01Y470630D01*
G02X1539388Y471951I1575J-44D01*
G03X1540487Y473422I-1163J2015D01*
G03X1540550Y473881I-2262J544D01*
G01Y474010D01*
G02X1541338Y475331I1575J-44D01*
G03X1542500Y477261I-1163J2015D01*
G01Y477390D01*
G02X1543288Y478711I1575J-44D01*
G03X1544450Y480641I-1163J2015D01*
G01Y480811D01*
G03X1543288Y482741I-2325J-85D01*
G02X1542500Y484062I787J1365D01*
G01Y484150D01*
G02X1543288Y485471I1575J-44D01*
G03X1544450Y487401I-1163J2015D01*
G01Y488385D01*
X1545418Y489353D01*
G01X1542125Y467206D02*
G02X1541975Y469112I918J1031D01*
G03X1542500Y470501I-1800J1474D01*
G01Y470630D01*
G02X1543288Y471951I1575J-44D01*
G03X1544450Y473881I-1163J2015D01*
G01Y474010D01*
G02X1545238Y475331I1575J-44D01*
G03X1546400Y477261I-1163J2015D01*
G01Y477390D01*
G02X1547188Y478711I1575J-44D01*
G03X1548350Y480641I-1163J2015D01*
G01Y480811D01*
G03X1547188Y482741I-2325J-85D01*
G02Y485471I787J1365D01*
G03X1548350Y487401I-1163J2015D01*
G01Y488938D01*
X1549368Y489956D01*
G01X1769250Y70350D02*
X1769600D01*
X1773235Y66715D01*
X1811553D01*
X1820984Y57284D01*
Y42281D01*
X1822355Y40910D01*
Y35416D01*
X1820664Y33725D01*
X1817058D01*
X1811597Y28264D01*
Y20938D01*
X1818468Y14067D01*
Y12595D01*
X1817429Y11556D01*
X1815697D01*
X1814531Y10390D01*
X1812204D01*
X1808769Y6955D01*
X1805516D01*
X1805514Y6957D01*
X1802486D01*
X1802484Y6955D01*
X1795100D01*
X1794470Y6325D01*
X1783264D01*
X1774584Y15005D01*
X1739684D01*
X1734875Y10196D01*
Y9238D01*
G01X1833061Y92145D02*
X1826245D01*
X1816510Y82410D01*
X1806384D01*
X1802324Y86470D01*
X1797432D01*
X1784661Y73699D01*
X1758060D01*
X1757998Y73637D01*
G54D22*
X1900945Y1674D03*
Y41634D03*
G54D13*
X17716Y140591D03*
X23228D03*
G54D32*
G01X261125Y646784D02*
Y648759D01*
X261585Y649219D01*
X262431D01*
X263497Y650029D01*
X264494Y651358D01*
X264730Y652288D01*
X265066Y654198D01*
X265587Y654563D01*
X266621Y654381D01*
X266986Y653859D01*
X265502Y645452D01*
X266415Y644148D01*
X268388Y643799D01*
X269688Y644709D01*
X271373Y654259D01*
X271896Y654626D01*
X272929Y654444D01*
X273293Y653921D01*
X271801Y645467D01*
X272711Y644164D01*
X274685Y643818D01*
X275989Y644728D01*
X277668Y654262D01*
X278190Y654627D01*
X279223Y654446D01*
X279588Y653924D01*
X278097Y645468D01*
X279007Y644165D01*
X280981Y643819D01*
X282285Y644729D01*
X283967Y654281D01*
X284489Y654645D01*
X285522Y654464D01*
X285888Y653944D01*
X284388Y645435D01*
X285298Y644132D01*
X287272Y643785D01*
X288572Y644696D01*
X290263Y654278D01*
X290786Y654646D01*
X291820Y654463D01*
X292185Y653942D01*
X290685Y645434D01*
X291594Y644133D01*
X293567Y643785D01*
X294870Y644695D01*
X296539Y654165D01*
X297062Y654532D01*
X298095Y654351D01*
X298459Y653829D01*
X296982Y645452D01*
X297892Y644149D01*
X299865Y643804D01*
X301168Y644713D01*
X302837Y654169D01*
X303358Y654533D01*
X304390Y654351D01*
X304755Y653829D01*
X303277Y645454D01*
X304188Y644150D01*
X306162Y643804D01*
X307465Y644713D01*
X309132Y654185D01*
X309656Y654550D01*
X310688Y654370D01*
X311053Y653846D01*
X309567Y645421D01*
X310478Y644117D01*
X312452Y643771D01*
X313755Y644680D01*
X315421Y654137D01*
X315981Y654529D01*
X316949Y654359D01*
X317340Y653799D01*
X315863Y645421D01*
X316773Y644118D01*
X318746Y643771D01*
X320049Y644681D01*
X320908Y649553D01*
X321687Y653941D01*
X322209Y654306D01*
X323243Y654124D01*
X323607Y653602D01*
X322130Y645224D01*
X323067Y643882D01*
X324975Y643547D01*
X326315Y644486D01*
X327981Y653942D01*
X328503Y654306D01*
X329538Y654124D01*
X329903Y653602D01*
X328417Y645178D01*
X329328Y643871D01*
X331299Y643527D01*
X332605Y644436D01*
X334271Y653909D01*
X334793Y654273D01*
X335828Y654091D01*
X336193Y653569D01*
X334715Y645194D01*
X335626Y643890D01*
X337597Y643543D01*
X338899Y644453D01*
X340568Y653909D01*
X341090Y654273D01*
X342124Y654092D01*
X342488Y653571D01*
X341011Y645195D01*
X341921Y643890D01*
X343895Y643544D01*
X345198Y644458D01*
X346866Y653927D01*
X347388Y654292D01*
X348422Y654109D01*
X348785Y653587D01*
X347285Y645080D01*
X348197Y643779D01*
X350171Y643430D01*
X351474Y644346D01*
X353164Y653927D01*
X353684Y654291D01*
X354718Y654109D01*
X355082Y653588D01*
X353582Y645077D01*
X354497Y643777D01*
X356466Y643432D01*
X357769Y644341D01*
X359452Y653893D01*
X359975Y654258D01*
X361009Y654076D01*
X361373Y653555D01*
X359882Y645099D01*
X360794Y643795D01*
X362766Y643450D01*
X364069Y644360D01*
X365747Y653894D01*
X366270Y654259D01*
X367305Y654077D01*
X367669Y653556D01*
X366177Y645103D01*
X367086Y643798D01*
X369060Y643450D01*
X370364Y644364D01*
X372048Y653914D01*
X372567Y654277D01*
X373601Y654094D01*
X373968Y653570D01*
X372484Y645164D01*
X373395Y643860D01*
X375369Y643513D01*
X376671Y644425D01*
X377082Y646762D01*
X377390Y647974D01*
X377747Y648450D01*
X378426Y649011D01*
X379063Y648981D01*
X379561Y648483D01*
Y646508D01*
G01X261125Y652784D02*
Y650809D01*
X261565Y650369D01*
X262043D01*
X262673Y650848D01*
X263435Y651864D01*
X263604Y652530D01*
X264016Y654867D01*
X265317Y655779D01*
X267291Y655432D01*
X268202Y654128D01*
X266718Y645722D01*
X267085Y645198D01*
X268119Y645015D01*
X268638Y645378D01*
X270322Y654928D01*
X271626Y655842D01*
X273600Y655494D01*
X274509Y654189D01*
X273017Y645736D01*
X273381Y645215D01*
X274416Y645033D01*
X274939Y645398D01*
X276617Y654932D01*
X277920Y655842D01*
X279892Y655497D01*
X280804Y654193D01*
X279313Y645737D01*
X279677Y645216D01*
X280711Y645034D01*
X281234Y645399D01*
X282917Y654951D01*
X284220Y655860D01*
X286189Y655515D01*
X287104Y654215D01*
X285604Y645704D01*
X285968Y645183D01*
X287002Y645001D01*
X287522Y645365D01*
X289212Y654946D01*
X290515Y655862D01*
X292489Y655513D01*
X293401Y654212D01*
X291901Y645705D01*
X292264Y645183D01*
X293298Y645000D01*
X293820Y645365D01*
X295488Y654834D01*
X296791Y655748D01*
X298765Y655402D01*
X299675Y654097D01*
X298198Y645721D01*
X298562Y645200D01*
X299596Y645019D01*
X300118Y645383D01*
X301787Y654839D01*
X303089Y655749D01*
X305060Y655402D01*
X305971Y654098D01*
X304493Y645723D01*
X304858Y645201D01*
X305893Y645019D01*
X306415Y645383D01*
X308081Y654856D01*
X309387Y655765D01*
X311358Y655421D01*
X312269Y654114D01*
X310783Y645690D01*
X311148Y645168D01*
X312183Y644986D01*
X312705Y645350D01*
X314371Y654806D01*
X315711Y655745D01*
X317619Y655410D01*
X318556Y654068D01*
X317079Y645690D01*
X317443Y645168D01*
X318477Y644986D01*
X318999Y645351D01*
X319759Y649663D01*
X320637Y654611D01*
X321940Y655521D01*
X323913Y655174D01*
X324823Y653871D01*
X323346Y645493D01*
X323737Y644933D01*
X324705Y644763D01*
X325265Y645155D01*
X326931Y654612D01*
X328234Y655521D01*
X330208Y655175D01*
X331119Y653871D01*
X329633Y645446D01*
X329998Y644922D01*
X331030Y644742D01*
X331554Y645107D01*
X333221Y654579D01*
X334524Y655488D01*
X336498Y655142D01*
X337409Y653838D01*
X335931Y645463D01*
X336296Y644941D01*
X337328Y644759D01*
X337849Y645123D01*
X339518Y654579D01*
X340821Y655488D01*
X342794Y655143D01*
X343704Y653840D01*
X342227Y645463D01*
X342591Y644941D01*
X343624Y644760D01*
X344147Y645127D01*
X345816Y654597D01*
X347119Y655507D01*
X349092Y655159D01*
X350001Y653858D01*
X348501Y645350D01*
X348866Y644829D01*
X349900Y644646D01*
X350423Y645014D01*
X352114Y654596D01*
X353414Y655507D01*
X355388Y655160D01*
X356298Y653857D01*
X354798Y645348D01*
X355164Y644828D01*
X356197Y644647D01*
X356719Y645011D01*
X358401Y654563D01*
X359705Y655473D01*
X361679Y655127D01*
X362589Y653824D01*
X361098Y645368D01*
X361463Y644846D01*
X362496Y644665D01*
X363018Y645030D01*
X364697Y654564D01*
X366001Y655474D01*
X367975Y655128D01*
X368885Y653825D01*
X367393Y645371D01*
X367757Y644848D01*
X368790Y644666D01*
X369313Y645033D01*
X370998Y654583D01*
X372298Y655493D01*
X374271Y655144D01*
X375184Y653840D01*
X373700Y645433D01*
X374065Y644911D01*
X375099Y644729D01*
X375621Y645094D01*
X375956Y647004D01*
X376331Y648481D01*
X376908Y649250D01*
X378036Y650181D01*
X379156Y650129D01*
X379561Y650533D01*
Y652508D01*
G01X549330Y204193D02*
X550958D01*
X600510Y154641D01*
Y136661D01*
X601004Y136167D01*
Y135267D01*
X600510Y134773D01*
Y133873D01*
X601004Y133379D01*
Y132479D01*
X600510Y131985D01*
Y131085D01*
X601004Y130591D01*
Y129691D01*
X600510Y129197D01*
Y128175D01*
X600872Y127813D01*
Y126913D01*
X600510Y126551D01*
Y117085D01*
X601727Y115868D01*
X604040D01*
X605028Y116856D01*
Y119000D01*
G01X604977Y110200D02*
Y113023D01*
X603282Y114718D01*
X601250D01*
X599360Y116608D01*
Y154164D01*
X550481Y203043D01*
X549330D01*
G01X617400Y115800D02*
X618400D01*
X619252Y116652D01*
Y120271D01*
X617923Y121600D01*
Y123000D01*
X617323Y123600D01*
Y124800D01*
X617923Y125400D01*
Y126600D01*
X617323Y127200D01*
Y128400D01*
X617923Y129000D01*
Y130350D01*
X617273Y131000D01*
Y132350D01*
X617923Y133000D01*
Y134350D01*
X617273Y135000D01*
Y136350D01*
X617923Y137000D01*
Y141849D01*
X552886Y206886D01*
G01X553699Y207700D02*
X619073Y142326D01*
Y122077D01*
X620402Y120748D01*
Y116175D01*
X619490Y115263D01*
Y114660D01*
X620054Y114096D01*
G01X1109142Y-43700D02*
X914500D01*
G03Y-46250I0J-1275D01*
G01X1109042D01*
G02Y-51100I0J-2425D01*
G01X909373D01*
X905905Y-47632D01*
X823409D01*
X818984Y-52057D01*
G01X1109142Y-42550D02*
X914500D01*
G03Y-47400I0J-2425D01*
G01X1109042D01*
G02Y-49950I0J-1275D01*
G01X909850D01*
X906382Y-46482D01*
X823409D01*
X818984Y-42057D01*
G01X1206110Y646206D02*
X1203685Y648631D01*
X1201897D01*
X1197622Y648973D01*
X1194518Y647986D01*
X1193896Y647156D01*
X1193719Y646460D01*
X1193308Y644123D01*
X1192006Y643211D01*
X1190032Y643558D01*
X1189121Y644862D01*
X1190605Y653268D01*
X1190238Y653792D01*
X1189204Y653975D01*
X1188685Y653612D01*
X1187001Y644062D01*
X1185697Y643148D01*
X1183723Y643496D01*
X1182814Y644801D01*
X1184306Y653254D01*
X1183942Y653775D01*
X1182907Y653957D01*
X1182384Y653592D01*
X1180706Y644058D01*
X1179403Y643148D01*
X1177431Y643493D01*
X1176519Y644797D01*
X1178010Y653253D01*
X1177646Y653774D01*
X1176612Y653956D01*
X1176089Y653591D01*
X1174406Y644039D01*
X1173103Y643130D01*
X1171134Y643475D01*
X1170219Y644775D01*
X1171719Y653286D01*
X1171355Y653807D01*
X1170321Y653989D01*
X1169801Y653625D01*
X1168111Y644044D01*
X1166808Y643128D01*
X1164834Y643477D01*
X1163922Y644778D01*
X1165422Y653285D01*
X1165059Y653807D01*
X1164025Y653990D01*
X1163503Y653625D01*
X1161835Y644156D01*
X1160532Y643242D01*
X1158558Y643588D01*
X1157648Y644893D01*
X1159125Y653269D01*
X1158761Y653790D01*
X1157727Y653971D01*
X1157205Y653607D01*
X1155536Y644151D01*
X1154234Y643241D01*
X1152263Y643588D01*
X1151352Y644892D01*
X1152830Y653267D01*
X1152465Y653789D01*
X1151430Y653971D01*
X1150908Y653607D01*
X1149242Y644134D01*
X1147936Y643225D01*
X1145965Y643569D01*
X1145054Y644876D01*
X1146540Y653300D01*
X1146175Y653822D01*
X1145140Y654004D01*
X1144618Y653640D01*
X1142952Y644184D01*
X1141612Y643245D01*
X1139704Y643580D01*
X1138767Y644922D01*
X1140243Y653296D01*
X1139879Y653819D01*
X1138845Y654001D01*
X1138320Y653633D01*
X1136667Y644287D01*
X1135366Y643376D01*
X1133392Y643723D01*
X1132481Y645027D01*
X1133914Y653142D01*
X1133547Y653666D01*
X1132513Y653849D01*
X1131994Y653486D01*
X1130361Y644227D01*
X1129059Y643315D01*
X1127085Y643662D01*
X1126174Y644966D01*
X1127607Y653081D01*
X1127240Y653605D01*
X1126206Y653788D01*
X1125687Y653425D01*
X1124074Y644280D01*
X1122772Y643368D01*
X1120798Y643715D01*
X1119887Y645019D01*
X1121300Y653020D01*
X1120933Y653544D01*
X1119899Y653727D01*
X1119380Y653364D01*
X1117764Y644202D01*
X1116462Y643290D01*
X1114488Y643637D01*
X1113577Y644940D01*
X1114993Y652959D01*
X1114626Y653483D01*
X1113592Y653666D01*
X1113073Y653303D01*
X1111457Y644141D01*
X1110153Y643227D01*
X1108179Y643575D01*
X1107270Y644879D01*
X1108694Y652945D01*
X1108330Y653466D01*
X1107295Y653648D01*
X1106772Y653283D01*
X1105165Y644154D01*
X1103862Y643244D01*
X1101890Y643589D01*
X1100978Y644893D01*
X1102398Y652944D01*
X1102034Y653465D01*
X1101000Y653647D01*
X1100477Y653282D01*
X1098862Y644118D01*
X1097559Y643209D01*
X1095590Y643554D01*
X1094675Y644854D01*
X1096107Y652977D01*
X1095743Y653498D01*
X1094709Y653680D01*
X1094189Y653316D01*
X1092568Y644123D01*
X1091264Y643207D01*
X1089290Y643556D01*
X1088378Y644857D01*
X1089810Y652976D01*
X1089447Y653498D01*
X1088413Y653681D01*
X1087891Y653316D01*
X1086274Y644138D01*
X1084971Y643224D01*
X1082997Y643570D01*
X1082087Y644875D01*
X1083513Y652960D01*
X1083149Y653481D01*
X1082115Y653662D01*
X1081593Y653298D01*
X1079975Y644133D01*
X1078673Y643223D01*
X1076702Y643570D01*
X1075791Y644874D01*
X1077218Y652958D01*
X1076853Y653480D01*
X1075818Y653662D01*
X1075296Y653298D01*
X1073684Y644133D01*
X1072378Y643224D01*
X1070407Y643568D01*
X1069496Y644875D01*
X1070928Y652991D01*
X1070563Y653513D01*
X1069528Y653695D01*
X1069006Y653331D01*
X1067391Y644166D01*
X1066090Y643254D01*
X1064116Y643601D01*
X1063205Y644905D01*
X1064638Y653020D01*
X1064271Y653544D01*
X1063237Y653727D01*
X1062718Y653364D01*
X1061102Y644202D01*
X1059798Y643288D01*
X1057824Y643636D01*
X1056915Y644940D01*
X1058339Y653006D01*
X1057975Y653527D01*
X1056940Y653709D01*
X1056417Y653344D01*
X1054807Y644198D01*
X1053504Y643288D01*
X1051532Y643633D01*
X1050620Y644937D01*
X1052043Y653005D01*
X1051679Y653526D01*
X1050645Y653708D01*
X1050122Y653343D01*
X1048507Y644179D01*
X1047204Y643270D01*
X1045235Y643615D01*
X1044320Y644915D01*
X1045752Y653038D01*
X1045388Y653559D01*
X1044354Y653741D01*
X1043834Y653377D01*
X1042198Y644104D01*
X1040895Y643188D01*
X1038921Y643537D01*
X1038009Y644838D01*
X1039455Y653037D01*
X1039092Y653559D01*
X1038058Y653742D01*
X1037536Y653377D01*
X1035919Y644199D01*
X1034616Y643285D01*
X1032642Y643631D01*
X1031732Y644936D01*
X1033158Y653021D01*
X1032794Y653542D01*
X1031760Y653723D01*
X1031238Y653359D01*
X1029620Y644194D01*
X1028318Y643284D01*
X1026347Y643631D01*
X1025436Y644935D01*
X1026863Y653019D01*
X1026498Y653541D01*
X1025463Y653723D01*
X1024941Y653359D01*
X1023329Y644194D01*
X1022023Y643285D01*
X1020052Y643629D01*
X1019141Y644936D01*
X1020573Y653052D01*
X1020208Y653574D01*
X1019173Y653756D01*
X1018651Y653392D01*
X1017036Y644227D01*
X1015696Y643288D01*
X1013788Y643623D01*
X1012851Y644965D01*
X1014277Y653052D01*
X1013913Y653574D01*
X1012879Y653756D01*
X1012357Y653391D01*
X1010719Y644131D01*
X1009416Y643221D01*
X1007443Y643568D01*
X1006533Y644871D01*
X1008010Y653249D01*
X1007619Y653809D01*
X1006651Y653979D01*
X1006091Y653587D01*
X1004425Y644130D01*
X1003122Y643221D01*
X1001148Y643567D01*
X1000237Y644871D01*
X1001723Y653296D01*
X1001358Y653820D01*
X1000326Y654000D01*
X999802Y653635D01*
X998135Y644163D01*
X996832Y643254D01*
X994858Y643600D01*
X993947Y644904D01*
X995425Y653279D01*
X995060Y653801D01*
X994028Y653983D01*
X993507Y653619D01*
X991838Y644163D01*
X990535Y643254D01*
X988562Y643599D01*
X987652Y644902D01*
X989129Y653279D01*
X988765Y653801D01*
X987732Y653982D01*
X987209Y653615D01*
X985540Y644145D01*
X984237Y643235D01*
X982264Y643583D01*
X981355Y644884D01*
X982855Y653392D01*
X982490Y653913D01*
X981456Y654096D01*
X980933Y653728D01*
X979242Y644146D01*
X977942Y643235D01*
X975968Y643582D01*
X975058Y644885D01*
X976558Y653394D01*
X976192Y653914D01*
X975159Y654095D01*
X974637Y653731D01*
X972955Y644179D01*
X971651Y643269D01*
X969677Y643615D01*
X968767Y644918D01*
X970258Y653374D01*
X969893Y653896D01*
X968860Y654077D01*
X968338Y653712D01*
X966659Y644178D01*
X965355Y643268D01*
X963381Y643614D01*
X962471Y644917D01*
X963963Y653371D01*
X963599Y653894D01*
X962566Y654076D01*
X962043Y653709D01*
X960358Y644159D01*
X959058Y643249D01*
X957085Y643598D01*
X956172Y644902D01*
X957656Y653309D01*
X957291Y653831D01*
X956257Y654013D01*
X955736Y653648D01*
X955400Y651738D01*
X955156Y650777D01*
X954175Y649469D01*
X950504Y648302D01*
X946049Y648659D01*
X944308D01*
X941883Y646234D01*
G01Y652234D02*
X944308Y649809D01*
X946096D01*
X950371Y649467D01*
X953475Y650454D01*
X954097Y651284D01*
X954274Y651980D01*
X954685Y654317D01*
X955987Y655229D01*
X957961Y654882D01*
X958872Y653578D01*
X957388Y645172D01*
X957755Y644648D01*
X958789Y644465D01*
X959308Y644828D01*
X960992Y654378D01*
X962296Y655292D01*
X964270Y654944D01*
X965179Y653639D01*
X963687Y645186D01*
X964051Y644665D01*
X965086Y644483D01*
X965609Y644848D01*
X967287Y654382D01*
X968590Y655292D01*
X970562Y654947D01*
X971474Y653643D01*
X969983Y645187D01*
X970347Y644666D01*
X971381Y644484D01*
X971904Y644849D01*
X973587Y654401D01*
X974890Y655310D01*
X976859Y654965D01*
X977774Y653665D01*
X976274Y645154D01*
X976638Y644633D01*
X977672Y644451D01*
X978192Y644815D01*
X979882Y654396D01*
X981185Y655312D01*
X983159Y654963D01*
X984071Y653662D01*
X982571Y645155D01*
X982934Y644633D01*
X983968Y644450D01*
X984490Y644815D01*
X986158Y654284D01*
X987461Y655198D01*
X989435Y654852D01*
X990345Y653547D01*
X988868Y645171D01*
X989232Y644650D01*
X990266Y644469D01*
X990788Y644833D01*
X992457Y654289D01*
X993759Y655199D01*
X995730Y654852D01*
X996641Y653548D01*
X995163Y645173D01*
X995528Y644651D01*
X996563Y644469D01*
X997085Y644833D01*
X998751Y654306D01*
X1000057Y655215D01*
X1002028Y654871D01*
X1002939Y653564D01*
X1001453Y645140D01*
X1001818Y644618D01*
X1002853Y644436D01*
X1003375Y644800D01*
X1005041Y654256D01*
X1006381Y655195D01*
X1008289Y654860D01*
X1009226Y653518D01*
X1007749Y645140D01*
X1008113Y644618D01*
X1009147Y644436D01*
X1009669Y644801D01*
X1011307Y654061D01*
X1012610Y654971D01*
X1014583Y654624D01*
X1015493Y653321D01*
X1014067Y645234D01*
X1014458Y644674D01*
X1015426Y644504D01*
X1015986Y644896D01*
X1017601Y654062D01*
X1018904Y654971D01*
X1020878Y654625D01*
X1021789Y653321D01*
X1020357Y645204D01*
X1020722Y644680D01*
X1021754Y644500D01*
X1022278Y644865D01*
X1023891Y654029D01*
X1025194Y654938D01*
X1027168Y654592D01*
X1028079Y653288D01*
X1026652Y645204D01*
X1027017Y644682D01*
X1028049Y644500D01*
X1028570Y644864D01*
X1030188Y654029D01*
X1031491Y654938D01*
X1033464Y654593D01*
X1034374Y653290D01*
X1032948Y645204D01*
X1033312Y644682D01*
X1034345Y644501D01*
X1034868Y644868D01*
X1036486Y654047D01*
X1037789Y654957D01*
X1039762Y654609D01*
X1040671Y653308D01*
X1039225Y645108D01*
X1039590Y644587D01*
X1040624Y644404D01*
X1041147Y644772D01*
X1042784Y654046D01*
X1044084Y654957D01*
X1046058Y654610D01*
X1046968Y653307D01*
X1045536Y645186D01*
X1045902Y644666D01*
X1046935Y644485D01*
X1047457Y644849D01*
X1049071Y654013D01*
X1050375Y654923D01*
X1052349Y654577D01*
X1053259Y653274D01*
X1051836Y645206D01*
X1052201Y644684D01*
X1053234Y644503D01*
X1053756Y644868D01*
X1055367Y654014D01*
X1056671Y654924D01*
X1058645Y654578D01*
X1059555Y653275D01*
X1058131Y645208D01*
X1058496Y644685D01*
X1059528Y644504D01*
X1060052Y644871D01*
X1061668Y654033D01*
X1062968Y654943D01*
X1064941Y654594D01*
X1065854Y653290D01*
X1064421Y645174D01*
X1064786Y644652D01*
X1065820Y644470D01*
X1066341Y644835D01*
X1067956Y654001D01*
X1069259Y654910D01*
X1071233Y654564D01*
X1072144Y653260D01*
X1070712Y645143D01*
X1071077Y644619D01*
X1072109Y644439D01*
X1072633Y644804D01*
X1074246Y653968D01*
X1075549Y654877D01*
X1077523Y654531D01*
X1078434Y653227D01*
X1077007Y645143D01*
X1077372Y644621D01*
X1078404Y644439D01*
X1078925Y644803D01*
X1080543Y653968D01*
X1081846Y654877D01*
X1083819Y654532D01*
X1084729Y653229D01*
X1083303Y645143D01*
X1083667Y644621D01*
X1084700Y644440D01*
X1085223Y644807D01*
X1086841Y653986D01*
X1088144Y654896D01*
X1090117Y654548D01*
X1091026Y653247D01*
X1089594Y645127D01*
X1089959Y644606D01*
X1090993Y644423D01*
X1091517Y644791D01*
X1093139Y653985D01*
X1094439Y654896D01*
X1096413Y654549D01*
X1097323Y653246D01*
X1095891Y645125D01*
X1096257Y644605D01*
X1097290Y644424D01*
X1097812Y644788D01*
X1099426Y653952D01*
X1100730Y654862D01*
X1102704Y654516D01*
X1103614Y653213D01*
X1102194Y645162D01*
X1102559Y644640D01*
X1103592Y644459D01*
X1104114Y644824D01*
X1105722Y653953D01*
X1107026Y654863D01*
X1109000Y654517D01*
X1109910Y653214D01*
X1108486Y645147D01*
X1108851Y644624D01*
X1109883Y644443D01*
X1110407Y644810D01*
X1112023Y653972D01*
X1113323Y654882D01*
X1115296Y654533D01*
X1116209Y653229D01*
X1114794Y645210D01*
X1115159Y644687D01*
X1116192Y644506D01*
X1116714Y644871D01*
X1118330Y654033D01*
X1119630Y654943D01*
X1121603Y654594D01*
X1122516Y653290D01*
X1121103Y645288D01*
X1121468Y644766D01*
X1122502Y644584D01*
X1123023Y644949D01*
X1124637Y654094D01*
X1125937Y655004D01*
X1127910Y654655D01*
X1128823Y653351D01*
X1127390Y645235D01*
X1127755Y644713D01*
X1128789Y644531D01*
X1129310Y644896D01*
X1130944Y654155D01*
X1132244Y655065D01*
X1134217Y654716D01*
X1135130Y653412D01*
X1133697Y645296D01*
X1134062Y644774D01*
X1135096Y644592D01*
X1135617Y644957D01*
X1137270Y654302D01*
X1138575Y655217D01*
X1140550Y654869D01*
X1141458Y653564D01*
X1139983Y645191D01*
X1140374Y644631D01*
X1141342Y644461D01*
X1141902Y644853D01*
X1143568Y654310D01*
X1144871Y655219D01*
X1146845Y654873D01*
X1147756Y653569D01*
X1146270Y645144D01*
X1146635Y644620D01*
X1147667Y644440D01*
X1148191Y644805D01*
X1149858Y654277D01*
X1151161Y655186D01*
X1153135Y654840D01*
X1154046Y653536D01*
X1152568Y645161D01*
X1152933Y644639D01*
X1153965Y644457D01*
X1154486Y644821D01*
X1156155Y654277D01*
X1157458Y655186D01*
X1159431Y654841D01*
X1160341Y653538D01*
X1158864Y645161D01*
X1159228Y644639D01*
X1160261Y644458D01*
X1160784Y644825D01*
X1162453Y654295D01*
X1163756Y655205D01*
X1165729Y654857D01*
X1166638Y653556D01*
X1165138Y645048D01*
X1165503Y644527D01*
X1166537Y644344D01*
X1167060Y644712D01*
X1168751Y654294D01*
X1170051Y655205D01*
X1172025Y654858D01*
X1172935Y653555D01*
X1171435Y645046D01*
X1171801Y644526D01*
X1172834Y644345D01*
X1173356Y644709D01*
X1175038Y654261D01*
X1176342Y655171D01*
X1178316Y654825D01*
X1179226Y653522D01*
X1177735Y645066D01*
X1178100Y644544D01*
X1179133Y644363D01*
X1179655Y644728D01*
X1181334Y654262D01*
X1182638Y655172D01*
X1184612Y654826D01*
X1185522Y653523D01*
X1184030Y645069D01*
X1184394Y644546D01*
X1185427Y644364D01*
X1185950Y644731D01*
X1187635Y654281D01*
X1188935Y655191D01*
X1190908Y654842D01*
X1191821Y653538D01*
X1190337Y645131D01*
X1190702Y644609D01*
X1191736Y644427D01*
X1192257Y644792D01*
X1192593Y646702D01*
X1192837Y647663D01*
X1193818Y648971D01*
X1197489Y650138D01*
X1201944Y649781D01*
X1203685D01*
X1206110Y652206D01*
G01X1412941Y489523D02*
Y490751D01*
X1412442Y491250D01*
X1409934D01*
X1400826Y488186D01*
X1388869Y479340D01*
X1365353Y474347D01*
X1358269Y475765D01*
X1352627Y479526D01*
X1348074Y480437D01*
X1343903Y479550D01*
X1343402Y478779D01*
X1342033Y478488D01*
X1341262Y478989D01*
X1338894Y478486D01*
X1317994Y482926D01*
X1298968Y477547D01*
X1294547Y474112D01*
X1285341Y461017D01*
X1278386Y434403D01*
X1231629Y404782D01*
X1225994Y397019D01*
X1215525Y390900D01*
X1213777D01*
G01X1413193Y482532D02*
Y481061D01*
X1412684Y480552D01*
X1403762D01*
X1352251Y469828D01*
X1345040Y471269D01*
X1335300Y477792D01*
X1320043Y481027D01*
X1300664Y474001D01*
X1294100Y468900D01*
X1292228Y461012D01*
X1294301Y453951D01*
X1294302D01*
X1289626Y437644D01*
X1287808Y435335D01*
X1272649Y428386D01*
X1233422Y403774D01*
X1227284Y395320D01*
X1227285D01*
X1216522Y389030D01*
X1209534D01*
G01X1380741Y487489D02*
X1380749Y485779D01*
X1379714Y484744D01*
X1375802D01*
X1368140Y479751D01*
X1364475Y478293D01*
X1362038Y478781D01*
Y478780D01*
X1359602Y479267D01*
X1353807Y483130D01*
X1348319Y484228D01*
X1338932Y482236D01*
X1315653Y487181D01*
X1297461Y481788D01*
X1291926Y477488D01*
X1281048Y463762D01*
X1278006Y448814D01*
X1274943Y444185D01*
X1260700Y434752D01*
X1209500Y398121D01*
X1205296D01*
G01X1360863Y481673D02*
Y482951D01*
X1360291Y483523D01*
X1359249D01*
X1357320Y484440D01*
X1348121Y486555D01*
X1336366Y484200D01*
X1308975Y490019D01*
X1289325Y484759D01*
X1287668Y482489D01*
X1283268Y469945D01*
X1279169Y464307D01*
X1278872Y463178D01*
X1260087Y436639D01*
X1209947Y400766D01*
X1204732D01*
G01X1217841Y415921D02*
X1249027Y436769D01*
X1255665Y460778D01*
X1260785Y468151D01*
X1266840Y469670D01*
X1270511Y467786D01*
X1275209Y469103D01*
X1277360Y471945D01*
X1282673Y487089D01*
X1287167Y493247D01*
X1300812Y496897D01*
X1333051Y490049D01*
X1348456Y493062D01*
X1354642Y491768D01*
X1360617Y493472D01*
X1361724Y494579D01*
X1362360D01*
X1362841Y494098D01*
Y492823D01*
G01X1383263Y493673D02*
X1383256Y495110D01*
X1382812Y495554D01*
X1380875D01*
X1369578Y488584D01*
X1365484Y489339D01*
X1364408Y489065D01*
X1362823Y488662D01*
X1360256Y489235D01*
X1354841Y488447D01*
X1348913Y489687D01*
X1335253Y487000D01*
X1308067Y492775D01*
X1287141Y487175D01*
X1285013Y484259D01*
X1280136Y470355D01*
X1275951Y464600D01*
X1275712Y463688D01*
X1260039Y441293D01*
X1210049Y405525D01*
X1205798D01*
G01X1436600Y482900D02*
Y481600D01*
X1435945Y480945D01*
X1430404D01*
X1422013Y472554D01*
X1408776Y469743D01*
X1393641Y472958D01*
X1354431Y464878D01*
X1346349Y459494D01*
X1344407Y456582D01*
X1343410Y454069D01*
X1343409Y454068D01*
X1342410Y451553D01*
X1340826Y450600D01*
X1333726D01*
X1327085Y448830D01*
X1321756Y450030D01*
X1304136Y445905D01*
X1302095Y443863D01*
Y439662D01*
X1292217Y429785D01*
X1274793Y421953D01*
X1239709Y399943D01*
X1231720Y388940D01*
X1217653Y380490D01*
X1210128D01*
G01X1436541Y494423D02*
Y492898D01*
X1436091Y492448D01*
X1431868D01*
X1428452Y489032D01*
X1420278Y475070D01*
X1410788Y473054D01*
X1396047Y476003D01*
X1350744Y466942D01*
X1342950Y468501D01*
X1339029Y471126D01*
X1329223Y473084D01*
X1325021Y472149D01*
X1322769Y470267D01*
X1311230Y468516D01*
X1302935Y470176D01*
X1298867Y469237D01*
X1296822Y467193D01*
X1295444Y461381D01*
X1297349Y453820D01*
X1292426Y435556D01*
X1292427D01*
X1290497Y432919D01*
X1273364Y425008D01*
X1237171Y402303D01*
X1229723Y392044D01*
X1217023Y384416D01*
X1212490D01*
G01X1412741Y494223D02*
Y492838D01*
X1412303Y492400D01*
X1409745D01*
X1400287Y489219D01*
X1396306Y486273D01*
X1395397Y486409D01*
X1394312Y485606D01*
X1394176Y484697D01*
X1388385Y480413D01*
Y480414D01*
X1365346Y475522D01*
X1358718Y476848D01*
X1353076Y480609D01*
X1348067Y481612D01*
X1341023Y480115D01*
Y480114D01*
X1338894Y479662D01*
X1317955Y484111D01*
X1298439Y478593D01*
X1293705Y474915D01*
X1284280Y461509D01*
X1277387Y435133D01*
X1231014Y405754D01*
X1231013D01*
X1230827Y405636D01*
X1225205Y397890D01*
X1215213Y392050D01*
X1213777D01*
G01X1413041Y477423D02*
Y478952D01*
X1412591Y479402D01*
X1403881D01*
X1352256Y468654D01*
X1344590Y470186D01*
X1334844Y476713D01*
X1320126Y479833D01*
X1301227Y472981D01*
X1295126Y468240D01*
X1293418Y461043D01*
X1295405Y454275D01*
X1295406D01*
X1295500Y453955D01*
X1290670Y437110D01*
X1288540Y434405D01*
X1273198Y427372D01*
X1234222Y402918D01*
X1228074Y394449D01*
X1216834Y387880D01*
X1209621D01*
G01X1205296Y396971D02*
X1209870D01*
X1261528Y433930D01*
X1261533Y433931D01*
X1261542Y433928D01*
X1275773Y443355D01*
X1279089Y448365D01*
X1281322Y459340D01*
X1282089Y459848D01*
X1282358Y461171D01*
X1281851Y461937D01*
X1282120Y463260D01*
X1292742Y476664D01*
X1297996Y480747D01*
X1300839Y481590D01*
X1301647Y481151D01*
X1302941Y481535D01*
X1303380Y482343D01*
X1304674Y482727D01*
X1305482Y482288D01*
X1306776Y482672D01*
X1307215Y483480D01*
X1315700Y485995D01*
X1338932Y481060D01*
X1348326Y483053D01*
X1353358Y482047D01*
X1359153Y478184D01*
X1364583Y477098D01*
X1368672Y478724D01*
X1376144Y483594D01*
X1380022D01*
X1381041Y482575D01*
G01X1360741Y486523D02*
Y485123D01*
X1360291Y484673D01*
X1359509D01*
X1357700Y485533D01*
X1348138Y487732D01*
X1336373Y485375D01*
X1308944Y491202D01*
X1288635Y485765D01*
X1286639Y483030D01*
X1282238Y470485D01*
X1278111Y464809D01*
X1277812Y463673D01*
X1259260Y437462D01*
X1209577Y401916D01*
X1204732D01*
G01X1217201Y416877D02*
X1248032Y437488D01*
X1254608Y461274D01*
X1260086Y469162D01*
X1266980Y470891D01*
X1270635Y469016D01*
X1274525Y470107D01*
X1276334Y472496D01*
X1281644Y487630D01*
X1286477Y494253D01*
X1300781Y498080D01*
X1333060Y491223D01*
X1348464Y494236D01*
X1354599Y492952D01*
X1360015Y494497D01*
X1362880Y497362D01*
Y497556D01*
G01X1383241Y498595D02*
X1383248Y497158D01*
X1382794Y496704D01*
X1380548D01*
X1369351Y489796D01*
X1365444Y490516D01*
X1362806Y489845D01*
X1360300Y490404D01*
X1354877Y489615D01*
X1348920Y490861D01*
X1335262Y488174D01*
X1308036Y493958D01*
X1286451Y488181D01*
X1283984Y484800D01*
X1279106Y470895D01*
X1274893Y465101D01*
X1274651Y464179D01*
X1259209Y442114D01*
X1209679Y406675D01*
X1205798D01*
G01X1436396Y477691D02*
Y479403D01*
X1436004Y479795D01*
X1430881D01*
X1422586Y471499D01*
X1408776Y468567D01*
X1393637Y471783D01*
X1354883Y463796D01*
X1347178Y458664D01*
X1345432Y456044D01*
X1344479Y453645D01*
X1344478Y453642D01*
X1343336Y450767D01*
X1341146Y449450D01*
X1333877D01*
X1327108Y447645D01*
X1321761Y448850D01*
X1304718Y444859D01*
X1303245Y443386D01*
Y439185D01*
X1292882Y428822D01*
X1275337Y420936D01*
X1240509Y399087D01*
X1232514Y388074D01*
X1217972Y379340D01*
X1210128D01*
G01X1436441Y489323D02*
Y490848D01*
X1435991Y491298D01*
X1432345D01*
X1429370Y488323D01*
X1421014Y474050D01*
X1410795Y471879D01*
X1396047Y474830D01*
X1350744Y465769D01*
X1342500Y467418D01*
X1338579Y470043D01*
X1338577D01*
X1336528Y470452D01*
X1335763Y469942D01*
X1334439Y470206D01*
X1333929Y470971D01*
X1331814Y471392D01*
Y471393D01*
X1329236Y471908D01*
X1325546Y471087D01*
X1323259Y469178D01*
X1311203Y467348D01*
X1302952Y468999D01*
X1299447Y468190D01*
X1297866Y466610D01*
X1296628Y461389D01*
X1298538Y453810D01*
X1293482Y435050D01*
X1291250Y431999D01*
X1273917Y423996D01*
X1237971Y401447D01*
X1230514Y391173D01*
X1217342Y383266D01*
X1212490D01*
G01X1202637Y353700D02*
X1205297D01*
X1211090Y350380D01*
X1225645Y347190D01*
X1248010Y329281D01*
X1262048Y274718D01*
X1285300Y246811D01*
X1285987Y245986D01*
X1296025Y241268D01*
X1307600Y237175D01*
X1310546D01*
X1312025Y238654D01*
Y239652D01*
X1313575Y241202D01*
X1316705D01*
X1318225Y239682D01*
Y238350D01*
X1318904Y237671D01*
X1320289D01*
G01X1331400Y237900D02*
X1329675D01*
X1329225Y238350D01*
Y240079D01*
X1327634Y241670D01*
X1319774D01*
X1317668Y243776D01*
X1299238D01*
X1286522Y249756D01*
X1266172Y274181D01*
X1251360Y331712D01*
X1225424Y352481D01*
X1216383Y355220D01*
X1214487D01*
G01X1342400Y237900D02*
X1340675D01*
X1340225Y238350D01*
Y240077D01*
X1338554Y241748D01*
X1331994D01*
X1329572Y244170D01*
X1320811D01*
X1318705Y246276D01*
X1300716D01*
X1287499Y252491D01*
X1271035Y272252D01*
X1255344Y333229D01*
X1226493Y356329D01*
X1213850Y360250D01*
X1211497D01*
G01X1353400Y237900D02*
X1351675D01*
X1351225Y238350D01*
Y241865D01*
X1348788Y244302D01*
X1332977D01*
X1330609Y246670D01*
X1321848D01*
X1319742Y248776D01*
X1301923D01*
X1288876Y254910D01*
X1274997Y271569D01*
X1258623Y335149D01*
X1229430Y358524D01*
X1214016Y363302D01*
X1214007Y363305D01*
X1213833D01*
X1204665Y363321D01*
X1201065Y366921D01*
X1200187D01*
G01X1364400Y237900D02*
X1362675D01*
X1362225Y238350D01*
Y242044D01*
X1357467Y246802D01*
X1334014D01*
X1331646Y249170D01*
X1322885D01*
X1320779Y251276D01*
X1303184D01*
X1290260Y257353D01*
X1278800Y271108D01*
X1261979Y336473D01*
X1231077Y361219D01*
X1215877Y365929D01*
X1207479D01*
G01X1212440Y368463D02*
X1217051D01*
X1234123Y363172D01*
X1265203Y338286D01*
X1282546Y270923D01*
X1292200Y259339D01*
X1304034Y253776D01*
X1321816D01*
X1323922Y251670D01*
X1332683D01*
X1335051Y249302D01*
X1368297D01*
X1373225Y244374D01*
Y238350D01*
X1373675Y237900D01*
X1375400D01*
G01X1212007Y372772D02*
X1214422D01*
X1235775Y366145D01*
X1268390Y340030D01*
X1286051Y271400D01*
X1294719Y261215D01*
X1300166Y259285D01*
X1306366Y261510D01*
X1309170Y260678D01*
X1318537Y256276D01*
X1322853D01*
X1324959Y254170D01*
X1333720D01*
X1336088Y251802D01*
X1372727D01*
X1384225Y240304D01*
Y238350D01*
X1384675Y237900D01*
X1386400D01*
G01X1211174Y376914D02*
X1213489D01*
X1235954Y369919D01*
X1272240Y340863D01*
X1290195Y271091D01*
X1296733Y263256D01*
X1300079Y262069D01*
X1306289Y264298D01*
X1309370Y263383D01*
X1319175Y258776D01*
X1323890D01*
X1325996Y256670D01*
X1334757D01*
X1337125Y254302D01*
X1380324D01*
X1395161Y239465D01*
Y238414D01*
X1395675Y237900D01*
X1397400D01*
G01X1202637Y352550D02*
X1204990D01*
X1210671Y349294D01*
X1225136Y346124D01*
X1246991Y328623D01*
X1257933Y286093D01*
X1257465Y285301D01*
X1257814Y283945D01*
X1258605Y283478D01*
X1258954Y282122D01*
X1258487Y281330D01*
X1258836Y279974D01*
X1259627Y279507D01*
X1259976Y278151D01*
X1259509Y277359D01*
X1259858Y276003D01*
X1260649Y275536D01*
X1260998Y274180D01*
X1285266Y245053D01*
X1295587Y240202D01*
X1307402Y236025D01*
X1311023D01*
X1313175Y238177D01*
Y239175D01*
X1314052Y240052D01*
X1316228D01*
X1317075Y239205D01*
Y238350D01*
X1316370Y237645D01*
X1315100D01*
G01X1325900Y237900D02*
X1327304D01*
X1328075Y238671D01*
Y239602D01*
X1327157Y240520D01*
X1319297D01*
X1317191Y242626D01*
X1298981D01*
X1285801Y248823D01*
X1265122Y273643D01*
X1264773Y274999D01*
X1263981Y275466D01*
X1263632Y276822D01*
X1264100Y277614D01*
X1263751Y278970D01*
X1262959Y279437D01*
X1262610Y280793D01*
X1263078Y281585D01*
X1262729Y282941D01*
X1261937Y283408D01*
X1261588Y284764D01*
X1262056Y285555D01*
X1261707Y286911D01*
X1260915Y287378D01*
X1260566Y288734D01*
X1261034Y289525D01*
X1250341Y331053D01*
X1224878Y351444D01*
X1216212Y354070D01*
X1214487D01*
G01X1211497Y359100D02*
X1213674D01*
X1225944Y355295D01*
X1254326Y332569D01*
X1254325D01*
X1266593Y284892D01*
X1266594D01*
X1266127Y284100D01*
X1266476Y282744D01*
X1267267Y282277D01*
X1267616Y280921D01*
X1267149Y280129D01*
X1267498Y278773D01*
X1268289Y278306D01*
X1268625Y276999D01*
X1268158Y276207D01*
X1268494Y274900D01*
X1269286Y274432D01*
X1269985Y271714D01*
X1286778Y251558D01*
X1300459Y245126D01*
X1318228D01*
X1320334Y243020D01*
X1329095D01*
X1331517Y240598D01*
X1338077D01*
X1339075Y239600D01*
Y238350D01*
X1338625Y237900D01*
X1336900D01*
G01X1347900D02*
X1349625D01*
X1350075Y238350D01*
Y241388D01*
X1348311Y243152D01*
X1332500D01*
X1330132Y245520D01*
X1321371D01*
X1319265Y247626D01*
X1301666D01*
X1288155Y253977D01*
X1273947Y271031D01*
X1270482Y284485D01*
X1269690Y284952D01*
X1269341Y286308D01*
X1269808Y287099D01*
X1269459Y288455D01*
X1268667Y288922D01*
X1268318Y290278D01*
X1268786Y291069D01*
X1268449Y292376D01*
X1267658Y292844D01*
X1267321Y294151D01*
X1267788Y294943D01*
X1257604Y334490D01*
X1228881Y357490D01*
X1213831Y362155D01*
X1204187Y362171D01*
X1200588Y365771D01*
X1200187D01*
G01X1358900Y237900D02*
X1360625D01*
X1361075Y238350D01*
Y241567D01*
X1356990Y245652D01*
X1333537D01*
X1331169Y248020D01*
X1322408D01*
X1320302Y250126D01*
X1302927D01*
X1289539Y256420D01*
X1277750Y270570D01*
X1277401Y271926D01*
X1276610Y272393D01*
X1276261Y273749D01*
X1276728Y274541D01*
X1276379Y275896D01*
X1275588Y276364D01*
X1275239Y277720D01*
X1275706Y278511D01*
X1275357Y279867D01*
X1274566Y280334D01*
X1274217Y281690D01*
X1274684Y282482D01*
X1274335Y283837D01*
X1273544Y284305D01*
X1273195Y285661D01*
X1273662Y286452D01*
X1260960Y335814D01*
X1230528Y360185D01*
X1215702Y364779D01*
X1207479D01*
G01X1369900Y237900D02*
X1371625D01*
X1372075Y238350D01*
Y243897D01*
X1367820Y248152D01*
X1334574D01*
X1332206Y250520D01*
X1323445D01*
X1321339Y252626D01*
X1303777D01*
X1291479Y258406D01*
X1281496Y270384D01*
X1277565Y285651D01*
X1276774Y286119D01*
X1276437Y287426D01*
X1276905Y288218D01*
X1276568Y289525D01*
X1275776Y289992D01*
X1275440Y291300D01*
X1275907Y292091D01*
X1275571Y293399D01*
X1274779Y293866D01*
X1274442Y295173D01*
X1274910Y295965D01*
X1264184Y337627D01*
X1233574Y362138D01*
X1216876Y367313D01*
X1212440D01*
G01X1380900Y237900D02*
X1382625D01*
X1383075Y238350D01*
Y239827D01*
X1379347Y243555D01*
X1378428D01*
X1377473Y244510D01*
Y245429D01*
X1372250Y250652D01*
X1335611D01*
X1333243Y253020D01*
X1324482D01*
X1322376Y255126D01*
X1318280D01*
X1308760Y259600D01*
X1306400Y260300D01*
X1305129Y259844D01*
X1304737Y259013D01*
X1303467Y258556D01*
X1302635Y258949D01*
X1300168Y258063D01*
X1294043Y260233D01*
X1285003Y270857D01*
X1282610Y280154D01*
X1281819Y280621D01*
X1281470Y281977D01*
X1281937Y282769D01*
X1281588Y284124D01*
X1280797Y284592D01*
X1280448Y285948D01*
X1280915Y286739D01*
X1267371Y339371D01*
X1235226Y365111D01*
X1214247Y371622D01*
X1212007D01*
G01X1211174Y375764D02*
X1213314D01*
X1235404Y368885D01*
X1271221Y340204D01*
X1285693Y283967D01*
X1285226Y283175D01*
X1285575Y281819D01*
X1286366Y281352D01*
X1286715Y279996D01*
X1286248Y279204D01*
X1286597Y277848D01*
X1287388Y277381D01*
X1287737Y276025D01*
X1287269Y275233D01*
X1287618Y273878D01*
X1288410Y273410D01*
X1289145Y270553D01*
X1296052Y262277D01*
X1300081Y260847D01*
X1306323Y263088D01*
X1308960Y262305D01*
X1318918Y257626D01*
X1323413D01*
X1325519Y255520D01*
X1334280D01*
X1336648Y253152D01*
X1379847D01*
X1394011Y238988D01*
Y238350D01*
X1393561Y237900D01*
X1391900D01*
G01X1320500Y145000D02*
X1321708D01*
X1322208Y145500D01*
Y146350D01*
X1321348Y147210D01*
X1313570D01*
X1312213Y145853D01*
X1307600D01*
X1301711Y139964D01*
X1291643D01*
X1286034Y145573D01*
X1282608D01*
X1279134Y142099D01*
X1276086D01*
X1274774Y143411D01*
X1271262D01*
X1270296Y144377D01*
X1265604D01*
X1257473Y136246D01*
Y134896D01*
X1258123Y134246D01*
Y132896D01*
X1257473Y132246D01*
Y130896D01*
X1258123Y130246D01*
Y128896D01*
X1257473Y128246D01*
Y126896D01*
X1258123Y126246D01*
Y124896D01*
X1257473Y124246D01*
Y123298D01*
X1253627Y119452D01*
Y114800D01*
X1254077Y114350D01*
X1254900D01*
X1255714Y115164D01*
Y117113D01*
X1257800Y119199D01*
Y120800D01*
G01X1325100Y145000D02*
X1323808D01*
X1323358Y145450D01*
Y146827D01*
X1321825Y148360D01*
X1313093D01*
X1311736Y147003D01*
X1307123D01*
X1301234Y141114D01*
X1292120D01*
X1286511Y146723D01*
X1282131D01*
X1278657Y143249D01*
X1276563D01*
X1275251Y144561D01*
X1271739D01*
X1270773Y145527D01*
X1265127D01*
X1256323Y136723D01*
Y123775D01*
X1252477Y119929D01*
Y114323D01*
X1253600Y113200D01*
X1254900D01*
X1255400Y112700D01*
Y108000D01*
G01X1314900Y232118D02*
X1316625D01*
X1317075Y231668D01*
Y230473D01*
X1318070Y228706D01*
X1322944Y225457D01*
X1323125Y224556D01*
X1324248Y223807D01*
X1325149Y223987D01*
X1329602Y221019D01*
X1329606Y221017D01*
X1335700Y219800D01*
X1337367Y218689D01*
X1337592Y218645D01*
X1337593D01*
X1362419Y213798D01*
X1363309Y212462D01*
X1364638Y205826D01*
X1364763Y205637D01*
X1364764D01*
X1382050Y179698D01*
Y144164D01*
X1383524Y141668D01*
X1394629Y137354D01*
X1400284Y133945D01*
X1405137Y126663D01*
X1420426Y54693D01*
X1444016Y37805D01*
X1446174Y34565D01*
X1457319Y27138D01*
X1489782Y17862D01*
X1491932Y14636D01*
X1492398Y12303D01*
X1492524Y12113D01*
X1492525Y12114D01*
X1493533Y10601D01*
X1498748Y7123D01*
X1501464Y6579D01*
X1518097Y9906D01*
X1525520Y8424D01*
X1527968Y8914D01*
X1540820Y6184D01*
X1545401Y7158D01*
X1552193Y5715D01*
X1562791Y7966D01*
X1567498Y6966D01*
X1575177Y8597D01*
X1593270Y4758D01*
X1607767Y7838D01*
X1614228Y14300D01*
X1617203D01*
X1620198Y13301D01*
X1621523Y11976D01*
Y11205D01*
X1621073Y10755D01*
X1619798D01*
G01X1327243Y279663D02*
X1325618Y278038D01*
Y277199D01*
X1324595Y275982D01*
X1322661Y275646D01*
X1311939Y280684D01*
X1311938Y280687D01*
X1311939D01*
X1310740Y284849D01*
X1311665Y289766D01*
X1313802Y292625D01*
X1314597Y296531D01*
X1313436Y302233D01*
X1313437D01*
X1313138Y303697D01*
X1314215Y308486D01*
X1315116Y309872D01*
X1316780Y311120D01*
X1316779D01*
X1334775Y324610D01*
X1351316Y331382D01*
X1361970Y328246D01*
X1365618Y329262D01*
X1368457Y328599D01*
X1371206Y329600D01*
X1379281Y328031D01*
X1381419Y328446D01*
X1393441Y326108D01*
X1401854Y327744D01*
X1405078Y332526D01*
X1405534Y334869D01*
X1404870Y338286D01*
X1404869Y338287D01*
Y338289D01*
X1407657Y352242D01*
X1410444Y356454D01*
X1426228Y366978D01*
X1428760Y374808D01*
X1427701Y379788D01*
X1428639Y384213D01*
X1427355Y390266D01*
X1429300Y399810D01*
Y423186D01*
X1430970Y431044D01*
X1436560Y435102D01*
X1438921Y442530D01*
X1437537Y447600D01*
X1438691Y451221D01*
X1443297Y454250D01*
X1446813D01*
G01X1333680Y276035D02*
X1333581D01*
X1332723Y275177D01*
Y274423D01*
X1331125Y272825D01*
X1322273D01*
X1306495Y280247D01*
X1305212Y284703D01*
X1305624Y286890D01*
X1311331Y294524D01*
X1311739Y296529D01*
X1310433Y302950D01*
X1313187Y316483D01*
X1313909Y317575D01*
X1313910D01*
X1319297Y325717D01*
X1358958Y336464D01*
X1362546Y335342D01*
X1366311Y336627D01*
X1369525Y335801D01*
X1372553Y337463D01*
X1375674Y338235D01*
X1378430Y337700D01*
X1383008Y334612D01*
X1385457Y334136D01*
X1388565Y334740D01*
X1399334Y332646D01*
X1400363Y332846D01*
X1401631Y333700D01*
X1402122Y334429D01*
X1402365Y335680D01*
X1401961Y337759D01*
X1405447Y355695D01*
X1411009Y364035D01*
X1419721Y365781D01*
X1423972Y368616D01*
X1426015Y374943D01*
X1425062Y379433D01*
X1426054Y384092D01*
X1424708Y390432D01*
X1426800Y400280D01*
Y423451D01*
X1428720Y432515D01*
X1434275Y436547D01*
X1436255Y442765D01*
X1434886Y447780D01*
X1436602Y453164D01*
X1443415Y457648D01*
X1460772D01*
G01X1340248Y271755D02*
X1338808Y270315D01*
Y269458D01*
X1337685Y268335D01*
X1331974D01*
X1330059Y270250D01*
X1321782D01*
X1304255Y278496D01*
X1302509Y284567D01*
X1303123Y287831D01*
X1308603Y295160D01*
X1308882Y296531D01*
X1307394Y303839D01*
X1310987Y321491D01*
X1316237Y329426D01*
X1329553Y338364D01*
X1351895Y343357D01*
X1360763Y341682D01*
X1364802Y342497D01*
X1369745Y341426D01*
X1372513Y342538D01*
X1379472Y341142D01*
X1384015Y338078D01*
X1385755Y337739D01*
X1388307Y338235D01*
X1394894Y336955D01*
X1397646Y337491D01*
X1399096Y338469D01*
X1399356Y338854D01*
X1402844Y356799D01*
X1408886Y365858D01*
X1414964Y370561D01*
X1421403Y371851D01*
X1422546Y372613D01*
X1423167Y375706D01*
X1422422Y379219D01*
X1423472Y384152D01*
X1422140Y390425D01*
X1424300Y400575D01*
Y424543D01*
X1426262Y433800D01*
X1425076Y438159D01*
X1425950Y440904D01*
X1425110Y443979D01*
X1425105Y443999D01*
X1423902Y448404D01*
X1426390Y454830D01*
X1428140Y456992D01*
X1445854Y463250D01*
X1458010D01*
G01X1347468Y268095D02*
X1346061Y266688D01*
Y265383D01*
X1344596Y263918D01*
X1341437D01*
X1339520Y265835D01*
X1330921D01*
X1329015Y267741D01*
X1321155D01*
X1301932Y276782D01*
X1296006Y299658D01*
X1299105Y315343D01*
X1299958Y316710D01*
X1299957D01*
X1299958Y316711D01*
X1319920Y348713D01*
X1327736Y353401D01*
X1337392Y355332D01*
X1349599Y352272D01*
X1371542Y356661D01*
X1386326Y353705D01*
X1399467Y356272D01*
X1407065Y367666D01*
X1411921Y371423D01*
X1414709Y387901D01*
X1416736Y391427D01*
X1415751Y395529D01*
X1417882Y398689D01*
X1419836Y400006D01*
X1421800Y402916D01*
Y424808D01*
X1423575Y433187D01*
X1422252Y438031D01*
X1423186Y440959D01*
X1421178Y448315D01*
X1424370Y456547D01*
X1426814Y459568D01*
X1440211Y464299D01*
X1454043Y472450D01*
X1460883D01*
G01X1356268Y265695D02*
X1355298Y264725D01*
Y262797D01*
X1353775Y261274D01*
X1340544D01*
X1338484Y263334D01*
X1329793D01*
X1327886Y265241D01*
X1320584D01*
X1298279Y275729D01*
X1291927Y300248D01*
X1295398Y317807D01*
X1315199Y349555D01*
X1326106Y356096D01*
X1337326Y358341D01*
X1349729Y355232D01*
X1371467Y359581D01*
X1386574Y356507D01*
X1398174Y358868D01*
X1405290Y369541D01*
X1409085Y372476D01*
X1410428Y378612D01*
X1407823Y389022D01*
X1412067Y400845D01*
X1417402Y404505D01*
X1419300Y407398D01*
Y425338D01*
X1420909Y432932D01*
X1419563Y437861D01*
X1420570Y441015D01*
X1418534Y448478D01*
X1422298Y458200D01*
X1425675Y462373D01*
X1439329Y467199D01*
X1454886Y476364D01*
X1468200D01*
G01X1475573Y478420D02*
X1455697D01*
X1439641Y468956D01*
X1420200Y462088D01*
X1410999Y460300D01*
X1404007Y461659D01*
X1403245Y461145D01*
X1401920Y461403D01*
X1401406Y462165D01*
X1400080Y462423D01*
X1399318Y461909D01*
X1397993Y462166D01*
X1397479Y462928D01*
X1396154Y463186D01*
X1391832Y462345D01*
X1388000Y459761D01*
X1387824Y458858D01*
X1386705Y458104D01*
X1385803Y458279D01*
X1384683Y457524D01*
X1384508Y456622D01*
X1383389Y455867D01*
X1382486Y456043D01*
X1381367Y455288D01*
X1376834Y454407D01*
X1373257Y455102D01*
X1369338Y454340D01*
X1368773Y453960D01*
X1368282Y453230D01*
X1367860Y451064D01*
X1367417Y450397D01*
X1366316Y449656D01*
X1363133Y449037D01*
X1360592Y449531D01*
X1357883Y449005D01*
X1351204Y444500D01*
X1349500D01*
X1348150Y443150D01*
Y441150D01*
X1346505Y439505D01*
X1343337D01*
X1338682Y438600D01*
X1334129Y439485D01*
X1330601Y438799D01*
X1326949Y436337D01*
X1316595Y434325D01*
X1313826D01*
X1313075Y433574D01*
Y425849D01*
X1310650Y422253D01*
X1306774Y419639D01*
X1304835Y409645D01*
X1306447Y401346D01*
X1303325Y385284D01*
X1305950Y371784D01*
X1303641Y359911D01*
X1307098Y342120D01*
X1303127Y335752D01*
X1303335Y334857D01*
X1302620Y333711D01*
X1301725Y333503D01*
X1301517Y333170D01*
X1301010Y332358D01*
X1301218Y331463D01*
X1300503Y330317D01*
X1299608Y330109D01*
X1298894Y328964D01*
X1299101Y328069D01*
X1298387Y326923D01*
X1297491Y326715D01*
X1296777Y325570D01*
X1296984Y324675D01*
X1296270Y323529D01*
X1295374Y323321D01*
X1293057Y319607D01*
X1292795Y318283D01*
X1293307Y317519D01*
X1293045Y316195D01*
X1292282Y315683D01*
X1292020Y314359D01*
X1292532Y313595D01*
X1292270Y312271D01*
X1291506Y311759D01*
X1289690Y302569D01*
X1296827Y274850D01*
X1320143Y263891D01*
X1327052D01*
X1328959Y261984D01*
X1337924D01*
X1339984Y259924D01*
X1363500D01*
X1363950Y260374D01*
Y264378D01*
X1362803Y265525D01*
G01X1381031Y265600D02*
X1379711Y264280D01*
Y257865D01*
X1378120Y256274D01*
X1338234D01*
X1336174Y258334D01*
X1326982D01*
X1325167Y260149D01*
X1319493D01*
X1309134Y265017D01*
X1306244Y265875D01*
X1299858Y263582D01*
X1297767Y264323D01*
X1292715Y270323D01*
X1285289Y299134D01*
X1290014Y323065D01*
X1302554Y343168D01*
X1299252Y360160D01*
X1301480Y371627D01*
X1298900Y384900D01*
X1301541Y398487D01*
X1299279Y410123D01*
X1301963Y422651D01*
X1307050Y426602D01*
Y435550D01*
X1309956Y438456D01*
X1315913D01*
X1325094Y440239D01*
X1326779Y441375D01*
X1327050Y441646D01*
Y444077D01*
X1328499Y445526D01*
X1341489D01*
X1342897Y445801D01*
X1342899D01*
X1344812Y447092D01*
X1345741Y448471D01*
X1348288Y450183D01*
X1351154Y450741D01*
X1357710Y455163D01*
X1362022Y456002D01*
X1364469Y457652D01*
X1366453Y460594D01*
X1369225Y462464D01*
X1396136Y467695D01*
X1411057Y464794D01*
X1422723Y467060D01*
X1438907Y472776D01*
X1455630Y482621D01*
X1455631Y482620D01*
X1460194D01*
G01X1323734Y279663D02*
X1324468Y278929D01*
Y277619D01*
X1323985Y277044D01*
X1322822Y276842D01*
X1320961Y277716D01*
X1320650Y278581D01*
X1319428Y279155D01*
X1318563Y278843D01*
X1312901Y281504D01*
X1311921Y284905D01*
X1312746Y289291D01*
X1314878Y292142D01*
X1315771Y296531D01*
X1315093Y299865D01*
X1315600Y300632D01*
X1315331Y301955D01*
X1314564Y302462D01*
X1314315Y303685D01*
X1315292Y308032D01*
X1315969Y309074D01*
X1317089Y309914D01*
X1317999Y309784D01*
X1319119Y310623D01*
X1319250Y311533D01*
X1320370Y312373D01*
X1321280Y312243D01*
X1322400Y313083D01*
X1322530Y313993D01*
X1323650Y314832D01*
X1324560Y314702D01*
X1325680Y315542D01*
X1325811Y316452D01*
X1326931Y317292D01*
X1327841Y317162D01*
X1328961Y318001D01*
X1329091Y318911D01*
X1332147Y321202D01*
X1333056Y321071D01*
X1334137Y321881D01*
X1334267Y322791D01*
X1335347Y323601D01*
X1351378Y330164D01*
X1361961Y327049D01*
X1365643Y328075D01*
X1368529Y327401D01*
X1371300Y328410D01*
X1379281Y326859D01*
X1381419Y327274D01*
X1384390Y326696D01*
X1384904Y325934D01*
X1386229Y325676D01*
X1386991Y326190D01*
X1388316Y325932D01*
X1388830Y325170D01*
X1390155Y324913D01*
X1390918Y325427D01*
X1393441Y324936D01*
X1402542Y326705D01*
X1406163Y332077D01*
X1406706Y334870D01*
X1406042Y338286D01*
X1406622Y341188D01*
X1407387Y341698D01*
X1407651Y343022D01*
X1407141Y343787D01*
X1408741Y351795D01*
X1411276Y355625D01*
X1427199Y366243D01*
X1429949Y374747D01*
X1428877Y379788D01*
X1429815Y384213D01*
X1428530Y390271D01*
X1430450Y399694D01*
Y423065D01*
X1432004Y430372D01*
X1437542Y434393D01*
X1438909Y438693D01*
X1439725Y439115D01*
X1440134Y440402D01*
X1439711Y441218D01*
X1440120Y442505D01*
X1438736Y447575D01*
X1439664Y450483D01*
X1443642Y453100D01*
X1446900D01*
G01X1330171Y276035D02*
X1331075Y275131D01*
X1331100D01*
Y274427D01*
X1330648Y273975D01*
X1322530D01*
X1307456Y281066D01*
X1306393Y284759D01*
X1306705Y286415D01*
X1312407Y294042D01*
X1312913Y296529D01*
X1311607Y302950D01*
X1314270Y316034D01*
X1314606Y316542D01*
X1315507Y316725D01*
X1316280Y317893D01*
X1316096Y318793D01*
X1316869Y319961D01*
X1317769Y320145D01*
X1318542Y321312D01*
X1318358Y322213D01*
X1320017Y324720D01*
X1321368Y325086D01*
X1322166Y324629D01*
X1323517Y324995D01*
X1323974Y325792D01*
X1325326Y326159D01*
X1326123Y325701D01*
X1327474Y326067D01*
X1327932Y326865D01*
X1329283Y327231D01*
X1330080Y326774D01*
X1331431Y327140D01*
X1331889Y327937D01*
X1333240Y328303D01*
X1334037Y327846D01*
X1335389Y328212D01*
X1335846Y329009D01*
X1337197Y329375D01*
X1337995Y328918D01*
X1339346Y329284D01*
X1339803Y330081D01*
X1341106Y330434D01*
X1341903Y329977D01*
X1343206Y330330D01*
X1343664Y331127D01*
X1344967Y331480D01*
X1345764Y331023D01*
X1347067Y331376D01*
X1347525Y332173D01*
X1351216Y333173D01*
X1352014Y332716D01*
X1353317Y333069D01*
X1353774Y333866D01*
X1355077Y334219D01*
X1355875Y333762D01*
X1357178Y334115D01*
X1357635Y334912D01*
X1358938Y335265D01*
X1362562Y334132D01*
X1366357Y335427D01*
X1369680Y334573D01*
X1372975Y336382D01*
X1375706Y337057D01*
X1377981Y336615D01*
X1382559Y333527D01*
X1385457Y332964D01*
X1388565Y333568D01*
X1399334Y331474D01*
X1400812Y331761D01*
X1402460Y332871D01*
X1403207Y333980D01*
X1403537Y335679D01*
X1403133Y337759D01*
X1406532Y355249D01*
X1411702Y363001D01*
X1420170Y364698D01*
X1424944Y367881D01*
X1427204Y374882D01*
X1426238Y379433D01*
X1427230Y384092D01*
X1425884Y390432D01*
X1427950Y400155D01*
Y423330D01*
X1429754Y431844D01*
X1435257Y435838D01*
X1437454Y442740D01*
X1436086Y447755D01*
X1437575Y452427D01*
X1443760Y456498D01*
X1460772D01*
G01X1336448Y271755D02*
X1337658Y270545D01*
Y269935D01*
X1337208Y269485D01*
X1332451D01*
X1330536Y271400D01*
X1322040D01*
X1305217Y279315D01*
X1303690Y284623D01*
X1304204Y287356D01*
X1309679Y294678D01*
X1310056Y296531D01*
X1308568Y303839D01*
X1309103Y306468D01*
X1309870Y306975D01*
X1310139Y308298D01*
X1309632Y309065D01*
X1311111Y316333D01*
X1311878Y316840D01*
X1312147Y318163D01*
X1311640Y318930D01*
X1312070Y321042D01*
X1312815Y322168D01*
X1313716Y322351D01*
X1314460Y323477D01*
X1314277Y324378D01*
X1317069Y328599D01*
X1318807Y329766D01*
X1319709Y329588D01*
X1320830Y330341D01*
X1321008Y331242D01*
X1330015Y337288D01*
X1336756Y338794D01*
X1337532Y338302D01*
X1338849Y338596D01*
X1339342Y339372D01*
X1341394Y339831D01*
X1342170Y339338D01*
X1343488Y339633D01*
X1343980Y340409D01*
X1348966Y341523D01*
X1348967D01*
X1351915Y342182D01*
X1353291Y341922D01*
X1353809Y341163D01*
X1355184Y340903D01*
X1355944Y341421D01*
X1360770Y340510D01*
X1364794Y341322D01*
X1369846Y340227D01*
X1372623Y341342D01*
X1379020Y340059D01*
X1383565Y336993D01*
X1385755Y336567D01*
X1388307Y337063D01*
X1394894Y335783D01*
X1398096Y336406D01*
X1399925Y337640D01*
X1400441Y338405D01*
X1403929Y356350D01*
X1409739Y365063D01*
X1415455Y369486D01*
X1421852Y370768D01*
X1423580Y371920D01*
X1424342Y375712D01*
X1423598Y379219D01*
X1424648Y384152D01*
X1423316Y390425D01*
X1425450Y400453D01*
Y424422D01*
X1427445Y433834D01*
X1426275Y438133D01*
X1427150Y440877D01*
X1426219Y444284D01*
X1426215Y444300D01*
X1426671Y445098D01*
X1426316Y446401D01*
X1425518Y446857D01*
X1425112Y448342D01*
X1425599Y449601D01*
X1426440Y449972D01*
X1426928Y451231D01*
X1426556Y452072D01*
X1427398Y454246D01*
X1428830Y456016D01*
Y456015D01*
X1438509Y459435D01*
X1439338Y459038D01*
X1440611Y459488D01*
X1441008Y460318D01*
X1442281Y460767D01*
X1443110Y460371D01*
X1444383Y460821D01*
X1444779Y461650D01*
X1446052Y462100D01*
X1458010D01*
G01X1460883Y471300D02*
X1454357D01*
X1451905Y469855D01*
X1451675Y468965D01*
X1450469Y468254D01*
X1449579Y468484D01*
X1448372Y467773D01*
X1448143Y466883D01*
X1446936Y466172D01*
X1446046Y466402D01*
X1444883Y465717D01*
X1444653Y464827D01*
X1443490Y464141D01*
X1442600Y464371D01*
X1440699Y463251D01*
X1427504Y458592D01*
X1425378Y455963D01*
X1422388Y448251D01*
X1424386Y440934D01*
X1423452Y438006D01*
X1424758Y433221D01*
X1422950Y424687D01*
Y402564D01*
X1420664Y399177D01*
X1418711Y397860D01*
X1416988Y395305D01*
X1417962Y391250D01*
X1415809Y387506D01*
X1414982Y382620D01*
X1415514Y381870D01*
X1415289Y380539D01*
X1414539Y380007D01*
X1414541D01*
X1414315Y378676D01*
X1414314D01*
X1414847Y377927D01*
X1414622Y376595D01*
X1413872Y376063D01*
X1413873Y376062D01*
X1413648Y374732D01*
X1413647D01*
X1414180Y373983D01*
X1413955Y372652D01*
X1413205Y372119D01*
X1413206D01*
X1412980Y370788D01*
X1407918Y366871D01*
X1400158Y355235D01*
X1386323Y352532D01*
X1371542Y355488D01*
Y355486D01*
X1349571Y351093D01*
X1337364Y354153D01*
X1328157Y352312D01*
X1320749Y347869D01*
X1310989Y332222D01*
X1311196Y331326D01*
X1310482Y330181D01*
X1309586Y329973D01*
X1308872Y328828D01*
X1309080Y327933D01*
X1308339Y326745D01*
X1307443Y326537D01*
X1306702Y325349D01*
X1306910Y324454D01*
X1306169Y323266D01*
X1305274Y323058D01*
X1304533Y321871D01*
X1304740Y320975D01*
X1303999Y319787D01*
X1303104Y319580D01*
X1302363Y318392D01*
X1302570Y317496D01*
X1301829Y316308D01*
X1300934Y316101D01*
X1300193Y314913D01*
X1297186Y299692D01*
X1302910Y277593D01*
X1321412Y268891D01*
X1329492D01*
X1331398Y266985D01*
X1339997D01*
X1341914Y265068D01*
X1344119D01*
X1344911Y265860D01*
Y266852D01*
X1343668Y268095D01*
G01X1468200Y475214D02*
X1455200D01*
X1439817Y466151D01*
X1426365Y461397D01*
X1423306Y457616D01*
X1419744Y448415D01*
X1421770Y440989D01*
X1420763Y437835D01*
X1422092Y432966D01*
X1420450Y425217D01*
Y407054D01*
X1418240Y403684D01*
X1413025Y400106D01*
X1409024Y388962D01*
X1411610Y378630D01*
X1410120Y371821D01*
X1406143Y368746D01*
X1398868Y357835D01*
X1386574Y355333D01*
X1371465Y358407D01*
X1349701Y354053D01*
X1337298Y357162D01*
X1326527Y355007D01*
X1316028Y348711D01*
X1315287Y347523D01*
X1315495Y346628D01*
X1314754Y345440D01*
X1313858Y345232D01*
X1313118Y344044D01*
X1313325Y343149D01*
X1312584Y341961D01*
X1311689Y341753D01*
X1310948Y340565D01*
X1311155Y339670D01*
X1310415Y338482D01*
X1309519Y338274D01*
X1308778Y337086D01*
X1308986Y336191D01*
X1308245Y335003D01*
X1307349Y334795D01*
X1296486Y317377D01*
X1295827Y314045D01*
X1296339Y313281D01*
X1296077Y311957D01*
X1295314Y311445D01*
X1295052Y310121D01*
X1295563Y309357D01*
X1295302Y308033D01*
X1294538Y307521D01*
X1293107Y300282D01*
X1295607Y290630D01*
X1296400Y290163D01*
X1296738Y288857D01*
X1296272Y288064D01*
X1296610Y286757D01*
X1297403Y286291D01*
X1297741Y284984D01*
X1297275Y284192D01*
X1297613Y282885D01*
X1298406Y282419D01*
X1298744Y281112D01*
X1298278Y280320D01*
X1299257Y276540D01*
X1320841Y266391D01*
X1328363D01*
X1330270Y264484D01*
X1338961D01*
X1341021Y262424D01*
X1353298D01*
X1354148Y263274D01*
Y264851D01*
X1353304Y265695D01*
X1352468D01*
G01X1475573Y479570D02*
X1455383D01*
X1439153Y470004D01*
X1439151Y470003D01*
X1439150D01*
X1419897Y463201D01*
X1411000Y461472D01*
X1396155Y464358D01*
X1391383Y463430D01*
X1380918Y456373D01*
X1376834Y455579D01*
X1373257Y456274D01*
X1368889Y455425D01*
X1367944Y454789D01*
X1367197Y453679D01*
X1366774Y451510D01*
X1366584Y451224D01*
X1365867Y450741D01*
X1363133Y450209D01*
X1360592Y450703D01*
X1357434Y450090D01*
X1350852Y445650D01*
X1349023D01*
X1347000Y443627D01*
Y441627D01*
X1346028Y440655D01*
X1343226D01*
X1338682Y439772D01*
X1334129Y440657D01*
X1330152Y439884D01*
X1326500Y437422D01*
X1316484Y435475D01*
X1313349D01*
X1311925Y434051D01*
Y426201D01*
X1309821Y423082D01*
X1305735Y420326D01*
X1303663Y409645D01*
X1305275Y401346D01*
X1302153Y385284D01*
X1304778Y371784D01*
X1302469Y359911D01*
X1305881Y342346D01*
X1305883D01*
X1291969Y320037D01*
X1288511Y302535D01*
X1295848Y274039D01*
X1319886Y262741D01*
X1326575D01*
X1328482Y260834D01*
X1337447D01*
X1339507Y258774D01*
X1363977D01*
X1365100Y259897D01*
Y264313D01*
X1366312Y265525D01*
G01X1377522Y265600D02*
X1378561Y264561D01*
Y258342D01*
X1377643Y257424D01*
X1376243D01*
X1375593Y258074D01*
X1374193D01*
X1373543Y257424D01*
X1372143D01*
X1371493Y258074D01*
X1370093D01*
X1369443Y257424D01*
X1368043D01*
X1367393Y258074D01*
X1365993D01*
X1365343Y257424D01*
X1338711D01*
X1336651Y259484D01*
X1327459D01*
X1325644Y261299D01*
X1319750D01*
X1309545Y266095D01*
X1306210Y267085D01*
X1299855Y264804D01*
X1298446Y265303D01*
X1293764Y270864D01*
X1293427Y272171D01*
X1293894Y272963D01*
X1293557Y274270D01*
X1292766Y274737D01*
X1292429Y276045D01*
X1292896Y276836D01*
X1292559Y278144D01*
X1291767Y278611D01*
X1291430Y279918D01*
X1291897Y280710D01*
X1291560Y282017D01*
X1290769Y282484D01*
X1286468Y299168D01*
X1291102Y322635D01*
X1291843Y323823D01*
X1292738Y324030D01*
X1293479Y325218D01*
X1293272Y326114D01*
X1294013Y327302D01*
X1294908Y327509D01*
X1295649Y328697D01*
X1295442Y329592D01*
X1296183Y330780D01*
X1297078Y330988D01*
X1297819Y332176D01*
X1297612Y333071D01*
X1298353Y334259D01*
X1299248Y334466D01*
X1299989Y335654D01*
X1299782Y336549D01*
X1300523Y337737D01*
X1301418Y337944D01*
X1302159Y339132D01*
X1301952Y340028D01*
X1303770Y342943D01*
X1300424Y360160D01*
X1302652Y371627D01*
X1300072Y384900D01*
X1302713Y398487D01*
X1300453Y410113D01*
X1303000Y422000D01*
X1308200Y426039D01*
Y435073D01*
X1310433Y437306D01*
X1316024D01*
X1325543Y439154D01*
X1327514Y440483D01*
X1328200Y441169D01*
Y443600D01*
X1328976Y444376D01*
X1341600D01*
X1343347Y444716D01*
X1345641Y446263D01*
X1346570Y447641D01*
X1348737Y449098D01*
X1351604Y449656D01*
X1358160Y454078D01*
X1362472Y454917D01*
X1365298Y456823D01*
X1367282Y459765D01*
X1369675Y461379D01*
X1396136Y466523D01*
X1411057Y463622D01*
X1423026Y465947D01*
X1439395Y471728D01*
X1455942Y481470D01*
X1460194D01*
G01X1320400Y232118D02*
X1318675D01*
X1318225Y231668D01*
Y230775D01*
X1318937Y229511D01*
X1318938D01*
X1330055Y222101D01*
X1336149Y220884D01*
X1337813Y219774D01*
X1363110Y214835D01*
X1364393Y212912D01*
X1365721Y206275D01*
X1383200Y180047D01*
Y144479D01*
X1384312Y142596D01*
X1395138Y138390D01*
X1401099Y134798D01*
X1406217Y127118D01*
X1421459Y55369D01*
X1444857Y38618D01*
X1447004Y35395D01*
X1457808Y28195D01*
X1490505Y18852D01*
X1493016Y15085D01*
X1493482Y12752D01*
X1494363Y11430D01*
X1499197Y8206D01*
X1501464Y7752D01*
X1518097Y11079D01*
X1525520Y9597D01*
X1527975Y10089D01*
X1540820Y7360D01*
X1545401Y8334D01*
X1552193Y6891D01*
X1562791Y9142D01*
X1567498Y8142D01*
X1575177Y9773D01*
X1593270Y5934D01*
X1607194Y8893D01*
X1613751Y15450D01*
X1617390D01*
X1620820Y14307D01*
X1622673Y12453D01*
Y11205D01*
X1623123Y10755D01*
X1624798D01*
G01X1331400Y232118D02*
X1329675D01*
X1329225Y231668D01*
Y230561D01*
X1329995Y229350D01*
X1340210Y221990D01*
X1367331Y216693D01*
X1371492Y210459D01*
X1373448Y200653D01*
X1388100Y178673D01*
Y153812D01*
X1395805Y142253D01*
X1402534Y138197D01*
X1408250Y129617D01*
X1423716Y56840D01*
X1446428Y40582D01*
X1454845Y37790D01*
X1460763Y30057D01*
X1494394Y20444D01*
X1496320Y17557D01*
X1501949Y13803D01*
X1506802Y12832D01*
X1517838Y15040D01*
X1526830Y12471D01*
X1545090Y16351D01*
X1546700Y15877D01*
X1551216Y16837D01*
X1554595Y16160D01*
X1561043Y17449D01*
X1565192Y16622D01*
X1565510Y16559D01*
X1577720Y19002D01*
Y18979D01*
X1577721D01*
X1577957Y18955D01*
X1598011Y14746D01*
X1598013Y14747D01*
Y14746D01*
X1615748Y18517D01*
X1630426Y15403D01*
X1632023Y13431D01*
Y7275D01*
X1632473Y6825D01*
X1634148D01*
G01X1342400Y232118D02*
X1340593D01*
X1340143Y231668D01*
Y229131D01*
X1341788Y225834D01*
X1344402Y223985D01*
X1369048Y219179D01*
X1374260Y211359D01*
X1376245Y201432D01*
X1393900Y174949D01*
Y150250D01*
X1397803Y144394D01*
X1404031Y140642D01*
X1410554Y130857D01*
X1425967Y58316D01*
X1446616Y43534D01*
X1462316Y38324D01*
X1467247Y30932D01*
X1496593Y22548D01*
X1498613Y19518D01*
X1502646Y16828D01*
X1506285Y16100D01*
X1516284Y18100D01*
X1526869Y15075D01*
X1545179Y18961D01*
X1546813Y18483D01*
X1551229Y19421D01*
X1554147Y18837D01*
X1560944Y20196D01*
X1565192Y19346D01*
X1565783Y19228D01*
X1577793Y21631D01*
X1598052Y17329D01*
X1615716Y21081D01*
X1625521Y19000D01*
X1636816D01*
X1640619Y17262D01*
X1641818Y16063D01*
Y11697D01*
X1642410Y11105D01*
X1643865D01*
G01X1325900Y232118D02*
X1327625D01*
X1328075Y231668D01*
Y230226D01*
X1329143Y228546D01*
X1332354Y226232D01*
X1332502Y225325D01*
X1333597Y224535D01*
X1334505Y224683D01*
X1339742Y220909D01*
X1366640Y215656D01*
X1370408Y210010D01*
X1372364Y200204D01*
X1386950Y178324D01*
Y153463D01*
X1394990Y141400D01*
X1401719Y137344D01*
X1407170Y129162D01*
X1422683Y56164D01*
X1445900Y39545D01*
X1454146Y36809D01*
X1460082Y29054D01*
X1493672Y19454D01*
X1495490Y16727D01*
X1501500Y12720D01*
X1506802Y11659D01*
X1517790Y13857D01*
X1526789Y11286D01*
X1545044Y15165D01*
X1546654Y14691D01*
X1551223Y15662D01*
X1554595Y14987D01*
X1561043Y16276D01*
X1565192Y15449D01*
X1565510Y15386D01*
X1577699Y17825D01*
X1577780Y17817D01*
X1598013Y13570D01*
X1615748Y17341D01*
X1629788Y14362D01*
X1630873Y13023D01*
Y7275D01*
X1630423Y6825D01*
X1629148D01*
G01X1336900Y232118D02*
X1338542D01*
X1338993Y231667D01*
Y228860D01*
X1340887Y225061D01*
X1343940Y222903D01*
X1368357Y218142D01*
X1373176Y210910D01*
X1375162Y200983D01*
X1375287Y200794D01*
X1375288D01*
X1392750Y174600D01*
Y149901D01*
X1396988Y143541D01*
X1403216Y139789D01*
X1409475Y130402D01*
X1424934Y57640D01*
X1446088Y42497D01*
X1461578Y37356D01*
X1466525Y29942D01*
X1495870Y21558D01*
X1497783Y18688D01*
X1502197Y15745D01*
X1506285Y14927D01*
X1516236Y16917D01*
X1526828Y13890D01*
X1545134Y17775D01*
X1546768Y17297D01*
X1551236Y18246D01*
X1554147Y17664D01*
X1560944Y19023D01*
X1565192Y18173D01*
X1565783Y18055D01*
X1565785D01*
X1577786Y20456D01*
X1598052Y16153D01*
X1615716Y19905D01*
X1625400Y17850D01*
X1632565D01*
X1633215Y17200D01*
X1634565D01*
X1635215Y17850D01*
X1636565D01*
X1639952Y16302D01*
X1640668Y15586D01*
Y11555D01*
X1640218Y11105D01*
X1638865D01*
G01X1322260Y282730D02*
X1320900Y284090D01*
Y286273D01*
X1321357Y286730D01*
X1323690D01*
X1326328Y287940D01*
X1329205Y296837D01*
X1330024Y297255D01*
X1330439Y298540D01*
X1330021Y299358D01*
X1330436Y300643D01*
X1331255Y301061D01*
X1331670Y302346D01*
X1331251Y303164D01*
X1337183Y321510D01*
X1351696Y327453D01*
X1361942Y324437D01*
X1365698Y325484D01*
X1368686Y324787D01*
X1370963Y325616D01*
X1372065Y325354D01*
X1376504Y322360D01*
X1380572Y321572D01*
X1381107D01*
X1387303Y322777D01*
X1391751Y321912D01*
X1409576Y325377D01*
X1411212Y326480D01*
X1412134Y327846D01*
X1413890Y336879D01*
X1413115Y340863D01*
X1413629Y341625D01*
X1413371Y342950D01*
X1412609Y343464D01*
X1412352Y344790D01*
X1412866Y345552D01*
X1412608Y346877D01*
X1411846Y347391D01*
X1411588Y348716D01*
X1412283Y352290D01*
X1413470Y354070D01*
X1413472Y354072D01*
X1429463Y364731D01*
X1432595Y374421D01*
X1431453Y379803D01*
X1432403Y384290D01*
X1431141Y390248D01*
X1432950Y398910D01*
Y422799D01*
X1434176Y428564D01*
X1440539Y433169D01*
X1443084Y441173D01*
X1441416Y447291D01*
X1441882Y448754D01*
X1441887Y448772D01*
X1444361Y450400D01*
X1446313D01*
G01X1318751Y282730D02*
X1319750Y283729D01*
Y286750D01*
X1320880Y287880D01*
X1323438D01*
X1325389Y288775D01*
X1336253Y322372D01*
X1351634Y328671D01*
X1361951Y325634D01*
X1365673Y326671D01*
X1368614Y325985D01*
X1368655Y326000D01*
X1370894Y326815D01*
X1372535Y326425D01*
X1376953Y323445D01*
X1380683Y322722D01*
X1380996D01*
X1387303Y323949D01*
X1391751Y323084D01*
X1409127Y326462D01*
X1410384Y327309D01*
X1411049Y328296D01*
X1412718Y336879D01*
X1411986Y340642D01*
Y340643D01*
X1411941Y340877D01*
X1411895Y341111D01*
X1411894D01*
X1410416Y348716D01*
X1411198Y352736D01*
X1412576Y354803D01*
X1412739Y354966D01*
X1428491Y365466D01*
X1431406Y374483D01*
X1430277Y379803D01*
X1431227Y384290D01*
X1429965Y390246D01*
X1431800Y399029D01*
Y422920D01*
X1433143Y429236D01*
X1439557Y433879D01*
X1441885Y441198D01*
X1440217Y447316D01*
X1440914Y449509D01*
X1444016Y451550D01*
X1446313D01*
G01X1627715Y39934D02*
X1626199Y39923D01*
X1625746Y40370D01*
X1625739Y42189D01*
X1624377Y43550D01*
X1622600D01*
X1605455Y39908D01*
X1595105Y42108D01*
X1588041Y40606D01*
X1583450Y41582D01*
X1580737Y41006D01*
X1569594Y43372D01*
X1556630Y40620D01*
X1541298Y43878D01*
X1530837Y41654D01*
X1491587Y49995D01*
X1483985Y48381D01*
X1458446Y57389D01*
X1439449Y70989D01*
X1425079Y138584D01*
X1422420Y142572D01*
X1415593Y176731D01*
X1399373Y200934D01*
X1398140Y207100D01*
X1399098Y211893D01*
X1408204Y217956D01*
X1409416Y224029D01*
X1405960Y233613D01*
X1401806Y240058D01*
X1394989Y245035D01*
X1386061Y267875D01*
X1384052Y271805D01*
X1377700Y274045D01*
X1362231Y284967D01*
X1361569Y287816D01*
X1340623Y296510D01*
X1339760Y298408D01*
Y300739D01*
G02X1339950Y301106I449J0D01*
G02X1340281Y301243I331J-331D01*
G01X1341740D01*
G01X1336240D02*
X1338106D01*
X1338160Y301189D01*
G02X1338610Y300739I0J-450D01*
G01Y298158D01*
X1339763Y295621D01*
X1360582Y286980D01*
X1361209Y284280D01*
X1377167Y273013D01*
X1383236Y270872D01*
X1385010Y267402D01*
X1394039Y244303D01*
X1400955Y239255D01*
X1404922Y233099D01*
X1408225Y223940D01*
X1407169Y218649D01*
X1398063Y212587D01*
X1396967Y207100D01*
X1398290Y200484D01*
X1414510Y176281D01*
X1421336Y142123D01*
X1424000Y138129D01*
X1438416Y70313D01*
X1457909Y56358D01*
X1483907Y47188D01*
X1491587Y48819D01*
X1530837Y40478D01*
X1541298Y42702D01*
X1556630Y39444D01*
X1569594Y42196D01*
X1580737Y39830D01*
X1583450Y40406D01*
X1588041Y39430D01*
X1595105Y40932D01*
X1605455Y38732D01*
X1622721Y42400D01*
X1623900D01*
X1624590Y41710D01*
X1624596Y40364D01*
X1624151Y39911D01*
X1622635Y39900D01*
G01X1353400Y232118D02*
X1351675D01*
X1351225Y231668D01*
Y230850D01*
X1351770Y229689D01*
X1360291Y224009D01*
X1371526Y221742D01*
X1376684Y214006D01*
X1379107Y201894D01*
X1396400Y175949D01*
Y151101D01*
X1399537Y146395D01*
X1405773Y142637D01*
X1412885Y131965D01*
X1428215Y59792D01*
X1445258Y47594D01*
X1463742Y41072D01*
X1469423Y33063D01*
X1486022Y28318D01*
X1506301Y23867D01*
X1513291Y20414D01*
X1515664Y20888D01*
X1526539Y17781D01*
X1544988Y21695D01*
X1547305Y21201D01*
X1551240Y22038D01*
X1553865Y21513D01*
X1560780Y22896D01*
X1565912Y21870D01*
X1577757Y24239D01*
X1577777D01*
X1577997Y24193D01*
X1578000Y24192D01*
X1578006Y24191D01*
X1578016Y24189D01*
X1578027Y24187D01*
X1578040Y24184D01*
X1598020Y19942D01*
X1615862Y23733D01*
X1620092Y22834D01*
X1635792Y26169D01*
X1641816Y24890D01*
X1649527Y20554D01*
X1651223Y16564D01*
Y9152D01*
X1652023Y8352D01*
Y6775D01*
X1652473Y6325D01*
X1653748D01*
G01X1347900Y232118D02*
X1349625D01*
X1350075Y231668D01*
Y230593D01*
X1350863Y228911D01*
X1359841Y222926D01*
X1370832Y220708D01*
X1375601Y213557D01*
X1378024Y201445D01*
X1395250Y175600D01*
Y150752D01*
X1398579Y145756D01*
X1398943Y145410D01*
X1404957Y141785D01*
X1411806Y131508D01*
X1427182Y59116D01*
X1444721Y46563D01*
X1463015Y40109D01*
X1468718Y32067D01*
X1485740Y27202D01*
X1505915Y22773D01*
X1513133Y19208D01*
X1515616Y19705D01*
X1526498Y16596D01*
X1544987Y20519D01*
X1547305Y20025D01*
X1551247Y20863D01*
X1553865Y20340D01*
X1560780Y21723D01*
X1565912Y20697D01*
X1577760Y23066D01*
X1577785Y23061D01*
X1577796Y23059D01*
X1577801Y23058D01*
Y23057D01*
X1598020Y18766D01*
X1615862Y22557D01*
X1620092Y21658D01*
X1635792Y24993D01*
X1641405Y23801D01*
X1648621Y19743D01*
X1650073Y16329D01*
Y8675D01*
X1650873Y7875D01*
Y6775D01*
X1650423Y6325D01*
X1648748D01*
G01X1637398Y39862D02*
X1635849D01*
X1635399Y40312D01*
Y42853D01*
X1633744Y44508D01*
X1624378Y46497D01*
X1605554Y42495D01*
X1595105Y44715D01*
X1588093Y43224D01*
X1583464Y44208D01*
X1580698Y43621D01*
X1569593Y45979D01*
X1556533Y43206D01*
X1541298Y46444D01*
X1531019Y44259D01*
X1491653Y52624D01*
X1484069Y51015D01*
X1459618Y59638D01*
X1441702Y72463D01*
X1427427Y139618D01*
X1424784Y143580D01*
X1417983Y177612D01*
X1417941Y177822D01*
X1401873Y201934D01*
X1400819Y207209D01*
X1401364Y209936D01*
X1410414Y215960D01*
X1412046Y224125D01*
X1407884Y235666D01*
X1403867Y242033D01*
X1397084Y246984D01*
X1388883Y267957D01*
X1385406Y274760D01*
X1375587Y279639D01*
X1371913Y286107D01*
X1353266Y295946D01*
X1351527Y297923D01*
Y298690D01*
G02X1352442Y299605I915J0D01*
G01X1353672D01*
G01X1347892Y299741D02*
X1347895Y299738D01*
X1349329D01*
G02X1350377Y298690I0J-1048D01*
G01Y297489D01*
X1352542Y295027D01*
X1352856Y294861D01*
X1371078Y285246D01*
X1374760Y278765D01*
X1384554Y273898D01*
X1387832Y267484D01*
X1396134Y246252D01*
X1403011Y241233D01*
X1406844Y235158D01*
X1410855Y224036D01*
X1409379Y216654D01*
X1400329Y210630D01*
X1399646Y207209D01*
X1400789Y201485D01*
X1416857Y177373D01*
X1423700Y143132D01*
X1426348Y139163D01*
X1440669Y71787D01*
X1459081Y58607D01*
X1483991Y49822D01*
X1491653Y51448D01*
X1531019Y43083D01*
X1541298Y45268D01*
X1556532Y42030D01*
Y42031D01*
X1556533Y42030D01*
X1569593Y44803D01*
X1569594Y44802D01*
Y44803D01*
X1580698Y42445D01*
X1583464Y43032D01*
X1588093Y42048D01*
X1595105Y43539D01*
X1605554Y41319D01*
X1624378Y45321D01*
X1633171Y43453D01*
X1634249Y42376D01*
Y40312D01*
X1633799Y39862D01*
X1632398D01*
G01X1364400Y232118D02*
X1362462D01*
X1362101Y231757D01*
Y231075D01*
X1362428Y230602D01*
X1367564Y225466D01*
X1372979Y224384D01*
X1379075Y215239D01*
X1381496Y203136D01*
X1406796Y165202D01*
X1412269Y137867D01*
X1415204Y133464D01*
X1429894Y64326D01*
X1453326Y47551D01*
X1483419Y36937D01*
X1492144Y38787D01*
X1543749Y27818D01*
X1547358Y28583D01*
X1553858Y27202D01*
X1558280Y28141D01*
X1562809Y27179D01*
X1567700Y28218D01*
X1572585Y27180D01*
X1577476Y28219D01*
X1581974Y27264D01*
X1587988Y28542D01*
X1593923Y27280D01*
X1597812Y28107D01*
X1601406Y27344D01*
X1606175Y28356D01*
X1620093Y25400D01*
X1635964Y28772D01*
X1645868Y26669D01*
X1659755Y18970D01*
X1660673Y17038D01*
Y10726D01*
X1661245Y10154D01*
X1662373D01*
G01X1375400Y232118D02*
X1373675D01*
X1373225Y231668D01*
Y229617D01*
X1381157Y218280D01*
X1383956Y204282D01*
X1409156Y166443D01*
X1414567Y139395D01*
X1417420Y135113D01*
X1432145Y65801D01*
X1454493Y49802D01*
X1483579Y39544D01*
X1492282Y41390D01*
X1543852Y30435D01*
X1547335Y31173D01*
X1553903Y29777D01*
X1558280Y30707D01*
X1562809Y29745D01*
X1567700Y30784D01*
X1572585Y29746D01*
X1577476Y30785D01*
X1581885Y29849D01*
X1587876Y31122D01*
X1592582Y30122D01*
X1596540Y30963D01*
X1601384Y29934D01*
X1606107Y30937D01*
X1620095Y27966D01*
X1636011Y31348D01*
X1665894Y25002D01*
X1668914Y22986D01*
X1670250Y19854D01*
Y6850D01*
X1670864Y6236D01*
X1671979D01*
G01X1386400Y232118D02*
X1384675D01*
X1384225Y231668D01*
Y231031D01*
X1385424Y229323D01*
X1391805Y197428D01*
X1411320Y168422D01*
X1416886Y140609D01*
X1417983Y138964D01*
X1419718Y136361D01*
X1434395Y67276D01*
X1455665Y52051D01*
X1483562Y42211D01*
X1492135Y44029D01*
X1543930Y33021D01*
X1547583Y33797D01*
X1554164Y32399D01*
X1558280Y33273D01*
X1562809Y32311D01*
X1567700Y33350D01*
X1572585Y32312D01*
X1577476Y33351D01*
X1581885Y32415D01*
X1588001Y33714D01*
X1592708Y32714D01*
X1596610Y33543D01*
X1601455Y32514D01*
X1606107Y33503D01*
X1620094Y30532D01*
X1636191Y33952D01*
X1671350Y26484D01*
X1673303Y25180D01*
X1679625Y15539D01*
Y11831D01*
X1680075Y11381D01*
X1681428D01*
G01X1690948Y10725D02*
X1689548D01*
X1689024Y11249D01*
Y17775D01*
X1685298Y24301D01*
X1680453Y27535D01*
X1637169Y36727D01*
X1620096Y33097D01*
X1606107Y36069D01*
X1601500Y35090D01*
X1596656Y36119D01*
X1592932Y35328D01*
X1588225Y36328D01*
X1581885Y34981D01*
X1577476Y35917D01*
X1572585Y34878D01*
X1567700Y35916D01*
X1562809Y34877D01*
X1558280Y35839D01*
X1554356Y35005D01*
X1547778Y36404D01*
X1544039Y35612D01*
X1492073Y46658D01*
X1483599Y44861D01*
X1456837Y54299D01*
X1436641Y68755D01*
X1422054Y137462D01*
X1419296Y141600D01*
X1413674Y169731D01*
X1399006Y191741D01*
X1390541Y217842D01*
X1392321Y226529D01*
X1395225Y230667D01*
Y231668D01*
X1395675Y232118D01*
X1397400D01*
G01X1358900D02*
X1360501D01*
X1360951Y231668D01*
Y230715D01*
X1361541Y229862D01*
X1366997Y224406D01*
X1372286Y223349D01*
X1377992Y214790D01*
X1380413Y202687D01*
X1405713Y164753D01*
X1411186Y137418D01*
X1414124Y133009D01*
X1428861Y63650D01*
X1452789Y46520D01*
X1483341Y35744D01*
X1492142Y37611D01*
X1543749Y26642D01*
X1547358Y27407D01*
X1553858Y26026D01*
X1558280Y26965D01*
X1562809Y26003D01*
X1567700Y27042D01*
X1572585Y26004D01*
X1577477Y27043D01*
X1581974Y26088D01*
X1587988Y27366D01*
X1593923Y26104D01*
X1597812Y26931D01*
X1601406Y26168D01*
X1606175Y27180D01*
X1620093Y24224D01*
X1635964Y27596D01*
X1645461Y25579D01*
X1658874Y18142D01*
X1659523Y16778D01*
Y10824D01*
X1658957Y10258D01*
X1657369D01*
G01X1369900Y232118D02*
X1371625D01*
X1372075Y231668D01*
Y229254D01*
X1380076Y217818D01*
X1382872Y203833D01*
X1408072Y165994D01*
X1413483Y138946D01*
X1416340Y134658D01*
X1431112Y65125D01*
X1453956Y48771D01*
X1483501Y38351D01*
X1492282Y40214D01*
X1543852Y29259D01*
X1547335Y29997D01*
X1553903Y28601D01*
X1558280Y29531D01*
X1562809Y28569D01*
X1567700Y29608D01*
X1572584Y28570D01*
X1577476Y29609D01*
X1581885Y28673D01*
X1587876Y29946D01*
X1592582Y28946D01*
X1596540Y29787D01*
X1601384Y28758D01*
X1606107Y29761D01*
X1620095Y26790D01*
X1636011Y30172D01*
X1665439Y23922D01*
X1667990Y22219D01*
X1669100Y19618D01*
Y6800D01*
X1668536Y6236D01*
X1666979D01*
G01X1380900Y232118D02*
X1382625D01*
X1383075Y231668D01*
Y230667D01*
X1384343Y228860D01*
X1390722Y196977D01*
X1410237Y167971D01*
X1415803Y140160D01*
X1418638Y135906D01*
X1433362Y66600D01*
X1455128Y51020D01*
X1483484Y41018D01*
X1492135Y42853D01*
X1543930Y31845D01*
X1547583Y32621D01*
X1554164Y31223D01*
X1558280Y32097D01*
X1562809Y31135D01*
X1567700Y32174D01*
X1572584Y31136D01*
X1577476Y32175D01*
X1581885Y31239D01*
X1588001Y32538D01*
X1592708Y31538D01*
X1596610Y32367D01*
X1601455Y31338D01*
X1606107Y32327D01*
X1620094Y29356D01*
X1636191Y32776D01*
X1670895Y25404D01*
X1672469Y24353D01*
X1678475Y15195D01*
Y12000D01*
X1677856Y11381D01*
X1676428D01*
G01X1685948Y10725D02*
X1687306D01*
X1687874Y11293D01*
Y17469D01*
X1684433Y23495D01*
X1679998Y26455D01*
X1637169Y35551D01*
X1620096Y31921D01*
X1606107Y34893D01*
X1601500Y33914D01*
X1596656Y34943D01*
X1592932Y34152D01*
X1588225Y35152D01*
X1581885Y33805D01*
X1577476Y34741D01*
X1572585Y33702D01*
X1567700Y34740D01*
X1562809Y33701D01*
X1558280Y34663D01*
X1554356Y33829D01*
X1547778Y35228D01*
X1544039Y34436D01*
X1492073Y45482D01*
X1483521Y43668D01*
X1456300Y53268D01*
X1435608Y68079D01*
X1420974Y137007D01*
X1418212Y141151D01*
X1417983Y142297D01*
X1412590Y169282D01*
X1397961Y191235D01*
X1389353Y217776D01*
X1391242Y226994D01*
X1394075Y231031D01*
Y231668D01*
X1393625Y232118D01*
X1391900D01*
G01X1646848Y39462D02*
X1645418D01*
X1644968Y39912D01*
Y43463D01*
X1643413Y45019D01*
X1624138Y49109D01*
X1605410Y45131D01*
X1595105Y47322D01*
X1588378Y45892D01*
X1583805Y46864D01*
X1580754Y46216D01*
X1569591Y48587D01*
X1556438Y45793D01*
X1541301Y49010D01*
X1530997Y46820D01*
X1491623Y55188D01*
X1484228Y53619D01*
X1460789Y61887D01*
X1444156Y73792D01*
X1430010Y140360D01*
X1427129Y144685D01*
X1420249Y179115D01*
X1415767Y185759D01*
X1411333Y207949D01*
X1414691Y224343D01*
X1412271Y231056D01*
X1411341Y235452D01*
X1411187Y236249D01*
X1406121Y243903D01*
X1399229Y248924D01*
X1391933Y267591D01*
X1386819Y277598D01*
X1379301Y282064D01*
X1371492Y293168D01*
X1365325Y297017D01*
X1365117Y297912D01*
X1363972Y298627D01*
X1363076Y298420D01*
X1361869Y299173D01*
Y299900D01*
G02X1362784Y300815I915J0D01*
G01X1364014D01*
G01X1656298Y39462D02*
X1654939D01*
X1654450Y39951D01*
Y41550D01*
X1649690Y46310D01*
X1624094Y51743D01*
X1605327Y47756D01*
X1594800Y49994D01*
X1588046Y48558D01*
X1583543Y49515D01*
X1580518Y48873D01*
X1569593Y51193D01*
X1556340Y48379D01*
X1541301Y51576D01*
X1531078Y49403D01*
X1491552Y57802D01*
X1484284Y56259D01*
X1461959Y64134D01*
X1446421Y75257D01*
X1432346Y141442D01*
X1429537Y145656D01*
X1422636Y180134D01*
X1418791Y185848D01*
X1417983Y189887D01*
X1414151Y209045D01*
X1417342Y224610D01*
X1414615Y232173D01*
X1411448Y247170D01*
X1404270Y252400D01*
X1399556Y265595D01*
Y265596D01*
X1399555Y265597D01*
X1389160Y282123D01*
Y282122D01*
X1384052Y292520D01*
X1372665Y299467D01*
Y300769D01*
G02X1373115Y301219I450J0D01*
G01X1374820D01*
G01X1386101Y301465D02*
X1384313D01*
G03X1383868Y301080I0J-450D01*
G01X1383863Y301046D01*
Y298915D01*
X1384914Y296775D01*
X1385514Y296571D01*
X1386939Y297271D01*
X1388442Y296758D01*
X1389261Y295093D01*
X1388748Y293590D01*
X1387323Y292890D01*
X1387119Y292290D01*
X1387518Y291476D01*
X1388118Y291272D01*
X1389543Y291972D01*
X1391046Y291459D01*
X1391865Y289794D01*
X1391352Y288291D01*
X1389928Y287591D01*
X1389723Y286991D01*
X1391954Y282482D01*
X1391955D01*
X1391949Y282478D01*
X1391950D01*
X1401819Y266848D01*
X1406407Y253998D01*
X1413695Y248685D01*
X1417080Y232714D01*
X1420075Y224402D01*
X1419447Y221338D01*
X1422610Y205549D01*
X1421354Y199268D01*
X1431850Y146896D01*
X1434702Y142619D01*
X1445748Y90678D01*
X1451103Y82646D01*
X1459261Y77208D01*
X1460400Y75501D01*
X1461939Y70808D01*
X1472965Y62915D01*
X1484321Y58910D01*
X1491364Y60403D01*
X1531079Y51969D01*
X1541298Y54142D01*
X1556245Y50966D01*
X1569591Y53799D01*
X1580266Y51533D01*
X1583356Y52190D01*
X1588108Y51178D01*
X1594799Y52601D01*
X1595038Y52551D01*
Y52550D01*
X1604933Y50446D01*
X1614154Y52404D01*
X1623854Y54464D01*
X1650905Y48723D01*
X1656977Y42650D01*
X1662313D01*
X1663936Y41027D01*
Y40063D01*
X1664537Y39462D01*
X1665748D01*
G01X1675198D02*
X1673739D01*
X1673400Y39801D01*
Y41700D01*
X1672251Y42849D01*
X1665851D01*
X1659126Y49574D01*
X1623856Y57063D01*
X1604958Y53048D01*
X1594799Y55208D01*
X1588136Y53791D01*
X1583460Y54785D01*
X1580344Y54123D01*
X1569590Y56407D01*
X1556150Y53552D01*
X1541298Y56708D01*
X1531103Y54540D01*
X1491091Y63045D01*
X1484259Y61595D01*
X1474341Y65090D01*
X1464174Y72369D01*
X1461412Y85363D01*
X1460300Y87033D01*
X1458561Y88192D01*
X1454251Y89054D01*
X1450734Y91398D01*
X1447014Y96984D01*
X1437088Y143658D01*
X1434317Y147815D01*
X1424016Y199320D01*
X1429249Y212930D01*
X1423502Y227112D01*
X1419677Y233078D01*
X1416065Y250113D01*
X1408544Y255596D01*
X1404125Y267973D01*
X1394335Y283479D01*
X1395460Y289759D01*
Y301601D01*
G02X1395910Y302051I450J0D01*
G01X1397635D01*
G01X1358514Y300815D02*
X1359804D01*
G02X1360719Y299900I0J-915D01*
G01Y298534D01*
X1370685Y292316D01*
X1370684D01*
X1378500Y281200D01*
X1378712Y281074D01*
X1378714Y281075D01*
X1385945Y276778D01*
X1390882Y267118D01*
X1398280Y248192D01*
X1405276Y243095D01*
X1410104Y235800D01*
X1410102D01*
X1410213Y235224D01*
X1411162Y230740D01*
X1413499Y224257D01*
X1410158Y207946D01*
X1414684Y185307D01*
X1417983Y180417D01*
X1419166Y178663D01*
X1426045Y144236D01*
X1428930Y139905D01*
X1443123Y73116D01*
X1460252Y60856D01*
X1484150Y52426D01*
X1491623Y54012D01*
X1530997Y45644D01*
X1541301Y47834D01*
X1556438Y44617D01*
X1569593Y47410D01*
X1580754Y45040D01*
X1583808Y45688D01*
Y45687D01*
X1588378Y44716D01*
X1595105Y46146D01*
X1605410Y43955D01*
X1624138Y47933D01*
X1642842Y43962D01*
X1643818Y42986D01*
Y39912D01*
X1643368Y39462D01*
X1641848D01*
G01X1369320Y301219D02*
X1371065D01*
G02X1371515Y300769I0J-450D01*
G01Y298821D01*
X1383167Y291712D01*
Y291711D01*
X1388154Y281561D01*
X1398514Y265091D01*
X1403306Y251679D01*
X1410414Y246500D01*
X1413506Y231858D01*
X1416150Y224524D01*
X1412977Y209048D01*
X1417708Y185397D01*
X1417983Y184988D01*
X1421553Y179683D01*
X1428454Y145207D01*
X1431267Y140987D01*
X1445389Y74581D01*
X1461422Y63103D01*
X1484206Y55066D01*
X1491552Y56626D01*
X1531078Y48227D01*
X1541301Y50400D01*
X1556340Y47203D01*
X1569594Y50017D01*
X1580518Y47697D01*
X1583545Y48339D01*
Y48338D01*
X1588046Y47382D01*
X1594800Y48818D01*
X1605327Y46580D01*
X1624094Y50567D01*
X1649117Y45255D01*
X1653300Y41073D01*
Y39900D01*
X1652862Y39462D01*
X1651298D01*
G01X1380601Y301465D02*
X1382263D01*
G02X1382710Y301067I0J-450D01*
G01X1382713Y301015D01*
Y298647D01*
X1384092Y295840D01*
X1385594Y295328D01*
X1387019Y296028D01*
X1387620Y295823D01*
X1388018Y295013D01*
X1387813Y294412D01*
X1386388Y293712D01*
X1385876Y292210D01*
X1386696Y290541D01*
X1388198Y290029D01*
X1389623Y290729D01*
X1390224Y290524D01*
X1390622Y289714D01*
X1390417Y289113D01*
X1388993Y288413D01*
X1388480Y286910D01*
X1390976Y281864D01*
X1390977Y281863D01*
X1400778Y266341D01*
X1405443Y253277D01*
X1412661Y248015D01*
X1415971Y232398D01*
X1418883Y224316D01*
X1418273Y221341D01*
X1421437Y205549D01*
X1420181Y199268D01*
X1430767Y146447D01*
X1433623Y142164D01*
X1444669Y90223D01*
X1450145Y82008D01*
X1450273Y81816D01*
X1458431Y76378D01*
X1459355Y74992D01*
X1460962Y70092D01*
X1472428Y61884D01*
X1484243Y57717D01*
X1491364Y59227D01*
X1531079Y50793D01*
X1541298Y52966D01*
X1556245Y49790D01*
X1569591Y52623D01*
X1580266Y50357D01*
X1583356Y51014D01*
X1588108Y50002D01*
X1594799Y51425D01*
X1604933Y49270D01*
X1623854Y53288D01*
X1650332Y47668D01*
X1656500Y41500D01*
X1661836D01*
X1662786Y40550D01*
Y39912D01*
X1662336Y39462D01*
X1660748D01*
G01X1392135Y302051D02*
X1393860D01*
G02X1394310Y301601I0J-450D01*
G01Y289862D01*
X1393124Y283242D01*
X1403084Y267466D01*
X1407579Y254875D01*
X1415031Y249443D01*
X1417983Y235520D01*
X1418595Y232634D01*
X1422472Y226586D01*
X1428012Y212919D01*
X1422822Y199422D01*
X1433234Y147366D01*
X1436009Y143202D01*
X1445935Y96527D01*
X1449904Y90568D01*
X1453802Y87971D01*
X1458112Y87109D01*
X1459470Y86204D01*
X1460332Y84908D01*
X1463141Y71693D01*
X1473804Y64059D01*
X1484182Y60402D01*
X1491091Y61869D01*
X1531103Y53364D01*
X1541298Y55532D01*
X1556150Y52376D01*
X1569590Y55231D01*
X1580344Y52947D01*
X1583460Y53609D01*
X1588136Y52615D01*
X1594799Y54032D01*
X1604958Y51872D01*
X1623856Y55887D01*
X1658553Y48519D01*
X1665374Y41699D01*
X1671774D01*
X1672250Y41223D01*
Y39846D01*
X1671866Y39462D01*
X1670198D01*
G01X1403037Y302046D02*
X1404762D01*
G02X1405212Y301596I0J-450D01*
G01Y295504D01*
X1408240Y285428D01*
X1404210Y271896D01*
X1409718Y256474D01*
X1417276Y250965D01*
X1417983Y247630D01*
X1420875Y233986D01*
X1425595Y226624D01*
X1430941Y213447D01*
X1425623Y199627D01*
X1435898Y147968D01*
Y147967D01*
X1438401Y144213D01*
X1447604Y100931D01*
X1449505Y98150D01*
X1457241Y95456D01*
X1462015Y89069D01*
X1465372Y73269D01*
X1475212Y66225D01*
X1484163Y63070D01*
X1490865Y64491D01*
X1531143Y55938D01*
X1541292Y58099D01*
X1556054Y54963D01*
X1569588Y57837D01*
X1580322Y55559D01*
X1583325Y56197D01*
Y56196D01*
X1583326Y56197D01*
X1588095Y55183D01*
X1594870Y56624D01*
X1604886Y54495D01*
X1623768Y58504D01*
X1659820Y50852D01*
X1666472Y44200D01*
X1673173D01*
X1675172Y42201D01*
X1680672D01*
X1681600Y41273D01*
Y39900D01*
X1681162Y39462D01*
X1679648D01*
G01X1684648D02*
X1683138D01*
X1682750Y39850D01*
Y41750D01*
X1681149Y43351D01*
X1675649D01*
X1673650Y45350D01*
X1666949D01*
X1660393Y51907D01*
X1623768Y59680D01*
X1604886Y55671D01*
X1594870Y57800D01*
X1588095Y56359D01*
X1583326Y57373D01*
X1580322Y56735D01*
X1569588Y59013D01*
X1556054Y56139D01*
X1541292Y59275D01*
X1531143Y57114D01*
X1490865Y65667D01*
X1484241Y64263D01*
X1475749Y67256D01*
X1466405Y73945D01*
X1463088Y89556D01*
X1457952Y96427D01*
X1450241Y99112D01*
X1448682Y101392D01*
X1439480Y144668D01*
X1436982Y148415D01*
X1426816Y199525D01*
X1432178Y213458D01*
X1426621Y227155D01*
X1421957Y234430D01*
X1418310Y251635D01*
X1417983Y251873D01*
X1410682Y257195D01*
X1405420Y271928D01*
X1409441Y285429D01*
X1406362Y295674D01*
Y301596D01*
G02X1406812Y302046I450J0D01*
G01X1408537D01*
G01X1413720Y301983D02*
X1415445D01*
X1415893Y301535D01*
Y301528D01*
X1413102Y286682D01*
X1407630Y269900D01*
X1411855Y258071D01*
X1419527Y252478D01*
X1423231Y235013D01*
X1429069Y225904D01*
X1433932Y213909D01*
X1430788Y205724D01*
X1434335Y187998D01*
X1432294Y181321D01*
X1435488Y165284D01*
X1440135Y158308D01*
X1441842Y148902D01*
X1440833Y145031D01*
X1449995Y101952D01*
X1451136Y100283D01*
X1459416Y97398D01*
X1464232Y90955D01*
X1467650Y74870D01*
X1476775Y68334D01*
X1476783Y68331D01*
Y68332D01*
X1484229Y65704D01*
X1490722Y67083D01*
X1531118Y58500D01*
X1541300Y60663D01*
X1555956Y57549D01*
X1569590Y60444D01*
X1580390Y58151D01*
X1583377Y58786D01*
Y58785D01*
X1588075Y57785D01*
X1594869Y59231D01*
X1604897Y57099D01*
X1623834Y61121D01*
X1661049Y53222D01*
X1667572Y46700D01*
X1674501D01*
X1675962Y45239D01*
X1683049D01*
X1690734Y41549D01*
X1691100Y41183D01*
Y39900D01*
X1690662Y39462D01*
X1689098D01*
G01X1694098D02*
X1692539D01*
X1692250Y39751D01*
Y41660D01*
X1691409Y42501D01*
X1683311Y46389D01*
X1676439D01*
X1674978Y47850D01*
X1668049D01*
X1661622Y54277D01*
X1623834Y62297D01*
X1604897Y58275D01*
X1594869Y60407D01*
X1588075Y58961D01*
X1583376Y59962D01*
X1580390Y59327D01*
X1569590Y61621D01*
X1555956Y58725D01*
X1541300Y61839D01*
X1531118Y59676D01*
X1490722Y68259D01*
X1484307Y66897D01*
X1477312Y69365D01*
X1468683Y75546D01*
X1465305Y91442D01*
X1460127Y98369D01*
X1451872Y101246D01*
X1451073Y102414D01*
X1442015Y145004D01*
X1443019Y148858D01*
X1441224Y158748D01*
X1436572Y165732D01*
X1433479Y181262D01*
X1435520Y187939D01*
X1431982Y205623D01*
X1435169Y213920D01*
X1430095Y226435D01*
X1424313Y235457D01*
X1420561Y253148D01*
X1412819Y258792D01*
X1408846Y269917D01*
X1414218Y286390D01*
X1417040Y301401D01*
X1417041Y301406D01*
X1417046Y301542D01*
G02X1417495Y301983I449J-8D01*
G01X1419220D01*
G01X1799462Y8830D02*
X1801720Y11088D01*
Y13551D01*
X1799749Y15522D01*
X1783578Y28245D01*
X1782771Y28715D01*
X1771886Y30893D01*
X1764596Y35751D01*
X1761038Y41019D01*
X1756994Y43717D01*
X1751563Y44802D01*
X1745729Y43572D01*
X1739115Y44978D01*
X1733790Y48554D01*
X1732642D01*
X1727829Y47531D01*
X1727600D01*
X1716510Y49531D01*
X1711906Y48593D01*
X1706203Y49754D01*
X1703754Y51375D01*
X1691219Y53926D01*
X1687279Y53124D01*
X1682183Y54162D01*
X1681911D01*
X1679577Y56496D01*
X1671826Y58071D01*
X1669681Y57644D01*
X1624493Y67240D01*
X1624492Y67241D01*
X1618401Y65860D01*
X1604298Y70502D01*
X1588827Y67080D01*
X1583371Y68239D01*
X1576760Y72616D01*
X1575258Y72921D01*
X1567324Y71307D01*
X1565192Y69897D01*
X1563492Y68772D01*
X1563322Y68602D01*
X1563082D01*
X1559131Y67812D01*
X1544523Y70735D01*
X1530130Y67663D01*
X1497262Y74823D01*
X1477306Y88770D01*
X1459388Y112737D01*
X1453595Y139989D01*
X1455129Y145293D01*
X1453111Y152658D01*
X1449692Y156163D01*
X1444718Y183542D01*
X1445031Y184494D01*
X1441549Y199350D01*
X1445099Y217125D01*
X1444758Y218830D01*
X1431444Y238796D01*
X1427374Y258011D01*
X1422226Y261764D01*
X1420195Y270217D01*
X1427150Y303051D01*
Y316446D01*
X1429528Y328091D01*
X1426197Y344752D01*
X1428188Y354709D01*
X1437352Y360818D01*
X1441539Y373784D01*
X1441540D01*
X1440371Y379290D01*
X1441224Y383305D01*
X1439804Y390035D01*
X1441572Y398372D01*
X1446450Y403250D01*
Y406585D01*
X1451220Y412572D01*
X1454418Y429166D01*
Y431369D01*
X1454830Y433192D01*
X1455625Y434239D01*
X1460667Y436950D01*
X1472320D01*
X1472849Y437479D01*
G01X1473663Y436665D02*
X1472798Y435800D01*
X1471398D01*
X1470748Y435150D01*
X1469348D01*
X1468698Y435800D01*
X1467298D01*
X1466648Y435150D01*
X1465248D01*
X1464598Y435800D01*
X1460957D01*
X1456390Y433344D01*
X1455897Y432695D01*
X1455568Y431240D01*
Y429051D01*
X1452296Y412077D01*
X1447600Y406182D01*
Y402773D01*
X1442627Y397799D01*
X1440980Y390034D01*
X1442400Y383304D01*
X1441547Y379290D01*
X1442729Y373723D01*
X1438324Y360083D01*
X1429223Y354016D01*
X1427370Y344752D01*
X1430702Y328089D01*
X1428300Y316329D01*
Y302930D01*
X1421374Y270233D01*
X1423246Y262445D01*
X1428409Y258681D01*
X1432524Y239251D01*
X1445841Y219279D01*
X1446272Y217125D01*
X1442726Y199369D01*
X1446225Y184442D01*
X1445902Y183460D01*
X1450762Y156715D01*
X1454142Y153248D01*
X1456324Y145285D01*
X1454780Y139946D01*
X1460461Y113224D01*
X1478117Y89607D01*
X1497732Y75898D01*
X1530132Y68840D01*
X1544515Y71910D01*
X1559131Y68986D01*
Y68985D01*
X1562857Y69731D01*
X1566875Y72390D01*
X1575258Y74095D01*
X1577209Y73699D01*
X1583824Y69319D01*
X1588822Y68257D01*
X1604358Y71694D01*
X1618458Y67053D01*
X1624701Y68468D01*
X1624932Y68323D01*
X1669688Y58819D01*
X1671824Y59246D01*
X1680146Y57555D01*
X1682412Y55289D01*
X1687279Y54298D01*
X1691219Y55100D01*
X1704203Y52458D01*
X1706652Y50837D01*
X1711906Y49767D01*
X1716497Y50702D01*
X1727703Y48681D01*
X1727708D01*
X1732521Y49704D01*
X1734141D01*
X1737093Y47722D01*
Y47721D01*
X1739572Y46057D01*
X1745730Y44748D01*
X1751557Y45977D01*
X1757443Y44801D01*
X1761868Y41849D01*
X1761867D01*
X1765423Y36583D01*
X1772335Y31976D01*
X1783185Y29806D01*
X1784227Y29199D01*
X1792374Y22789D01*
Y22788D01*
X1800514Y16384D01*
X1802870Y14028D01*
Y10422D01*
X1804462Y8830D01*
G01X1790078Y11860D02*
X1791280D01*
X1791961Y12541D01*
Y13837D01*
X1790934Y15473D01*
X1784061Y18416D01*
X1781707Y22119D01*
X1763493Y32543D01*
X1759004Y39277D01*
X1755747Y41405D01*
X1752417Y42069D01*
X1745485Y40596D01*
X1728911Y44119D01*
X1715622Y41294D01*
X1708228Y42778D01*
X1698908Y48946D01*
X1697398Y49254D01*
X1692517Y48260D01*
X1689887Y48793D01*
X1687373Y50457D01*
X1681387Y51676D01*
X1679257Y51242D01*
X1676452Y51813D01*
X1672592Y54369D01*
X1648150Y59399D01*
X1648149D01*
X1623705Y64430D01*
X1623703D01*
X1618171Y63169D01*
X1604161Y67770D01*
X1588492Y64441D01*
X1581065Y66017D01*
X1577417Y65498D01*
X1569294Y67224D01*
X1558725Y64978D01*
X1544132Y68079D01*
X1530054Y65085D01*
X1495706Y72564D01*
X1475854Y86451D01*
X1457009Y111660D01*
X1453859Y126481D01*
X1450735Y128759D01*
X1447306Y144884D01*
X1448393Y149049D01*
X1443492Y176032D01*
X1439940Y178319D01*
X1439128Y180870D01*
X1441307Y187230D01*
X1438695Y198413D01*
X1442371Y216818D01*
X1442143Y217953D01*
X1429068Y237573D01*
X1425038Y256576D01*
X1419959Y260278D01*
X1417589Y270148D01*
X1424400Y302329D01*
Y317498D01*
X1426381Y327032D01*
X1423026Y343800D01*
X1425449Y355904D01*
X1434564Y361980D01*
X1438618Y374529D01*
X1437533Y379637D01*
X1438403Y383815D01*
X1437071Y390091D01*
X1439051Y399402D01*
X1442235Y402586D01*
Y404768D01*
X1441205Y405798D01*
Y407254D01*
X1442980Y409029D01*
X1443252D01*
G01X1442830Y406472D02*
X1443385Y405917D01*
Y402109D01*
X1440106Y398829D01*
X1438247Y390091D01*
X1439579Y383817D01*
X1438709Y379639D01*
X1439807Y374468D01*
X1435536Y361245D01*
X1426484Y355211D01*
X1424199Y343800D01*
X1427555Y327028D01*
X1425550Y317376D01*
Y302208D01*
X1418768Y270164D01*
X1420979Y260959D01*
X1426072Y257246D01*
X1430148Y238028D01*
X1443226Y218402D01*
X1443544Y216819D01*
X1439872Y198432D01*
X1442503Y187170D01*
X1440340Y180857D01*
X1440911Y179063D01*
X1444533Y176731D01*
X1449570Y149004D01*
X1448487Y144857D01*
X1451769Y129429D01*
X1454893Y127151D01*
X1458082Y112147D01*
X1476666Y87286D01*
X1496176Y73639D01*
X1530057Y66262D01*
X1544132Y69255D01*
X1558725Y66154D01*
X1569294Y68400D01*
X1577457Y66666D01*
X1581105Y67185D01*
X1588492Y65617D01*
X1604225Y68960D01*
X1618227Y64362D01*
X1623690Y65608D01*
X1673042Y55451D01*
X1676901Y52896D01*
X1679257Y52416D01*
X1681387Y52850D01*
X1687822Y51540D01*
X1688008Y51417D01*
Y51416D01*
X1690335Y49876D01*
X1692516Y49434D01*
X1697398Y50428D01*
X1699357Y50029D01*
X1708677Y43861D01*
X1711697Y43253D01*
X1712462Y43762D01*
X1713785Y43498D01*
X1714295Y42733D01*
X1715619Y42468D01*
X1721085Y43631D01*
X1721586Y44402D01*
X1722907Y44683D01*
X1723677Y44182D01*
X1724998Y44463D01*
X1725499Y45234D01*
X1726820Y45515D01*
X1727590Y45014D01*
X1728911Y45295D01*
X1732616Y44508D01*
X1733387Y45008D01*
X1734707Y44727D01*
X1735208Y43957D01*
X1745485Y41772D01*
X1752410Y43244D01*
X1756190Y42490D01*
X1759831Y40112D01*
X1764273Y33448D01*
X1772140Y28945D01*
X1772997Y29178D01*
X1774169Y28508D01*
X1774410Y27621D01*
X1775582Y26950D01*
X1776469Y27192D01*
X1777640Y26521D01*
X1777882Y25634D01*
X1779054Y24963D01*
X1779941Y25204D01*
X1781112Y24534D01*
X1781353Y23647D01*
X1782525Y22976D01*
X1784841Y19333D01*
X1791717Y16389D01*
X1793111Y14169D01*
Y12446D01*
X1793657Y11900D01*
X1795078D01*
G01X1792700Y36871D02*
X1794750Y38921D01*
Y39401D01*
X1793852Y40748D01*
X1791534Y42294D01*
X1783783Y43843D01*
X1776150Y42317D01*
X1770238Y43501D01*
X1754485Y54006D01*
X1754478Y54011D01*
X1742031Y56498D01*
X1730411Y54030D01*
X1721134Y57631D01*
X1716417Y58591D01*
X1712214Y57742D01*
X1692925Y61667D01*
X1689706Y61012D01*
X1685700Y61827D01*
X1684328Y62736D01*
X1682684Y65220D01*
X1680589Y66605D01*
X1678435Y67044D01*
X1678434D01*
X1678433Y67043D01*
X1676346Y67470D01*
X1666418Y65484D01*
X1661594Y66449D01*
X1638099Y74719D01*
X1638100D01*
X1618200Y78700D01*
X1612112Y82758D01*
X1608316Y88454D01*
X1607174Y89100D01*
X1604111D01*
X1592775Y86374D01*
X1587024D01*
X1585875Y85224D01*
X1578199Y80074D01*
X1574937Y79422D01*
X1564521Y81108D01*
X1560802Y80365D01*
Y80364D01*
X1557083Y79620D01*
X1530207Y72995D01*
X1501483Y79233D01*
X1496988Y82355D01*
X1494073Y88005D01*
X1493414Y88864D01*
X1491214Y90318D01*
X1479972Y93723D01*
X1464144Y114893D01*
X1458849Y139799D01*
X1460428Y145257D01*
X1457608Y155551D01*
X1459669Y165593D01*
X1451443Y191581D01*
X1454962Y202673D01*
X1451200Y221645D01*
X1448459Y225755D01*
X1435006Y256345D01*
X1433666Y261530D01*
X1427829Y268923D01*
X1428783Y272896D01*
X1427388Y278699D01*
X1432250Y301707D01*
Y315720D01*
X1435466Y330901D01*
X1433051Y342977D01*
X1435075Y353105D01*
X1441949Y357686D01*
X1451859Y370969D01*
X1453493Y378917D01*
Y387606D01*
X1454296Y391399D01*
X1453308Y396053D01*
X1458449Y420758D01*
X1459907Y422984D01*
X1463123Y426200D01*
X1473000D01*
X1474310Y427510D01*
Y428099D01*
G01X1475460D02*
Y427033D01*
X1473477Y425050D01*
X1463600D01*
X1460805Y422254D01*
X1459531Y420309D01*
X1454484Y396055D01*
X1455472Y391399D01*
X1454643Y387485D01*
Y378800D01*
X1452935Y370486D01*
X1442752Y356839D01*
X1436110Y352412D01*
X1434224Y342977D01*
X1436641Y330894D01*
X1433400Y315599D01*
Y301586D01*
X1428567Y278715D01*
X1429966Y272897D01*
X1429078Y269198D01*
X1434720Y262053D01*
X1436097Y256723D01*
X1449472Y226310D01*
X1452284Y222093D01*
X1456148Y202607D01*
X1452650Y191581D01*
X1460856Y165655D01*
X1458790Y155589D01*
X1461623Y145249D01*
X1460034Y139756D01*
X1465217Y115380D01*
X1480667Y94715D01*
X1491708Y91370D01*
X1494210Y89718D01*
X1495048Y88624D01*
X1497880Y83137D01*
X1501951Y80309D01*
X1530191Y74176D01*
X1556832Y80743D01*
X1564499Y82277D01*
X1574916Y80591D01*
X1577749Y81157D01*
X1585140Y86117D01*
X1586547Y87524D01*
X1592638D01*
X1603974Y90250D01*
X1607477D01*
X1609121Y89321D01*
X1612942Y83588D01*
X1618649Y79783D01*
Y79784D01*
X1638405Y75831D01*
X1661899Y67561D01*
X1666418Y66657D01*
X1676348Y68644D01*
X1681038Y67688D01*
X1683514Y66050D01*
X1685158Y63566D01*
X1686149Y62910D01*
X1689706Y62186D01*
X1692925Y62841D01*
X1712215Y58916D01*
X1716418Y59765D01*
X1721363Y58758D01*
Y58759D01*
X1721459Y58739D01*
X1730508Y55227D01*
X1741792Y57623D01*
Y57624D01*
X1742024Y57673D01*
X1754946Y55091D01*
X1755138Y54953D01*
X1770687Y44584D01*
X1776150Y43490D01*
X1783783Y45016D01*
X1791983Y43378D01*
X1794682Y41578D01*
X1795900Y39750D01*
Y38604D01*
X1797700Y36804D01*
G01X1439651Y412466D02*
X1438662Y411477D01*
X1436949D01*
X1434900Y409428D01*
Y397676D01*
X1433497Y391088D01*
X1434811Y384895D01*
X1433666Y379502D01*
X1434787Y374225D01*
X1431370Y363648D01*
X1423230Y358218D01*
X1419505Y352632D01*
X1417950Y344859D01*
X1422186Y323679D01*
X1420415Y315112D01*
X1421300Y310940D01*
Y302872D01*
X1414279Y269739D01*
X1416961Y258572D01*
X1422233Y254732D01*
X1426117Y236400D01*
X1438077Y218458D01*
X1436675Y211410D01*
X1435799Y210096D01*
X1434483Y203505D01*
X1437670Y187573D01*
X1435670Y181228D01*
X1437003Y174571D01*
X1441886Y167247D01*
X1445168Y149171D01*
X1444069Y144958D01*
X1447904Y126924D01*
X1451028Y124646D01*
X1454251Y109488D01*
X1467123Y92268D01*
X1469314Y81961D01*
X1483539Y71781D01*
X1530925Y61714D01*
X1541161Y63888D01*
X1555172Y60910D01*
X1569592Y63972D01*
X1578579Y62063D01*
X1581082Y62597D01*
X1588065Y61176D01*
X1599978Y63600D01*
X1601172D01*
X1601882Y62890D01*
X1608452D01*
G01X1606797Y64949D02*
X1605888Y64040D01*
X1602359D01*
X1601649Y64750D01*
X1599862D01*
X1588065Y62350D01*
X1581076Y63772D01*
X1578578Y63239D01*
X1569592Y65148D01*
X1555172Y62086D01*
X1549939Y63198D01*
X1549438Y63969D01*
X1548118Y64250D01*
X1547347Y63749D01*
X1546026Y64030D01*
X1545526Y64801D01*
X1544205Y65081D01*
X1543434Y64581D01*
X1541161Y65064D01*
X1530925Y62890D01*
X1484014Y72856D01*
X1482876Y73671D01*
X1482725Y74578D01*
X1481587Y75392D01*
X1480680Y75242D01*
X1479541Y76057D01*
X1479391Y76964D01*
X1478253Y77779D01*
X1477346Y77628D01*
X1476207Y78443D01*
X1476057Y79350D01*
X1474919Y80165D01*
X1474012Y80015D01*
X1470346Y82638D01*
X1468195Y92756D01*
X1455324Y109975D01*
X1452062Y125316D01*
X1448938Y127594D01*
X1445251Y144931D01*
X1446346Y149126D01*
X1442975Y167687D01*
X1438086Y175020D01*
X1436856Y181164D01*
X1438856Y187509D01*
X1436441Y199583D01*
X1436951Y200348D01*
X1436686Y201671D01*
X1435921Y202181D01*
X1435656Y203505D01*
X1436882Y209645D01*
X1436883D01*
X1437759Y210962D01*
X1439298Y218700D01*
X1427197Y236855D01*
X1423267Y255402D01*
X1417981Y259253D01*
X1415458Y269755D01*
X1422450Y302751D01*
Y311061D01*
X1421590Y315115D01*
X1423360Y323675D01*
X1422261Y329171D01*
X1422770Y329936D01*
X1422506Y331259D01*
X1421741Y331769D01*
X1421476Y333093D01*
X1421986Y333858D01*
X1421722Y335181D01*
X1420957Y335691D01*
X1420692Y337015D01*
X1421201Y337780D01*
X1420937Y339103D01*
X1420172Y339613D01*
X1419907Y340937D01*
X1420417Y341702D01*
X1420153Y343025D01*
X1419388Y343535D01*
X1419123Y344859D01*
X1419388Y346183D01*
X1420153Y346693D01*
X1420417Y348016D01*
X1419908Y348781D01*
X1420588Y352183D01*
X1424060Y357388D01*
X1432342Y362913D01*
X1435976Y374164D01*
X1434842Y379502D01*
X1435987Y384895D01*
X1434673Y391088D01*
X1436050Y397554D01*
Y408951D01*
X1437426Y410327D01*
X1438908D01*
X1439813Y409422D01*
G01X1803300Y39900D02*
X1805380Y41980D01*
Y44444D01*
X1800342Y49482D01*
X1792552Y52150D01*
X1788228Y51285D01*
X1781858Y47039D01*
X1775050Y45677D01*
X1770065Y46674D01*
X1747480Y61732D01*
X1738485Y64143D01*
X1733172Y63082D01*
X1730070Y61014D01*
X1725139Y60028D01*
X1718015Y61464D01*
X1715496Y61975D01*
X1710874Y65034D01*
X1698199Y67614D01*
X1692611Y66478D01*
X1682537Y68525D01*
X1680162Y70097D01*
X1676219Y70899D01*
X1666405Y74774D01*
X1657103Y76777D01*
X1649935Y81940D01*
X1641367Y84766D01*
X1641276Y84826D01*
X1641104Y84861D01*
X1640502Y84981D01*
X1636888Y85705D01*
X1636886Y85704D01*
X1632492Y84825D01*
X1632283Y84964D01*
X1624564Y86508D01*
X1614991Y89855D01*
X1611800Y92800D01*
X1606236Y95582D01*
X1603285D01*
X1601492Y93789D01*
X1600935Y91627D01*
X1600156Y91138D01*
X1592668Y89337D01*
X1581325D01*
X1545517Y79714D01*
X1530123Y85581D01*
X1510889Y80987D01*
X1508465Y81983D01*
X1499880Y93671D01*
X1493102Y96229D01*
X1490605Y95625D01*
X1479224Y98978D01*
X1466522Y115971D01*
X1461476Y139704D01*
X1463077Y145239D01*
X1460229Y155635D01*
X1462543Y166911D01*
X1454565Y192120D01*
X1457834Y202423D01*
X1451436Y234402D01*
X1448437Y238682D01*
X1447357Y240287D01*
X1446755Y243387D01*
X1445044Y245923D01*
X1443214Y247157D01*
X1441286Y251539D01*
X1441648Y253363D01*
X1440641Y254952D01*
X1439600Y259554D01*
X1437497Y260791D01*
X1430595Y269534D01*
X1431403Y272893D01*
X1430047Y278542D01*
X1434850Y301236D01*
Y315724D01*
X1438385Y332407D01*
X1436247Y343100D01*
X1438038Y352061D01*
X1444812Y356577D01*
X1454611Y370459D01*
X1458493Y371813D01*
X1459432Y373730D01*
X1458606Y377311D01*
Y388364D01*
X1458189Y389942D01*
X1457304Y390590D01*
X1455907Y396178D01*
X1460599Y418733D01*
X1462236Y421764D01*
X1464072Y423600D01*
X1472470D01*
G01X1808363Y40033D02*
X1806530Y41866D01*
Y44921D01*
X1803795Y47656D01*
Y48575D01*
X1802841Y49529D01*
X1801922D01*
X1800967Y50484D01*
X1792631Y53339D01*
X1787779Y52368D01*
X1781409Y48122D01*
X1775050Y46850D01*
X1770514Y47757D01*
X1747961Y62794D01*
X1746657Y63144D01*
X1746198Y63940D01*
X1744894Y64289D01*
X1744097Y63830D01*
X1742793Y64179D01*
X1742334Y64976D01*
X1741030Y65325D01*
X1740234Y64866D01*
X1738524Y65324D01*
X1732723Y64165D01*
X1729621Y62097D01*
X1725140Y61201D01*
X1715944Y63058D01*
X1711323Y66117D01*
X1698199Y68788D01*
X1692611Y67652D01*
X1682985Y69608D01*
X1680611Y71180D01*
X1676547Y72006D01*
X1671642Y73943D01*
Y73944D01*
X1666740Y75879D01*
X1657580Y77851D01*
X1650463Y82977D01*
X1641873Y85811D01*
X1641723Y85909D01*
X1641331Y85989D01*
X1640727Y86109D01*
X1636727Y86911D01*
X1636509Y86802D01*
X1632733Y86046D01*
X1632731Y86048D01*
X1624868Y87620D01*
X1615596Y90862D01*
X1612460Y93756D01*
X1606508Y96732D01*
X1602808D01*
X1600456Y94381D01*
X1599935Y92358D01*
X1599704Y92213D01*
X1592531Y90487D01*
X1581170D01*
X1555431Y83570D01*
X1554635Y84029D01*
X1553331Y83679D01*
X1552872Y82882D01*
X1545578Y80922D01*
X1530201Y86782D01*
X1510983Y82192D01*
X1509201Y82924D01*
X1500605Y94627D01*
X1493176Y97431D01*
X1490634Y96816D01*
X1479917Y99974D01*
X1467595Y116458D01*
X1462661Y139661D01*
X1464272Y145231D01*
X1461411Y155673D01*
X1463730Y166973D01*
X1455772Y192120D01*
X1459020Y202358D01*
X1452517Y234865D01*
X1449386Y239334D01*
X1448442Y240736D01*
X1447840Y243836D01*
X1445873Y246752D01*
X1444133Y247925D01*
X1442485Y251670D01*
X1442866Y253590D01*
X1441720Y255400D01*
X1440613Y260294D01*
X1438266Y261673D01*
X1431845Y269809D01*
X1432586Y272897D01*
X1431226Y278557D01*
X1431227D01*
X1431226Y278558D01*
X1436000Y301115D01*
Y315603D01*
X1439560Y332400D01*
X1437420Y343100D01*
X1439073Y351369D01*
X1445628Y355739D01*
X1455338Y369494D01*
X1459319Y370882D01*
X1460645Y373591D01*
X1459756Y377442D01*
Y388514D01*
X1459198Y390630D01*
X1458320Y391273D01*
X1457087Y396202D01*
X1461691Y418334D01*
X1463169Y421069D01*
X1464549Y422450D01*
X1472470D01*
G01X1469900Y428013D02*
X1467138Y430775D01*
X1463449D01*
X1458648Y425973D01*
X1455904Y421955D01*
X1453769Y411729D01*
X1449642Y406547D01*
X1449033Y403969D01*
X1451672Y391528D01*
X1450817Y387493D01*
Y378464D01*
X1449623Y372847D01*
X1439647Y359342D01*
X1431911Y354183D01*
X1429541Y342324D01*
X1432310Y328483D01*
X1429750Y316405D01*
Y302377D01*
X1422875Y269975D01*
X1424473Y263321D01*
X1429622Y259569D01*
X1433824Y239736D01*
X1449654Y215998D01*
X1452232Y203008D01*
X1448530Y191341D01*
X1456911Y164840D01*
X1454987Y155458D01*
X1457778Y145274D01*
X1456222Y139894D01*
X1461766Y113817D01*
X1478445Y91504D01*
X1489836Y87922D01*
X1491393Y86715D01*
X1493194Y84200D01*
X1495151Y80203D01*
X1500444Y76726D01*
X1530164Y70253D01*
X1554831Y76333D01*
X1564338Y78490D01*
X1565192Y78357D01*
X1575523Y76744D01*
X1598278Y81295D01*
X1601273Y80695D01*
X1604208Y76294D01*
X1606547Y74736D01*
X1635463Y68953D01*
X1642530Y70366D01*
X1663302Y63049D01*
X1676468Y60370D01*
X1676469Y60371D01*
X1676927D01*
X1679620Y60919D01*
X1681854Y60464D01*
X1684399Y58779D01*
X1684565Y58613D01*
X1684806D01*
X1688180Y57926D01*
X1692914Y58889D01*
X1701736Y57094D01*
X1708614Y52540D01*
X1711650Y51923D01*
X1715213Y52641D01*
X1717445Y54130D01*
X1720348Y54710D01*
X1729588Y51178D01*
X1734669Y52195D01*
X1741701Y49703D01*
X1747298Y51042D01*
X1754820Y49537D01*
X1761730Y44931D01*
X1764713Y40456D01*
X1766332Y38028D01*
X1773646Y33154D01*
X1773889Y33202D01*
X1792917Y29396D01*
X1802695Y22877D01*
X1810750Y14822D01*
Y14120D01*
X1808795Y12165D01*
G01X1467290Y428013D02*
Y428996D01*
X1466661Y429625D01*
X1463926D01*
X1459537Y425234D01*
X1456982Y421492D01*
X1454840Y411226D01*
X1453197Y409164D01*
X1453300Y408251D01*
X1452459Y407195D01*
X1451545Y407092D01*
X1450704Y406036D01*
X1450212Y403955D01*
X1452848Y391528D01*
X1451967Y387372D01*
Y378343D01*
X1450697Y372364D01*
X1440453Y358496D01*
X1432946Y353488D01*
X1431498Y346246D01*
X1432008Y345482D01*
X1431743Y344158D01*
X1430979Y343648D01*
X1430714Y342324D01*
X1433485Y328476D01*
X1430900Y316284D01*
Y302256D01*
X1424054Y269991D01*
X1425493Y264002D01*
X1430656Y260239D01*
X1434904Y240194D01*
X1437823Y235817D01*
X1438725Y235636D01*
X1439474Y234513D01*
X1439293Y233612D01*
X1440117Y232377D01*
X1441019Y232196D01*
X1441768Y231073D01*
X1441588Y230172D01*
X1442337Y229049D01*
X1443238Y228869D01*
X1443987Y227746D01*
X1443807Y226844D01*
X1444556Y225721D01*
X1445457Y225541D01*
X1446206Y224418D01*
X1446026Y223516D01*
X1450736Y216454D01*
X1453418Y202942D01*
X1449737Y191340D01*
X1458098Y164902D01*
X1456169Y155497D01*
X1458973Y145266D01*
X1457407Y139851D01*
X1462839Y114304D01*
X1479144Y92490D01*
X1490378Y88958D01*
X1492231Y87522D01*
X1494185Y84792D01*
X1496046Y80993D01*
X1500897Y77805D01*
X1530148Y71434D01*
X1554566Y77453D01*
X1564298Y79661D01*
X1565192Y79521D01*
X1575498Y77912D01*
X1584683Y79749D01*
X1585193Y80514D01*
X1586517Y80779D01*
X1587282Y80269D01*
X1588606Y80534D01*
X1589116Y81299D01*
X1590439Y81563D01*
X1591204Y81053D01*
X1598278Y82468D01*
X1601966Y81730D01*
X1605038Y77124D01*
X1606996Y75819D01*
X1635459Y70125D01*
X1642614Y71556D01*
X1663609Y64161D01*
X1676698Y61498D01*
X1679620Y62093D01*
X1682303Y61547D01*
X1685035Y59740D01*
X1688180Y59100D01*
X1692914Y60063D01*
X1702185Y58177D01*
X1709063Y53623D01*
X1711651Y53097D01*
X1714763Y53724D01*
X1716996Y55214D01*
X1720123Y55838D01*
X1720122D01*
X1720448Y55903D01*
X1729688Y52371D01*
X1734754Y53385D01*
X1741764Y50901D01*
X1747277Y52220D01*
X1755271Y50619D01*
X1762560Y45761D01*
X1765670Y41094D01*
X1767162Y38858D01*
X1773889Y34375D01*
X1773890D01*
X1793366Y30479D01*
X1803428Y23771D01*
X1811900Y15299D01*
Y14060D01*
X1813795Y12165D01*
G01X1812352Y36949D02*
X1814307Y38904D01*
Y42803D01*
X1811966Y48282D01*
X1810112Y49327D01*
X1791828Y55586D01*
X1789073Y55034D01*
X1781207Y49789D01*
X1775300Y48607D01*
X1771256Y49415D01*
Y49416D01*
X1749348Y64022D01*
X1744914Y68188D01*
X1743099Y68960D01*
X1732044Y66748D01*
X1728173Y64167D01*
X1722921Y63116D01*
X1717961Y64121D01*
X1712505Y67732D01*
X1698442Y70591D01*
X1693888Y69664D01*
X1688200Y70821D01*
X1686248Y72112D01*
X1684111Y75340D01*
X1682218Y76592D01*
X1677051Y77644D01*
X1673251Y76870D01*
X1672364Y77050D01*
X1666562Y78230D01*
X1665652Y78045D01*
X1658030Y79597D01*
X1656089Y80882D01*
X1651300Y84400D01*
X1633900Y90200D01*
X1630215D01*
X1626719Y93696D01*
X1621235Y96365D01*
X1613044Y98003D01*
X1608568Y100989D01*
X1607413D01*
X1603440Y99554D01*
X1596420D01*
X1587101Y102666D01*
X1579589D01*
X1573999Y100221D01*
X1569525D01*
X1564019Y98038D01*
X1557635Y92317D01*
X1554228Y91280D01*
X1554198Y91273D01*
X1553902Y91341D01*
X1553898Y91342D01*
X1551002Y92010D01*
X1547135Y94427D01*
X1544785Y94970D01*
X1542068Y94343D01*
X1537930Y95299D01*
X1527235Y89626D01*
X1520796Y91365D01*
X1516539Y97933D01*
X1512549Y100180D01*
X1507934Y101197D01*
X1502432Y104952D01*
X1499875Y105530D01*
X1496141Y104754D01*
X1490445Y100543D01*
X1488639Y100138D01*
X1481233Y102566D01*
X1478462Y106562D01*
X1475531Y116197D01*
X1477222Y124149D01*
X1474661Y136399D01*
X1467403Y145855D01*
X1464145Y157748D01*
X1465940Y166507D01*
X1462429Y184065D01*
X1463403Y188943D01*
X1453847Y235781D01*
X1449557Y242142D01*
X1448823Y245922D01*
X1447408Y248020D01*
X1444859Y249740D01*
Y249819D01*
X1443954Y251879D01*
X1444369Y253973D01*
X1442917Y256265D01*
X1441702Y261622D01*
X1439269Y262659D01*
X1434334Y268909D01*
X1436836Y278365D01*
X1436835D01*
X1434239Y285978D01*
X1437399Y300883D01*
X1437400D01*
Y314659D01*
X1441125Y333294D01*
X1440152Y338159D01*
X1442988Y352348D01*
X1447354Y355258D01*
X1451096Y360686D01*
X1460397Y369988D01*
X1460398D01*
X1462135Y373536D01*
X1461586Y375913D01*
Y386952D01*
X1460785Y389981D01*
Y395004D01*
X1459935Y399003D01*
X1463077Y414111D01*
X1466291Y417321D01*
X1476073D01*
G01X1514425Y134180D02*
X1512970Y135635D01*
X1504375D01*
X1491344Y148665D01*
X1489973Y153224D01*
X1489537Y153946D01*
X1487105Y155568D01*
X1485020Y157652D01*
X1476714Y163193D01*
G02X1476125Y166140I1179J1768D01*
G01X1477661Y168443D01*
G03X1477391Y169795I-811J541D01*
G01X1477388Y169797D01*
G03X1476036Y169526I-541J-811D01*
G01X1474500Y167224D01*
G02X1471553Y166635I-1768J1179D01*
G01X1469147Y168239D01*
X1467902Y170112D01*
X1465227Y183492D01*
X1465880Y186616D01*
X1469139Y193551D01*
X1468130Y198354D01*
G02X1468087Y198901I2081J439D01*
G02X1472292Y199230I2124J-109D01*
G01X1474183Y190237D01*
G03X1475321Y189481I954J201D01*
G01X1475340Y189485D01*
G03X1476093Y190640I-201J954D01*
G01X1473562Y202669D01*
G03X1472990Y203791I-2357J-495D01*
G01X1472969Y203814D01*
G03X1472079Y204419I-1765J-1639D01*
G01X1471910Y204484D01*
X1468873Y206951D01*
X1467555Y212373D01*
X1468721Y218199D01*
X1468720D01*
X1468627Y218667D01*
X1466277Y222218D01*
G02X1466876Y225163I1772J1173D01*
G01X1467931Y225861D01*
G03X1468206Y227213I-538J813D01*
G01X1468205Y227214D01*
G03X1468168Y227266I-812J-539D01*
G03X1466854Y227489I-776J-590D01*
G01X1465799Y226790D01*
G02X1462854Y227389I-1173J1772D01*
G01X1455553Y238415D01*
X1454038Y245863D01*
X1449072Y253362D01*
X1449073Y253363D01*
X1449089D01*
X1449118Y253392D01*
X1449099Y253407D01*
X1446358Y255721D01*
X1445361Y257121D01*
X1444904Y259144D01*
X1444890Y259223D01*
X1444240Y263427D01*
X1440569Y265051D01*
X1437111Y269432D01*
X1439499Y278458D01*
X1439498D01*
X1436862Y286185D01*
X1439550Y298891D01*
Y313140D01*
X1440673Y314263D01*
X1441462D01*
X1442600Y315401D01*
Y319027D01*
X1445883Y322310D01*
X1451236D01*
X1463340Y334418D01*
Y343060D01*
X1455850Y350550D01*
Y357499D01*
X1460514Y364284D01*
X1463965Y365633D01*
X1465840Y367508D01*
X1466547Y370842D01*
X1469857Y373108D01*
X1470594Y375458D01*
X1468604Y384050D01*
X1468939Y385900D01*
X1469049Y386223D01*
X1469048D01*
X1469509Y387114D01*
X1469510D01*
X1469692Y387411D01*
Y387410D01*
X1473200Y389737D01*
X1474782Y391747D01*
X1475769Y396828D01*
X1474366Y400269D01*
X1473930Y402447D01*
X1475836Y411978D01*
X1477242Y413384D01*
X1480313D01*
G01X1817352Y36909D02*
X1815457Y38804D01*
Y43162D01*
X1815365Y43254D01*
X1812871Y49093D01*
X1810572Y50387D01*
X1791906Y56775D01*
X1788626Y56117D01*
X1780758Y50872D01*
X1775300Y49780D01*
X1771705Y50499D01*
X1750070Y64922D01*
X1745554Y69167D01*
X1743222Y70158D01*
X1731595Y67831D01*
X1731405Y67705D01*
X1731406D01*
X1727724Y65250D01*
X1722922Y64290D01*
X1718409Y65204D01*
X1712954Y68815D01*
X1698442Y71765D01*
X1693888Y70838D01*
X1688649Y71904D01*
X1687078Y72942D01*
X1684941Y76170D01*
X1682667Y77675D01*
X1677051Y78818D01*
X1673251Y78044D01*
X1671517Y78397D01*
X1667807Y79152D01*
X1666566Y79404D01*
X1665652Y79219D01*
X1658479Y80680D01*
X1656771Y81810D01*
X1656770Y81809D01*
X1651835Y85434D01*
X1650554Y85861D01*
X1650143Y86683D01*
X1648862Y87110D01*
X1648040Y86699D01*
X1634087Y91350D01*
X1630692D01*
X1627396Y94646D01*
X1621605Y97464D01*
X1613493Y99086D01*
X1608917Y102139D01*
X1607211D01*
X1603238Y100704D01*
X1596607D01*
X1587290Y103816D01*
X1579348D01*
X1573758Y101371D01*
X1569305D01*
X1563404Y99032D01*
X1562399Y98131D01*
X1561481Y98181D01*
X1560475Y97281D01*
X1560425Y96363D01*
X1557056Y93344D01*
X1554161Y92462D01*
X1554156Y92463D01*
X1551448Y93088D01*
X1547582Y95505D01*
X1544785Y96151D01*
X1542068Y95524D01*
X1537770Y96517D01*
X1536577Y95884D01*
X1535699Y96154D01*
X1534506Y95521D01*
X1534236Y94642D01*
X1527097Y90855D01*
X1521522Y92361D01*
X1517351Y98797D01*
X1512964Y101267D01*
X1508399Y102273D01*
X1502900Y106026D01*
X1499885Y106707D01*
X1495660Y105829D01*
X1489956Y101613D01*
X1488696Y101330D01*
X1481958Y103539D01*
X1479510Y107069D01*
X1478751Y109566D01*
X1479183Y110377D01*
X1478790Y111669D01*
X1477979Y112101D01*
X1476718Y116248D01*
X1478398Y124148D01*
X1475734Y136892D01*
X1468453Y146376D01*
X1465327Y157787D01*
X1467114Y166504D01*
X1463602Y184065D01*
X1464577Y188949D01*
X1454930Y236233D01*
X1450642Y242591D01*
X1449908Y246371D01*
X1448237Y248849D01*
X1445828Y250474D01*
X1445153Y252011D01*
X1445587Y254200D01*
X1443995Y256713D01*
X1442694Y262450D01*
X1439990Y263602D01*
X1435594Y269171D01*
X1438037Y278407D01*
X1435430Y286049D01*
X1438549Y300761D01*
X1438550D01*
Y314545D01*
X1442298Y333294D01*
X1441325Y338159D01*
X1444023Y351655D01*
X1448176Y354423D01*
X1451984Y359946D01*
X1461347Y369310D01*
X1463347Y373397D01*
X1462736Y376045D01*
Y387102D01*
X1461935Y390131D01*
Y395125D01*
X1461111Y399008D01*
X1464133Y413540D01*
X1466767Y416171D01*
X1476073D01*
G01X1514425Y137980D02*
X1513230Y136785D01*
X1509103D01*
X1508453Y137435D01*
X1507103D01*
X1506453Y136785D01*
X1504852D01*
X1503463Y138174D01*
Y138175D01*
X1503462Y139095D01*
X1502508Y140049D01*
X1501589D01*
X1500634Y141004D01*
Y141923D01*
X1499680Y142877D01*
X1498760D01*
X1497805Y143832D01*
Y144751D01*
X1496851Y145705D01*
X1495932D01*
X1492363Y149274D01*
X1491033Y153695D01*
X1490388Y154761D01*
X1487838Y156462D01*
X1485754Y158546D01*
X1485233Y158894D01*
X1485053Y159795D01*
X1483930Y160544D01*
X1483029Y160364D01*
X1477352Y164150D01*
G02X1477082Y165502I541J811D01*
G01X1478618Y167805D01*
G03X1478029Y170752I-1768J1179D01*
G01X1478026Y170754D01*
G03X1475079Y170165I-1179J-1768D01*
G01X1473543Y167862D01*
G02X1472191Y167592I-811J541D01*
G01X1469977Y169068D01*
X1468986Y170560D01*
X1467970Y175641D01*
X1468480Y176406D01*
X1468215Y177730D01*
X1467450Y178240D01*
X1467185Y179564D01*
X1467695Y180329D01*
X1467431Y181652D01*
X1466666Y182162D01*
X1466401Y183486D01*
X1466979Y186248D01*
X1470344Y193411D01*
X1469256Y198591D01*
G02X1469236Y198842I954J202D01*
G02X1471166Y198993I975J-50D01*
G01X1473057Y190000D01*
G03X1475573Y188358I2079J438D01*
G01X1475577Y188359D01*
G03X1477219Y190876I-438J2080D01*
G01X1474688Y202906D01*
G03X1473843Y204563I-3483J-732D01*
G03X1472496Y205491I-2639J-2389D01*
G01X1469900Y207600D01*
X1468733Y212397D01*
X1469894Y218199D01*
X1469711Y219114D01*
X1467236Y222853D01*
G02X1467511Y224204I813J538D01*
G01X1468566Y224901D01*
G03X1469165Y227849I-1173J1773D01*
G03X1469086Y227961I-1776J-1169D01*
G01X1469085Y227962D01*
G03X1466219Y228448I-1692J-1286D01*
G01X1465164Y227749D01*
G02X1463813Y228024I-538J813D01*
G01X1456636Y238864D01*
X1455121Y246312D01*
X1449841Y254287D01*
X1447211Y256506D01*
X1446433Y257600D01*
X1446027Y259398D01*
X1445281Y264225D01*
X1441296Y265988D01*
X1438371Y269694D01*
X1440700Y278500D01*
X1438053Y286257D01*
X1440700Y298770D01*
Y312663D01*
X1441150Y313113D01*
X1441939D01*
X1443750Y314924D01*
Y318550D01*
X1446360Y321160D01*
X1451713D01*
X1464490Y333941D01*
Y343537D01*
X1457000Y351027D01*
Y357141D01*
X1461262Y363341D01*
X1464608Y364649D01*
X1466895Y366935D01*
X1467577Y370153D01*
X1470836Y372383D01*
X1471786Y375413D01*
X1469778Y384078D01*
X1470071Y385695D01*
X1470532Y386586D01*
X1473986Y388877D01*
X1475858Y391254D01*
X1476964Y396946D01*
X1476834Y397265D01*
X1476833D01*
X1475473Y400602D01*
X1475102Y402450D01*
X1476896Y411411D01*
X1477719Y412234D01*
X1480313D01*
G01X1680000Y550544D02*
X1681779Y548765D01*
G02X1681925Y548412I-354J-353D01*
G01Y543857D01*
G02X1681779Y543504I-500J0D01*
G01X1677621Y539346D01*
G02X1677268Y539200I-353J354D01*
G01X1661056D01*
G02X1660556Y539700I0J500D01*
G01Y540360D01*
G03X1656306I-2125J0D01*
G01Y538681D01*
G02X1654356I-975J0D01*
G01Y540398D01*
G03X1650106I-2125J0D01*
G01Y538819D01*
G02X1648156I-975J0D01*
G01Y540336D01*
G03X1643906I-2125J0D01*
G01Y539456D01*
G02X1641956I-975J0D01*
G01Y540451D01*
G03X1637706I-2125J0D01*
G01Y539388D01*
G02X1635756I-975J0D01*
G01Y540595D01*
G03X1631506I-2125J0D01*
G01Y540175D01*
G02X1630531Y539200I-975J0D01*
G01X1620552D01*
G03X1618819Y538482I0J-2451D01*
G01X1618250Y537912D01*
G02X1617375Y537550I-874J875D01*
G01X1599120D01*
G03X1594003Y535430I1J-7238D01*
G01X1583348Y524775D01*
G02X1583030Y524642I-319J317D01*
G01X1540353D01*
G03X1539221Y524173I0J-1601D01*
G01X1521105Y506056D01*
G02X1520752Y505910I-353J354D01*
G01X1511039D01*
G03X1509252Y504123I0J-1787D01*
G01Y503894D01*
G02X1509090Y503502I-555J0D01*
G01X1508626Y503038D01*
G01X1506985Y510645D02*
G03X1507538Y511980I-1335J1335D01*
G01Y512034D01*
G02X1509438Y513934I1900J0D01*
G01X1524285D01*
G03X1524638Y514080I0J500D01*
G01X1537860Y527302D01*
G02X1538993Y527770I1132J-1134D01*
G01X1581298D01*
G03X1582398Y528227I1J1550D01*
G01X1592680Y538509D01*
G02X1598041Y540730I5362J-5362D01*
G01X1615547D01*
G03X1617218Y541422I0J2364D01*
G01X1619929Y544133D01*
G02X1623500Y545611I3570J-3572D01*
G01X1632008D01*
G03X1632983Y546586I0J975D01*
G01Y546626D01*
G02X1637233I2125J0D01*
G01Y546586D01*
G03X1639183I975J0D01*
G01Y546625D01*
G02X1643433I2125J0D01*
G01Y546586D01*
G03X1645383I975J0D01*
G01Y546628D01*
G02X1649633I2125J0D01*
G01Y546586D01*
G03X1651583I975J0D01*
G02X1655833I2125J0D01*
G03X1656808Y545611I975J0D01*
G01X1659065D01*
G03X1660089Y546035I0J1449D01*
G01X1660427Y546373D01*
G03X1660850Y547393I-1020J1021D01*
G01Y550500D01*
G03X1660350Y551000I-500J0D01*
G01X1658754D01*
G01X1669600Y550544D02*
X1670219D01*
G03X1670907Y551232I0J688D01*
G01Y552351D01*
G03X1670165Y553093I-742J0D01*
G01X1656437D01*
G03X1656084Y552947I0J-500D01*
G01X1654370Y551233D01*
G02X1653204Y550750I-1166J1167D01*
G01X1648780D01*
G02X1646785Y552745I0J1995D01*
G01Y553765D01*
G03X1644835I-975J0D01*
G01Y552875D01*
G02X1642710Y550750I-2125J0D01*
G01X1632999D01*
G03X1632414Y550507I1J-828D01*
G01X1630354Y548448D01*
G02X1628336Y547612I-2018J2018D01*
G01X1621006D01*
G03X1619674Y547060I1J-1885D01*
G01X1616753Y544139D01*
G02X1614001Y543000I-2751J2752D01*
G01X1594588D01*
G03X1594269Y542868I0J-451D01*
G01X1594268D01*
X1593035Y541635D01*
G02X1590029I-1503J1502D01*
G01X1589045Y542619D01*
G03X1587666Y541240I-689J-690D01*
G01X1588650Y540256D01*
G02Y537250I-1502J-1503D01*
G01X1581622Y530222D01*
G02X1580457Y529740I-1166J1168D01*
G01X1537935D01*
G03X1537228Y529447I0J-1000D01*
G01X1524213Y516434D01*
Y516433D01*
G02X1523047Y515950I-1166J1167D01*
G01X1521132D01*
G02X1519218Y517864I0J1914D01*
G01Y519445D01*
G03X1517268I-975J0D01*
G01Y518075D01*
G02X1515143Y515950I-2125J0D01*
G01X1511167D01*
G02X1508375Y517105I-3J3944D01*
G01X1507405Y518075D01*
Y518155D01*
G01X1498277Y508239D02*
X1498813Y508775D01*
G03X1498945Y509093I-318J318D01*
G01Y509562D01*
G02X1500597Y511214I1652J0D01*
G01X1502683D01*
G03X1503180Y511420I0J703D01*
G01X1503789Y512029D01*
G03X1504107Y512797I-768J768D01*
G01Y513352D01*
G03X1503975Y513671I-451J0D01*
G01X1503157Y514489D01*
G02X1502685Y515630I1140J1140D01*
G01Y518860D01*
G02X1503454Y520717I2626J0D01*
G01X1507027Y524290D01*
G02X1508160Y524758I1132J-1134D01*
G01X1517314D01*
G03X1517632Y524891I-1J450D01*
G01X1526788Y534047D01*
G02X1529589Y535206I2800J-2802D01*
G01X1572780D01*
G03X1574491Y535916I-1J2420D01*
G01X1584737Y546162D01*
G02X1587731Y547402I2994J-2995D01*
G01X1609718D01*
G03X1610872Y547880I0J1632D01*
G01X1615289Y552297D01*
G02X1616923Y552973I1633J-1633D01*
G01X1626374D01*
G03X1627512Y554111I0J1138D01*
G01Y556347D01*
G02X1628425Y558554I3121J1D01*
G01X1630040Y560169D01*
G03X1630418Y561078I-910J911D01*
G01Y561213D01*
G02X1635304I2443J0D01*
G01Y560288D01*
G03X1636433Y559159I1129J0D01*
G01X1638452D01*
G03X1639485Y560192I0J1033D01*
G01Y561499D01*
G02X1643835I2175J0D01*
G01Y560251D01*
G03X1644927Y559159I1092J0D01*
G01X1648789D01*
G03X1650400Y560770I0J1611D01*
G01Y571174D01*
G03X1648618Y572956I-1782J0D01*
G01X1637075D01*
G02Y577306I0J2175D01*
G01X1648937D01*
G03X1649500Y577869I0J563D01*
G01Y579265D01*
G02X1651229Y581171I1915J0D01*
G01X1651358Y581184D01*
G03X1651632Y581313I-43J448D01*
G01X1652669Y582350D01*
G01X1625094Y559200D02*
Y558282D01*
G02X1624644Y557832I-450J0D01*
G01X1623541D01*
G02X1621492Y559881I0J2049D01*
G01Y565469D01*
G03X1617142I-2175J0D01*
G01Y564713D01*
G02X1615834Y563405I-1308J0D01*
G03X1613659Y561230I0J-2175D01*
G01Y560526D01*
G03X1615834Y558351I2175J0D01*
G01X1616629D01*
G02X1617654Y557326I0J-1025D01*
G01Y557148D01*
G02X1616806Y556301I-847J0D01*
G01X1616804Y556302D01*
X1614627Y556297D01*
G03X1613499Y555828I4J-1601D01*
G01X1612675Y555004D01*
G02X1611790Y554636I-889J890D01*
G01X1611668D01*
G03X1609620Y552588I0J-2048D01*
G01Y551604D01*
G02X1608564Y550548I-1056J0D01*
G01X1605870D01*
G02X1604895Y551523I0J975D01*
G01Y554675D01*
G03X1600645I-2125J0D01*
G01Y551523D01*
G02X1598695I-975J0D01*
G01Y554675D01*
G03X1594445I-2125J0D01*
G01Y551523D01*
G02X1593470Y550548I-975J0D01*
G01X1592737D01*
G02X1591996Y550856I0J1044D01*
G01X1591626Y551226D01*
X1591625D01*
G02X1591492Y551546I318J320D01*
G01Y565878D01*
G03X1590914Y567270I-1969J-1D01*
G01X1590836Y567348D01*
X1590837D01*
G03X1589445Y567925I-1393J-1392D01*
G01X1588971D01*
G03X1587516Y567322I0J-2057D01*
G01X1587438Y567244D01*
G03X1586835Y565789I1454J-1455D01*
G01Y554994D01*
G02X1586144Y553329I-2355J1D01*
G01X1575203Y542388D01*
G02X1573663Y541750I-1540J1540D01*
G01X1571141D01*
G03X1568966Y539575I0J-2175D01*
G01Y539453D01*
G02X1566916I-1025J0D01*
G01Y539575D01*
G03X1562566I-2175J0D01*
G01Y539453D01*
G02X1560516I-1025J0D01*
G01Y539575D01*
G03X1556166I-2175J0D01*
G01Y539453D01*
G02X1554116I-1025J0D01*
G01Y539575D01*
G03X1549766I-2175J0D01*
G01Y539453D01*
G02X1547716I-1025J0D01*
G03X1543366I-2175J0D01*
G02X1541316I-1025J0D01*
G01Y539575D01*
G03X1536966I-2175J0D01*
G01Y539374D01*
G02X1535981Y538389I-985J0D01*
G01X1535980D01*
G02X1534916Y539453I0J1064D01*
G01Y539575D01*
G03X1532741Y541750I-2175J0D01*
G01X1530996D01*
G03X1529385Y541083I0J-2279D01*
G01X1517359Y529057D01*
G02X1516193Y528574I-1165J1163D01*
G01X1503410D01*
G03X1501491Y527780I-1J-2713D01*
G01X1499551Y525841D01*
G03X1498960Y524411I1431J-1429D01*
G01Y517213D01*
G02X1498828Y516895I-450J0D01*
G01X1498055Y516122D01*
G01X1490100Y520000D02*
X1490668Y520568D01*
G03X1490800Y520886I-318J318D01*
G01Y529936D01*
G02X1491906Y532606I3775J0D01*
G01X1499358Y540058D01*
G02X1500863Y540680I1504J-1506D01*
G01X1515784D01*
G03X1517198Y541267I-1J2000D01*
G01X1523137Y547206D01*
G02X1525364Y548129I2228J-2228D01*
G01X1543006D01*
G03X1544106Y549229I0J1100D01*
G01Y550765D01*
G02X1548456I2175J0D01*
G01Y549154D01*
G03X1550506I1025J0D01*
G01Y550765D01*
G02X1554856I2175J0D01*
G01Y549154D01*
G03X1556906I1025J0D01*
G01Y550765D01*
G02X1561256I2175J0D01*
G01Y549154D01*
G03X1563306I1025J0D01*
G01Y550765D01*
G02X1567656I2175J0D01*
G01Y549192D01*
G03X1568719Y548129I1063J0D01*
G01X1570065D01*
G03X1570921Y548483I1J1210D01*
G01X1570922Y548485D01*
G03X1571696Y550349I-1863J1866D01*
G01Y553964D01*
G02X1572463Y555812I2614J-2D01*
G01X1573543Y556893D01*
G03X1574210Y558500I-1606J1608D01*
G01Y572408D01*
G02X1575095Y574544I3023J-1D01*
G01X1576188Y575637D01*
G02X1578243Y576487I2054J-2056D01*
G01X1581271D01*
G02X1583427Y575595I1J-3048D01*
G01X1584321Y574701D01*
G03X1585425Y574243I1105J1104D01*
G01X1593199D01*
G02X1595988Y573089I1J-3944D01*
G01X1597650Y571427D01*
G03X1598861Y570900I1211J1128D01*
G01X1600214D01*
G03X1600532Y571032I0J450D01*
G01X1601825Y572325D01*
G01X1485693Y508000D02*
X1485888Y508195D01*
G03X1486020Y508513I-318J318D01*
G01Y511017D01*
G02X1486572Y512349I1883J0D01*
G01X1487409Y513186D01*
G02X1490161I1376J-1376D01*
G01X1493886Y509460D01*
G03X1495170Y509991I532J531D01*
G03X1494455Y511719I-2445J0D01*
G01X1492702Y513474D01*
G02X1492703Y516630I1579J1577D01*
G01X1495236Y519163D01*
G03X1495849Y520643I-1480J1480D01*
G01X1495850Y520642D01*
Y525293D01*
G02X1496898Y527825I3582J0D01*
G01X1499224Y530151D01*
G03X1500438Y533083I-2930J2931D01*
G01X1500439Y533082D01*
Y535103D01*
G02X1501099Y536695I2252J-1D01*
G01X1501311Y536907D01*
G02X1502903Y537567I1593J-1592D01*
G01X1503680D01*
G02X1505245Y536919I0J-2214D01*
G01X1505340Y536824D01*
G02X1505972Y535302I-1517J-1522D01*
G01Y534867D01*
G03X1506295Y534088I1101J0D01*
G01X1506383Y534000D01*
G03X1507162Y533677I779J778D01*
G01X1508162D01*
G03X1509262Y534777I0J1100D01*
G01Y535602D01*
G02X1511188Y537528I1926J0D01*
G01X1511437D01*
G02X1513612Y535353I0J-2175D01*
G01Y534246D01*
G03X1514181Y533677I569J0D01*
G01X1514886D01*
G03X1515204Y533810I-1J449D01*
G01X1525780Y544386D01*
G02X1527166Y544960I1386J-1386D01*
G01X1572304D01*
G03X1573212Y545336I0J1284D01*
G01X1576992Y549116D01*
G03Y550566I-725J725D01*
G01X1575859Y551699D01*
G02Y554775I1538J1538D01*
G01X1575862Y554778D01*
G02X1578937I1538J-1538D01*
G01X1580018Y553697D01*
G03X1581574I778J778D01*
G01X1582588Y554711D01*
G03X1583715Y557432I-2721J2721D01*
G01Y567841D01*
G02X1584547Y569850I2842J0D01*
G01X1584892Y570195D01*
G02X1586975Y571058I2083J-2082D01*
G01X1592163D01*
G02X1594592Y568629I0J-2429D01*
G01Y561361D01*
X1594593Y561362D01*
G03X1594989Y560402I1357J-2D01*
G01X1594990D01*
X1594991Y560401D01*
G03X1595922Y560014I932J930D01*
G01X1605717D01*
G03X1606035Y560146I0J450D01*
G01X1607533Y561644D01*
G01X1479375Y507975D02*
X1479768Y508368D01*
G03X1479900Y508686I-318J318D01*
G01Y510700D01*
G03X1479688Y511212I-724J0D01*
G01X1479500Y511400D01*
G02X1478400Y514056I2656J2656D01*
G01Y516993D01*
G02X1478900Y518200I1707J0D01*
G01X1481340Y520639D01*
G02X1483900Y521700I2561J-2560D01*
G01X1485167D01*
G03X1487100Y523633I0J1933D01*
G01Y530365D01*
G02X1488402Y533508I4445J0D01*
G01X1499744Y544850D01*
G03X1500249Y546069I-1220J1220D01*
G01Y549182D01*
G02X1500727Y550334I1630J-1D01*
G01X1500843Y550450D01*
G02X1502719Y551229I1879J-1876D01*
G02X1502721I1J-2656D01*
G01X1504089D01*
G02X1506264Y549054I0J-2175D01*
G01Y544808D01*
G03X1508314I1025J0D01*
G01Y549054D01*
G02X1512664I2175J0D01*
G01Y544808D01*
G03X1514714I1025J0D01*
G01Y549054D01*
G02X1516889Y551229I2175J0D01*
G01X1537284D01*
G03X1539905Y552315I0J3706D01*
G01X1542741Y555151D01*
G02X1545073Y556117I2332J-2332D01*
G01X1566956D01*
G03X1569185Y557040I0J3153D01*
G01X1570168Y558023D01*
G03X1570853Y559679I-1657J1655D01*
G01X1570854Y559678D01*
Y573748D01*
G02X1572026Y576577I4001J0D01*
G01X1574333Y578884D01*
G02X1576572Y579812I2240J-2239D01*
G01X1583037D01*
G02X1584629Y579152I-1J-2252D01*
G01X1586098Y577683D01*
G03X1586877Y577360I779J778D01*
G01X1592965D01*
G03X1593744Y577683I0J1101D01*
G01X1595680Y579619D01*
G02X1599198Y581075I3517J-3519D01*
G01X1604383D01*
G03X1604701Y581207I0J450D01*
G01X1605994Y582500D01*
G01X1685000Y550544D02*
X1683221Y548765D01*
G03X1683075Y548412I354J-353D01*
G01Y543856D01*
G02X1682593Y542691I-1650J1D01*
G01X1678434Y538532D01*
G02X1677269Y538050I-1166J1168D01*
G01X1661056D01*
G02X1659406Y539700I0J1650D01*
G01Y540360D01*
G03X1657456I-975J0D01*
G01Y538681D01*
G02X1653206I-2125J0D01*
G01Y540398D01*
G03X1651256I-975J0D01*
G01Y538819D01*
G02X1647006I-2125J0D01*
G01Y540336D01*
G03X1645056I-975J0D01*
G01Y539456D01*
G02X1640806I-2125J0D01*
G01Y540451D01*
G03X1638856I-975J0D01*
G01Y539388D01*
G02X1634606I-2125J0D01*
G01Y540595D01*
G03X1632656I-975J0D01*
G01Y540175D01*
G02X1630531Y538050I-2125J0D01*
G01X1620553D01*
G03X1619633Y537668I1J-1301D01*
G01X1619064Y537099D01*
G02X1617375Y536400I-1688J1688D01*
G01X1599121D01*
G03X1594817Y534616I1J-6087D01*
G01X1584163Y523962D01*
G02X1583032Y523492I-1133J1131D01*
G01X1540353D01*
G03X1540035Y523359I1J-450D01*
G01X1521918Y505242D01*
G02X1520753Y504760I-1166J1168D01*
G01X1511039D01*
G03X1510402Y504123I0J-637D01*
G01Y503942D01*
G03X1510530Y503634I436J1D01*
G01X1511126Y503038D01*
G01X1509585Y510645D02*
X1508945Y511284D01*
G02X1508688Y511906I622J621D01*
G01Y512034D01*
G02X1509438Y512784I750J0D01*
G01X1511758D01*
G02X1512098Y512643I0J-480D01*
G01X1512160Y512581D01*
G03X1512500Y512440I340J339D01*
G01X1513452D01*
G03X1513792Y512581I0J480D01*
G01X1513854Y512643D01*
G02X1514194Y512784I340J-339D01*
G01X1524286D01*
G03X1525451Y513266I-1J1650D01*
G01X1538673Y526488D01*
G02X1538993Y526620I319J-320D01*
G01X1581298D01*
G03X1583214Y527415I3J2700D01*
G01X1593494Y537695D01*
G02X1598042Y539580I4549J-4547D01*
G01X1615547D01*
G03X1618032Y540608I1J3514D01*
G01X1620743Y543319D01*
G02X1623500Y544461I2757J-2757D01*
G01X1632008D01*
G03X1634133Y546586I0J2125D01*
G01Y546626D01*
G02X1636083I975J0D01*
G01Y546586D01*
G03X1640333I2125J0D01*
G01Y546625D01*
G02X1642283I975J0D01*
G01Y546586D01*
G03X1646533I2125J0D01*
G01Y546628D01*
G02X1648483I975J0D01*
G01Y546586D01*
G03X1652733I2125J0D01*
G02X1654683I975J0D01*
G03X1656808Y544461I2125J0D01*
G01X1659065D01*
G03X1660903Y545221I1J2599D01*
G01X1661241Y545559D01*
G03X1662000Y547392I-1834J1833D01*
G01Y550500D01*
G02X1662500Y551000I500J0D01*
G01X1663754D01*
G01X1674600Y550544D02*
X1672507D01*
G02X1672057Y550994I0J450D01*
G01Y552351D01*
G03X1670165Y554243I-1892J0D01*
G01X1656436D01*
G03X1655270Y553760I0J-1650D01*
G01X1653556Y552046D01*
G02X1653203Y551900I-353J354D01*
G01X1648780D01*
G02X1647935Y552745I0J845D01*
G01Y553765D01*
G03X1643685I-2125J0D01*
G01Y552875D01*
G02X1642710Y551900I-975J0D01*
G01X1632998D01*
G03X1631600Y551321I0J-1978D01*
G01X1629540Y549262D01*
G02X1628335Y548762I-1206J1203D01*
G01X1621005D01*
G03X1618860Y547874I0J-3035D01*
G01X1615939Y544953D01*
G02X1614002Y544150I-1938J1937D01*
G01X1594588D01*
G03X1593455Y543682I-1J-1602D01*
G01X1593454D01*
X1592221Y542449D01*
G02X1590843I-689J688D01*
G01X1589858Y543433D01*
G03X1586852Y540426I-1503J-1504D01*
G01X1587836Y539442D01*
G02Y538064I-688J-689D01*
G01X1580809Y531036D01*
G02X1580456Y530890I-353J354D01*
G01X1537933D01*
G03X1536412Y530260I0J-2150D01*
G01X1523399Y517247D01*
G02X1523046Y517100I-354J352D01*
G01X1521132D01*
G02X1520368Y517864I0J764D01*
G01Y519445D01*
G03X1516118I-2125J0D01*
G01Y518075D01*
G02X1515143Y517100I-975J0D01*
G01X1511167D01*
G02X1510848Y517232I0J451D01*
G01X1510005Y518075D01*
Y518155D01*
G01X1500877Y508239D02*
X1500227Y508889D01*
G02X1500095Y509207I318J318D01*
G01Y509562D01*
G02X1500597Y510064I502J0D01*
G01X1502683D01*
G03X1503994Y510606I1J1853D01*
G01X1504603Y511215D01*
G03X1505257Y512797I-1583J1581D01*
G01Y513352D01*
G03X1504789Y514485I-1602J1D01*
G01X1503971Y515303D01*
G02X1503835Y515629I325J327D01*
G01Y518859D01*
G02X1504268Y519903I1476J0D01*
G01X1507841Y523476D01*
G02X1508160Y523608I319J-319D01*
G01X1517314D01*
G03X1518446Y524077I0J1601D01*
G01X1520426Y526057D01*
G02X1521115Y526286I587J-615D01*
G03X1521804Y526516I101J844D01*
G01X1522759Y527471D01*
G03X1522989Y528160I-614J588D01*
G02X1523219Y528850I844J102D01*
G01X1524174Y529805D01*
G02X1524863Y530034I587J-615D01*
G03X1525552Y530264I101J844D01*
G01X1526507Y531219D01*
G03X1526737Y531908I-614J588D01*
G02X1526967Y532598I844J102D01*
G01X1527602Y533233D01*
G02X1529589Y534056I1987J-1987D01*
G01X1572780D01*
G03X1575305Y535102I0J3571D01*
G01X1585551Y545348D01*
G02X1587731Y546252I2181J-2180D01*
G01X1609717D01*
G03X1611686Y547066I2J2783D01*
G01X1616103Y551483D01*
G02X1616923Y551823I820J-819D01*
G01X1626374D01*
G03X1628662Y554111I0J2288D01*
G01Y556347D01*
G02X1629239Y557740I1970J0D01*
G01X1630854Y559355D01*
G03X1631568Y561079I-1724J1724D01*
G01Y561213D01*
G02X1634154I1293J0D01*
G01Y560288D01*
G03X1636433Y558009I2279J0D01*
G01X1638452D01*
G03X1640635Y560192I0J2183D01*
G01Y561499D01*
G02X1642685I1025J0D01*
G01Y560251D01*
G03X1644927Y558009I2242J0D01*
G01X1648789D01*
G03X1651550Y560770I0J2761D01*
G01Y571174D01*
G03X1648618Y574106I-2932J0D01*
G01X1637075D01*
G02Y576156I0J1025D01*
G01X1648937D01*
G03X1650650Y577869I0J1713D01*
G01Y579265D01*
G02X1651341Y580026I765J0D01*
G02X1651415Y580030I78J-761D01*
G01X1652219D01*
G02X1652669Y579580I0J-450D01*
G01Y578350D01*
G01X1500655Y516122D02*
X1500242Y516535D01*
G02X1500110Y516853I318J318D01*
G01Y524411D01*
G02X1500365Y525027I872J0D01*
G01X1501294Y525956D01*
X1501295D01*
X1502305Y526966D01*
G02X1503410Y527424I1105J-1104D01*
G01X1504760D01*
G02X1505410Y527099I-19J-850D01*
G03X1506060Y526774I669J525D01*
G01X1507410D01*
G03X1508060Y527099I-19J850D01*
G02X1508710Y527424I669J-525D01*
G01X1510893D01*
G02X1511543Y527099I-19J-850D01*
G03X1512193Y526774I669J525D01*
G01X1513543D01*
G03X1514193Y527099I-19J850D01*
G02X1514843Y527424I669J-525D01*
G01X1516193D01*
G03X1518173Y528243I3J2796D01*
G01X1530199Y540269D01*
G02X1530997Y540600I799J-798D01*
G01X1532741D01*
G02X1533766Y539575I0J-1025D01*
G01Y539453D01*
G03X1535980Y537239I2214J0D01*
G01X1535982D01*
G03X1538116Y539373I0J2134D01*
G01Y539575D01*
G02X1540166I1025J0D01*
G01Y539453D01*
G03X1544516I2175J0D01*
G02X1546566I1025J0D01*
G03X1550916I2175J0D01*
G01Y539575D01*
G02X1552966I1025J0D01*
G01Y539453D01*
G03X1557316I2175J0D01*
G01Y539575D01*
G02X1559366I1025J0D01*
G01Y539453D01*
G03X1563716I2175J0D01*
G01Y539575D01*
G02X1565766I1025J0D01*
G01Y539453D01*
G03X1570116I2175J0D01*
G01Y539575D01*
G02X1571141Y540600I1025J0D01*
G01X1573663D01*
G03X1576017Y541574I1J3328D01*
G01X1577038Y542595D01*
G02X1577727Y542825I588J-614D01*
G03X1578417Y543054I103J844D01*
G01X1579371Y544009D01*
G03X1579601Y544698I-614J588D01*
G02X1579831Y545388I844J102D01*
G01X1581026Y546583D01*
G02X1581716Y546813I588J-614D01*
G03X1582405Y547043I101J844D01*
G01X1583360Y547998D01*
G03X1583590Y548687I-614J588D01*
G02X1583819Y549376I844J102D01*
G01X1586958Y552515D01*
G03X1587985Y554993I-2478J2479D01*
G01Y565789D01*
G02X1588252Y566430I906J-1D01*
G01X1588330Y566508D01*
G02X1588971Y566775I642J-639D01*
G01X1589444D01*
G02X1590023Y566534I-1J-818D01*
G01X1590101Y566456D01*
G02X1590342Y565878I-577J-580D01*
G01Y551546D01*
G03X1590813Y550411I1602J-1D01*
G01X1591181Y550043D01*
G03X1592737Y549398I1554J1550D01*
G01X1593470D01*
G03X1595595Y551523I0J2125D01*
G01Y554675D01*
G02X1597545I975J0D01*
G01Y551523D01*
G03X1601795I2125J0D01*
G01Y554675D01*
G02X1603745I975J0D01*
G01Y551523D01*
G03X1605870Y549398I2125J0D01*
G01X1608564D01*
G03X1610770Y551604I0J2206D01*
G01Y552588D01*
G02X1611668Y553486I898J0D01*
G01X1611792D01*
G03X1613489Y554190I-5J2408D01*
G01X1614313Y555014D01*
G02X1614630Y555147I319J-317D01*
G01X1616805Y555151D01*
G03X1618804Y557148I2J1997D01*
G01Y557326D01*
G03X1616629Y559501I-2175J0D01*
G01X1615834D01*
G02X1614809Y560526I0J1025D01*
G01Y561230D01*
G02X1615834Y562255I1025J0D01*
G03X1618292Y564713I0J2458D01*
G01Y565469D01*
G02X1620342I1025J0D01*
G01Y559881D01*
G03X1623541Y556682I3199J0D01*
G01X1624644D01*
G02X1625094Y556232I0J-450D01*
G01Y555200D01*
G01X1492700Y520000D02*
X1492082Y520618D01*
G02X1491950Y520936I318J318D01*
G01Y524637D01*
G02X1492275Y525287I850J-19D01*
G03X1492600Y525937I-525J669D01*
G01Y527287D01*
G03X1492275Y527937I-850J-19D01*
G02X1491950Y528587I525J669D01*
G01Y529937D01*
X1491951Y529936D01*
G02X1492720Y531792I2625J0D01*
G01X1496424Y535496D01*
G02X1497114Y535726I588J-614D01*
G03X1497803Y535956I101J844D01*
G01X1498758Y536911D01*
G03X1498988Y537600I-614J588D01*
G02X1499217Y538289I844J102D01*
G01X1500172Y539244D01*
G02X1500863Y539530I691J-692D01*
G01X1505486D01*
G02X1506136Y539205I-19J-850D01*
G03X1506786Y538880I669J525D01*
G01X1508136D01*
G03X1508786Y539205I-19J850D01*
G02X1509436Y539530I669J-525D01*
G01X1515784D01*
G03X1518012Y540453I0J3151D01*
G01X1523951Y546392D01*
G02X1525365Y546979I1415J-1413D01*
G01X1543006D01*
G03X1545256Y549229I0J2250D01*
G01Y550765D01*
G02X1547306I1025J0D01*
G01Y549154D01*
G03X1551656I2175J0D01*
G01Y550765D01*
G02X1553706I1025J0D01*
G01Y549154D01*
G03X1558056I2175J0D01*
G01Y550765D01*
G02X1560106I1025J0D01*
G01Y549154D01*
G03X1564456I2175J0D01*
G01Y550765D01*
G02X1566506I1025J0D01*
G01Y549192D01*
G03X1568719Y546979I2213J0D01*
G01X1570065D01*
G03X1571734Y547669I1J2360D01*
G01X1571736Y547671D01*
G03X1572846Y550348I-2678J2679D01*
G01Y553963D01*
G02X1573276Y554998I1464J-1D01*
G01X1574357Y556079D01*
G03X1575360Y558499I-2420J2421D01*
G01Y561807D01*
G02X1575685Y562457I850J-19D01*
G03X1576010Y563107I-525J669D01*
G01Y564457D01*
G03X1575685Y565107I-850J-19D01*
G02X1575360Y565757I525J669D01*
G01Y567107D01*
G02X1575685Y567757I850J-19D01*
G03X1576010Y568407I-525J669D01*
G01Y569757D01*
G03X1575685Y570407I-850J-19D01*
G02X1575360Y571057I525J669D01*
G01Y572407D01*
G02X1575909Y573730I1872J-1D01*
G01X1577002Y574823D01*
G02X1578243Y575337I1241J-1241D01*
G01X1581271D01*
G02X1582613Y574781I0J-1898D01*
G01X1583507Y573887D01*
G03X1585426Y573093I1918J1919D01*
G01X1593199D01*
G02X1595174Y572275I0J-2793D01*
G01X1596836Y570613D01*
G03X1598861Y569750I2024J1942D01*
G01X1600214D01*
G02X1600532Y569618I0J-450D01*
G01X1601825Y568325D01*
G01X1607533Y557644D02*
X1606445Y558732D01*
G03X1606127Y558864I-318J-318D01*
G01X1595922D01*
G02X1594177Y559587I0J2467D01*
G01X1594175Y559589D01*
G02X1593442Y561362I1774J1772D01*
G01Y568629D01*
G03X1592163Y569908I-1279J0D01*
G01X1586975D01*
G03X1585706Y569381I1J-1795D01*
G01X1585361Y569036D01*
G03X1584865Y567841I1195J-1196D01*
G01Y557432D01*
G02X1583402Y553897I-4999J-1D01*
G01X1582388Y552883D01*
G02X1579204I-1592J1592D01*
G01X1578123Y553964D01*
G03X1576676I-723J-724D01*
G01X1576673Y553961D01*
G03Y552513I724J-724D01*
G01X1577806Y551380D01*
G02Y548302I-1539J-1539D01*
G01X1574026Y544522D01*
G02X1572304Y543810I-1721J1723D01*
G01X1550543D01*
G03X1549893Y543485I19J-850D01*
G02X1549243Y543160I-669J525D01*
G01X1547893D01*
G02X1547243Y543485I19J850D01*
G03X1546593Y543810I-669J-525D01*
G01X1544096D01*
G03X1543446Y543485I19J-850D01*
G02X1542796Y543160I-669J525D01*
G01X1541446D01*
G02X1540796Y543485I19J850D01*
G03X1540146Y543810I-669J-525D01*
G01X1527166D01*
G03X1526594Y543572I1J-810D01*
G01X1525745Y542723D01*
G03X1525516Y542034I615J-587D01*
G02X1525286Y541345I-844J-101D01*
G01X1524331Y540390D01*
G02X1523642Y540160I-588J614D01*
G03X1522952Y539930I-102J-844D01*
G01X1521997Y538975D01*
G03X1521768Y538286I615J-587D01*
G02X1521538Y537597I-844J-101D01*
G01X1520583Y536642D01*
G02X1519894Y536412I-588J614D01*
G03X1519204Y536182I-102J-844D01*
G01X1516018Y532996D01*
G02X1514886Y532527I-1132J1131D01*
G01X1514181D01*
G02X1512462Y534246I0J1719D01*
G01Y535353D01*
G03X1511437Y536378I-1025J0D01*
G01X1511188D01*
G03X1510412Y535602I0J-776D01*
G01Y534777D01*
G02X1508162Y532527I-2250J0D01*
G01X1507162D01*
G02X1505569Y533186I-1J2251D01*
G01X1505481Y533274D01*
G02X1504822Y534867I1592J1592D01*
G01Y535302D01*
G03X1504528Y536009I-998J-1D01*
G01X1504431Y536106D01*
G03X1503680Y536417I-752J-752D01*
G01X1502904D01*
G03X1502125Y536093I1J-1101D01*
G01X1501913Y535881D01*
G03X1501589Y535102I777J-780D01*
G01Y533083D01*
G02X1500038Y529337I-5295J-2D01*
G01X1497712Y527011D01*
G03X1497000Y525292I1719J-1719D01*
G01Y520643D01*
G02X1496050Y518349I-3244J0D01*
G01X1493517Y515816D01*
G03X1493516Y514287I765J-765D01*
G01X1495269Y512532D01*
G02X1496321Y509991I-2544J-2541D01*
G02X1493073Y508646I-1902J0D01*
G01X1489347Y512372D01*
G03X1488223I-562J-562D01*
G01X1487386Y511535D01*
G03X1487170Y511017I516J-519D01*
G01Y509509D01*
G03X1487446Y508843I944J1D01*
G01X1488289Y508000D01*
X1488293D01*
G01X1481975Y507975D02*
X1481182Y508768D01*
G02X1481050Y509086I318J318D01*
G01Y510700D01*
G03X1480502Y512026I-1875J1D01*
G01X1480314Y512214D01*
G02X1479551Y514056I1842J1842D01*
G01X1479550Y514055D01*
Y516992D01*
G02X1479714Y517386I556J0D01*
G01X1482154Y519825D01*
G02X1483901Y520550I1748J-1745D01*
G01X1485167D01*
G03X1488250Y523633I0J3083D01*
G01Y530364D01*
G02X1489216Y532694I3294J0D01*
G01X1500558Y544036D01*
G03X1501399Y546068I-2035J2032D01*
G01Y549181D01*
G02X1501541Y549521I480J-1D01*
G02X1502720Y550079I1172J-952D01*
G01X1504089D01*
G02X1505114Y549054I0J-1025D01*
G01Y544808D01*
G03X1509464I2175J0D01*
G01Y549054D01*
G02X1511514I1025J0D01*
G01Y544808D01*
G03X1515864I2175J0D01*
G01Y549054D01*
G02X1516889Y550079I1025J0D01*
G01X1518239D01*
G02X1518889Y549754I-19J-850D01*
G03X1519539Y549429I669J525D01*
G01X1520889D01*
G03X1521539Y549754I-19J850D01*
G02X1522189Y550079I669J-525D01*
G01X1537284D01*
G03X1540719Y551501I1J4856D01*
G01X1543555Y554337D01*
G02X1545073Y554967I1519J-1517D01*
G01X1547683D01*
G02X1548333Y554642I-19J-850D01*
G03X1548983Y554317I669J525D01*
G01X1550333D01*
G03X1550983Y554642I-19J850D01*
G02X1551633Y554967I669J-525D01*
G01X1554002D01*
G02X1554652Y554642I-19J-850D01*
G03X1555302Y554317I669J525D01*
G01X1556652D01*
G03X1557302Y554642I-19J850D01*
G02X1557952Y554967I669J-525D01*
G01X1560287D01*
G02X1560937Y554642I-19J-850D01*
G03X1561587Y554317I669J525D01*
G01X1562937D01*
G03X1563587Y554642I-19J850D01*
G02X1564237Y554967I669J-525D01*
G01X1566956D01*
G03X1569999Y556226I1J4304D01*
G01X1570982Y557209D01*
G03X1572004Y559679I-2470J2469D01*
G01Y573747D01*
G02X1572840Y575763I2851J-1D01*
G01X1575147Y578070D01*
G02X1576573Y578662I1427J-1425D01*
G01X1583036D01*
G02X1583815Y578338I-1J-1101D01*
G01X1585284Y576869D01*
G03X1586877Y576210I1592J1592D01*
G01X1592965D01*
G03X1594558Y576869I1J2251D01*
G01X1596494Y578805D01*
G02X1599198Y579925I2704J-2704D01*
G01X1604383D01*
G02X1604701Y579793I0J-450D01*
G01X1605994Y578500D01*
G01X1594280Y472370D02*
X1592972Y473678D01*
Y486472D01*
X1598600Y492100D01*
X1622583D01*
X1626333Y488350D01*
X1631478D01*
X1636088Y492960D01*
X1645868D01*
X1650988Y498080D01*
X1652338D01*
X1652988Y497430D01*
X1654338D01*
X1654988Y498080D01*
X1664991D01*
X1670413Y503502D01*
X1674425D01*
X1684823Y493104D01*
X1712019D01*
X1715016Y490107D01*
X1759707D01*
X1772925Y503325D01*
X1825577D01*
X1826227Y502675D01*
X1827577D01*
X1828227Y503325D01*
X1829577D01*
X1830227Y502675D01*
X1831577D01*
X1832227Y503325D01*
X1837075D01*
X1839075Y501325D01*
X1844048D01*
X1846600Y498772D01*
Y491901D01*
X1848801Y489700D01*
X1851790D01*
X1852719Y488771D01*
Y487575D01*
G01X1590580Y472370D02*
X1591822Y473612D01*
Y486949D01*
X1598123Y493250D01*
X1623060D01*
X1626810Y489500D01*
X1631001D01*
X1635611Y494110D01*
X1645391D01*
X1650511Y499230D01*
X1664514D01*
X1669936Y504652D01*
X1674902D01*
X1685300Y494254D01*
X1712496D01*
X1715493Y491257D01*
X1759230D01*
X1772448Y504475D01*
X1837552D01*
X1839552Y502475D01*
X1844525D01*
X1847750Y499249D01*
Y492378D01*
X1849278Y490850D01*
X1851800D01*
X1852719Y491769D01*
Y492575D01*
G54D23*
G01X-14971Y540000D02*
X-20610Y545639D01*
Y570890D01*
X-17500Y574000D01*
G01X41677Y-14390D02*
X42130Y-13937D01*
X42208D01*
X45653Y-10492D01*
X57027D01*
X59182Y-8337D01*
X76499D01*
X90117Y5281D01*
X97173D01*
X101800Y9908D01*
Y19100D01*
X108400Y25700D01*
Y75946D01*
X112664Y80210D01*
Y91108D01*
X113907Y92351D01*
Y93927D01*
X112664Y95170D01*
Y128795D01*
G01X53382Y-1173D02*
X49892Y2317D01*
X38059D01*
X36172Y4204D01*
Y5356D01*
X27622Y13906D01*
Y19137D01*
X24527Y22232D01*
X16362D01*
X15239Y21109D01*
X9816D01*
X5624Y25301D01*
Y30530D01*
X927Y35227D01*
Y37662D01*
X1572Y38307D01*
G01X42520Y-16896D02*
X43364D01*
X47927Y-12333D01*
X58146D01*
X60329Y-10150D01*
X77250D01*
X90681Y3281D01*
X98002D01*
X103800Y9079D01*
Y18271D01*
X110400Y24871D01*
Y75117D01*
X116600Y81317D01*
Y128422D01*
X114255Y130767D01*
X111018D01*
X109622Y129371D01*
Y128879D01*
G01X-6650Y487800D02*
X-5300D01*
X-2080Y484580D01*
X29580D01*
X32387Y487387D01*
X38913D01*
X41300Y485000D01*
X77000D01*
X77300Y484700D01*
X91910D01*
X94998Y481612D01*
G01X14700Y517000D02*
X14480Y517220D01*
Y525990D01*
X6000Y534470D01*
X679D01*
X-2700Y537849D01*
Y540882D01*
X-13550Y551732D01*
Y577950D01*
X-12600Y578900D01*
G01X22491Y500618D02*
X21759Y501350D01*
X12860D01*
X9930Y504280D01*
Y507500D01*
X190Y517240D01*
Y519800D01*
X3610Y523220D01*
Y525510D01*
X1760Y527360D01*
X-2819D01*
X-6820Y531361D01*
Y536640D01*
X-8931Y538751D01*
X-13722D01*
X-14971Y540000D01*
G01X61446Y18238D02*
X60035Y16827D01*
Y7508D01*
G01X98420Y112198D02*
X95878Y114740D01*
X83640D01*
X81880Y116500D01*
Y130480D01*
X85250Y133850D01*
Y163150D01*
X70000Y178400D01*
Y189400D01*
X65676Y193724D01*
X56376D01*
X50500Y199600D01*
Y205696D01*
G01X72800Y105000D02*
X72850Y105050D01*
Y115068D01*
X77790Y120008D01*
Y121030D01*
G01X117080Y225330D02*
X113470D01*
X110787Y228013D01*
Y270973D01*
X107022Y274738D01*
Y336678D01*
X99610Y344090D01*
X95530D01*
X94530Y345090D01*
Y348920D01*
X90660Y352790D01*
X67987D01*
X67786Y352991D01*
X67739D01*
X60934Y359796D01*
Y362307D01*
G01X117063Y257016D02*
X115264Y258815D01*
Y270788D01*
X112917Y273135D01*
Y289583D01*
X110250Y292250D01*
Y306930D01*
X112565Y309245D01*
Y323277D01*
X110515Y325327D01*
Y336845D01*
X110022Y337338D01*
Y338577D01*
X105980Y342619D01*
Y355290D01*
X103730Y357540D01*
X94720D01*
X92970Y355790D01*
X91903D01*
X91902Y355791D01*
X89418D01*
X89417Y355790D01*
X69230D01*
X65310Y359710D01*
Y363123D01*
X62850Y365583D01*
X58607D01*
X57790Y366400D01*
X57400D01*
X57200Y366600D01*
Y366795D01*
X57395D01*
G01X54400Y340300D02*
Y342600D01*
X53900Y343100D01*
Y349000D01*
X51900Y351000D01*
G01X65800Y338900D02*
X63200Y341500D01*
X55600D01*
X54400Y340300D01*
G01X82500Y341400D02*
X76400D01*
X75400Y342400D01*
X69300D01*
X65800Y338900D01*
G01X104600Y316602D02*
X105174Y317176D01*
Y333216D01*
X103200Y335190D01*
G01X84866Y294213D02*
X79424Y299655D01*
Y317390D01*
X81300Y319266D01*
Y323500D01*
X79400Y325400D01*
G01X79600Y335200D02*
X77000Y332600D01*
X69000D01*
X67488Y331088D01*
X51714D01*
X49200Y333602D01*
Y340650D01*
G01X88840Y324740D02*
Y325308D01*
X86848Y327300D01*
X78612D01*
X77500Y326188D01*
Y324472D01*
X79500Y322472D01*
Y320012D01*
X77861Y318373D01*
X71852D01*
X69000Y315521D01*
Y313188D01*
X67225Y311413D01*
Y308837D01*
X61088Y302700D01*
X58600D01*
G01X59452Y338800D02*
X64002Y334250D01*
X75962D01*
X78812Y337100D01*
X80850D01*
X82150Y335800D01*
G01X92086Y324258D02*
X91430Y324914D01*
Y325870D01*
X87800Y329500D01*
X75300D01*
X70400Y324600D01*
X68800D01*
X66900Y322700D01*
Y322000D01*
G01X117063Y321016D02*
Y323022D01*
X115337Y324748D01*
Y337633D01*
X112840Y340130D01*
Y345570D01*
X110610Y347800D01*
Y363240D01*
X108166Y365684D01*
X91844D01*
X90070Y363910D01*
X68700D01*
X63879Y368731D01*
X61914D01*
G01X117063Y353016D02*
X115544Y354535D01*
Y372466D01*
X114430Y373580D01*
X105430D01*
X104130Y374880D01*
X101010D01*
X98780Y372650D01*
X61250D01*
X57800Y376100D01*
G01X117063Y385016D02*
X106426D01*
X97440Y376030D01*
X63530D01*
X62600Y375100D01*
G01X106392Y527413D02*
Y521866D01*
X108864Y519394D01*
Y506319D01*
X116493Y498690D01*
Y453421D01*
X142514Y427400D01*
X147690D01*
X154910Y420180D01*
Y412560D01*
X169680Y397790D01*
X177790D01*
X180799Y400799D01*
Y404049D01*
G01X105392Y566000D02*
X109422Y561970D01*
Y523239D01*
X111864Y520797D01*
Y507562D01*
X119493Y499933D01*
Y454664D01*
X143433Y430724D01*
X148690D01*
X170748Y408666D01*
Y402382D01*
X172170Y400960D01*
X176160D01*
X177689Y402489D01*
Y404109D01*
G01X174609Y404009D02*
Y409091D01*
X149743Y433957D01*
X144443D01*
X122493Y455907D01*
Y503459D01*
X117180Y508772D01*
Y512471D01*
X114950Y514701D01*
Y520258D01*
X117537Y522845D01*
Y532532D01*
X112422Y537647D01*
Y563213D01*
X110439Y565196D01*
Y600353D01*
X106192Y604600D01*
G01X665396Y23000D02*
X655060Y12664D01*
Y-10111D01*
X647171Y-18000D01*
X462519D01*
X458009Y-13490D01*
X376545D01*
X374401Y-11346D01*
G01X447735Y588394D02*
X449065D01*
X450729Y590058D01*
Y591703D01*
X449092Y593340D01*
Y597980D01*
X451912Y600800D01*
G01X447766Y612659D02*
Y611126D01*
X449692Y609200D01*
Y605800D01*
X448984Y605092D01*
Y602208D01*
X450392Y600800D01*
X451912D01*
G01D02*
X580892D01*
X582992Y602900D01*
Y607100D01*
X584692Y608800D01*
X598306D01*
X602163Y612657D01*
G01X530803Y278338D02*
X530545Y278596D01*
X528491D01*
G01X530972Y270844D02*
X530924Y270796D01*
G01D02*
X528491D01*
G01X647487Y280308D02*
X648019D01*
X649571Y278756D01*
Y261051D01*
X646160Y257640D01*
X634360D01*
X627030Y250310D01*
Y234530D01*
X630872Y230688D01*
Y202678D01*
X654090Y179460D01*
X663482D01*
X668734Y174208D01*
Y163366D01*
X678800Y153300D01*
Y132210D01*
X666243Y119653D01*
Y111242D01*
X667761Y109724D01*
Y84409D01*
X665246Y81894D01*
X660194D01*
X654600Y76300D01*
Y71500D01*
X649860Y66760D01*
Y41350D01*
X656600Y34610D01*
Y31500D01*
G01X652500Y273600D02*
Y279330D01*
X649587Y282243D01*
Y300625D01*
X642400Y307812D01*
Y350300D01*
X652468Y360368D01*
X680764D01*
X683446Y363050D01*
Y364972D01*
G01X628950Y293550D02*
X624176Y298324D01*
Y390176D01*
X633876Y399876D01*
Y426395D01*
X614376Y445895D01*
Y456976D01*
X615300Y457900D01*
G01X623400Y476300D02*
X626042Y473658D01*
Y458058D01*
X636000Y448100D01*
X642100D01*
X647800Y442400D01*
Y406900D01*
X672600Y382100D01*
Y379400D01*
X676200Y375800D01*
Y372218D01*
X683446Y364972D01*
G01X677563Y365496D02*
X674200Y368859D01*
Y374500D01*
X670450Y378250D01*
Y381350D01*
X662500Y389300D01*
X651500D01*
X649600Y391200D01*
G01X714300Y-1900D02*
X724620D01*
X737307Y-14587D01*
X1022408D01*
X1025993Y-11002D01*
X1027202D01*
Y-11005D01*
G01X679300Y261700D02*
Y259940D01*
X692728Y246512D01*
Y229872D01*
X700300Y222300D01*
X707700D01*
X710956Y219044D01*
X714836D01*
X714893Y219101D01*
X715727Y218267D01*
G01X766732Y225189D02*
Y234100D01*
X761352Y239480D01*
X759054D01*
X745370Y253164D01*
Y255287D01*
X736977Y263680D01*
X718104D01*
X713330Y268454D01*
Y270510D01*
X711193Y272647D01*
X709949D01*
G01X766632Y257252D02*
X766469Y257089D01*
X763911D01*
X758400Y262600D01*
X742300D01*
X738110Y266790D01*
X719270D01*
X716400Y269660D01*
Y272300D01*
X713200Y275500D01*
X709700D01*
G01X709600Y278100D02*
X714200D01*
X719660Y272640D01*
X738540D01*
X741639Y275739D01*
X750550D01*
X762881Y288070D01*
X764890D01*
X764980Y287980D01*
G01X766732Y321189D02*
X764889D01*
X754294Y310594D01*
Y294154D01*
X736418Y276278D01*
X719022D01*
X715300Y280000D01*
X708150D01*
X706800Y278650D01*
Y278100D01*
G01X766732Y353189D02*
X765689D01*
X760100Y347600D01*
Y327200D01*
X748350Y315450D01*
Y295120D01*
X735141Y281911D01*
X710272D01*
G01X706800Y281900D02*
Y282300D01*
X710450Y285950D01*
X731250D01*
X733230Y287930D01*
Y292970D01*
X729917Y296283D01*
Y311237D01*
X738180Y319500D01*
X744200D01*
X757100Y332400D01*
Y364133D01*
X760673Y367706D01*
Y381568D01*
X764655Y385550D01*
X767155D01*
G01X683446Y364972D02*
X683417D01*
G01X804470Y186814D02*
X804949Y186335D01*
Y180549D01*
X761900Y137500D01*
Y97488D01*
X759500Y95088D01*
Y93500D01*
X761400Y91600D01*
Y80300D01*
X761444Y80256D01*
Y18599D01*
X760100Y17255D01*
G01X798337Y181216D02*
X796816D01*
X752900Y137300D01*
Y117100D01*
X754900Y115100D01*
Y99000D01*
X752900Y97000D01*
Y92311D01*
X753100Y92111D01*
G01X799620Y186547D02*
X801272Y184895D01*
Y181272D01*
X758900Y138900D01*
Y98731D01*
X756500Y96331D01*
Y90400D01*
X757600Y89300D01*
Y81500D01*
X756500Y80400D01*
Y56200D01*
X755500Y55200D01*
G01X756000Y525950D02*
X754800Y524750D01*
Y497961D01*
X766700Y486061D01*
Y452814D01*
X786700Y432814D01*
Y432813D01*
X790214Y429299D01*
X792698D01*
X792699Y429300D01*
X795950D01*
X822387Y402863D01*
X824000D01*
G01X755000Y566000D02*
Y560100D01*
X757000Y558100D01*
Y542500D01*
X758050Y541450D01*
Y521950D01*
X757800Y521700D01*
Y499204D01*
X769700Y487304D01*
Y454057D01*
X789700Y434057D01*
Y434056D01*
X791456Y432300D01*
X797300D01*
X826737Y402863D01*
X827800D01*
G01X832300D02*
X830980D01*
X798543Y435300D01*
X792700D01*
X772800Y455200D01*
Y491550D01*
X760800Y503550D01*
Y520414D01*
X761090Y520704D01*
Y543686D01*
X760100Y544676D01*
Y599600D01*
X755800Y603900D01*
Y604600D01*
G01X1097343Y588394D02*
X1101606D01*
X1110223Y579777D01*
X1246851D01*
X1251771Y574857D01*
G01X1310098Y150040D02*
X1298506D01*
X1294562Y146096D01*
X1291710D01*
X1278398Y159408D01*
X1264913D01*
X1264628Y159123D01*
X1238128D01*
X1227827Y169424D01*
X1219699D01*
X1209033Y180090D01*
Y183907D01*
G01X1272100Y141603D02*
X1274699Y139004D01*
Y121676D01*
X1276106Y120269D01*
X1279831D01*
X1281650Y118450D01*
Y110750D01*
X1293554Y98846D01*
Y96347D01*
X1295581Y94320D01*
G01X1477100Y2400D02*
Y4341D01*
X1477188Y4429D01*
Y8517D01*
X1468702Y17003D01*
X1461447D01*
X1452279Y26171D01*
X1413089D01*
X1385900Y53360D01*
Y69600D01*
X1375300Y80200D01*
X1362200D01*
X1359624Y77624D01*
X1338024D01*
X1336850Y76450D01*
G01X1381642Y25898D02*
X1380500Y24756D01*
Y11800D01*
X1379300Y10600D01*
X1368100D01*
X1365100Y7600D01*
X1354212D01*
X1348573Y13239D01*
Y34927D01*
X1338700Y44800D01*
Y54176D01*
X1348220Y63696D01*
X1350750D01*
X1358500Y71446D01*
Y74500D01*
G01X1382151Y-5545D02*
X1382578Y-5118D01*
Y932D01*
X1392724Y11078D01*
Y15366D01*
X1397203Y19845D01*
Y29180D01*
X1383721Y42662D01*
Y47362D01*
X1384088Y47729D01*
Y53826D01*
X1378266Y59648D01*
Y66767D01*
X1374067Y70966D01*
Y73353D01*
X1370020Y77400D01*
X1363500D01*
G01X1342570Y368220D02*
X1355220D01*
X1360210Y363230D01*
X1385240D01*
X1397790Y375780D01*
Y386650D01*
X1395792Y388648D01*
X1389748D01*
X1388900Y387800D01*
G01X1385000Y602700D02*
X1386900Y600800D01*
Y588500D01*
X1392900Y582500D01*
X1422684D01*
X1429360Y575824D01*
Y559152D01*
X1424263Y554055D01*
X1420272D01*
X1413600Y547383D01*
Y531300D01*
G01X1387986Y574960D02*
Y565232D01*
X1408628Y544590D01*
Y539890D01*
X1407238Y538500D01*
Y536022D01*
X1410486Y532774D01*
Y529792D01*
G01X1464150Y235550D02*
X1468720D01*
X1474010Y230260D01*
Y219490D01*
X1478611Y214889D01*
Y209695D01*
G01X1515500Y448250D02*
X1515146D01*
X1513307Y450089D01*
Y452317D01*
X1514421Y453431D01*
Y455354D01*
X1512540Y457235D01*
X1509950Y458756D01*
G02X1508975Y460381I975J1690D01*
G01Y460511D01*
G03X1508000Y462136I-1950J-65D01*
G02Y465516I975J1690D01*
G03X1508975Y467141I-975J1690D01*
G01Y467271D01*
G02X1509950Y468896I1950J-65D01*
G03Y472276I-975J1690D01*
G02Y475656I975J1690D01*
G03Y479036I-975J1690D01*
G02Y482416I975J1690D01*
G03Y485796I-975J1690D01*
G02X1508975Y487421I975J1690D01*
G01Y488803D01*
X1501979Y495799D01*
X1495120D01*
X1489619Y501300D01*
X1475160D01*
X1474600Y500740D01*
X1460930D01*
X1458550Y503120D01*
G01X1516775Y457066D02*
X1513850Y458756D01*
G02X1512875Y460381I975J1690D01*
G01Y460511D01*
G03X1511900Y462136I-1950J-65D01*
G02Y465516I975J1690D01*
G03X1512875Y467141I-975J1690D01*
G01Y467271D01*
G02X1513850Y468896I1950J-65D01*
G03Y472276I-975J1690D01*
G02Y475656I975J1690D01*
G03Y479036I-975J1690D01*
G02Y482416I975J1690D01*
G03Y485796I-975J1690D01*
G02X1512875Y487421I975J1690D01*
G01Y488434D01*
X1503509Y497800D01*
X1496110D01*
X1490620Y503290D01*
X1474110D01*
G01X1513796Y330680D02*
X1513730D01*
X1510440Y327390D01*
Y316437D01*
X1512590Y314287D01*
Y309661D01*
X1517375Y304876D01*
Y303986D01*
X1517374Y303985D01*
Y290943D01*
X1516012Y289581D01*
Y287700D01*
X1515956Y287644D01*
Y286068D01*
X1516012Y286012D01*
Y285712D01*
X1517396Y284328D01*
Y276875D01*
X1520679Y273592D01*
Y255441D01*
X1524768Y251352D01*
X1526749D01*
X1528302Y249799D01*
Y247215D01*
X1526432Y245345D01*
Y237283D01*
X1523950Y234801D01*
Y231048D01*
X1523927Y231025D01*
Y227827D01*
X1517218Y221118D01*
Y211490D01*
X1519350Y209358D01*
Y201954D01*
X1517219Y199823D01*
Y189946D01*
X1515179Y187906D01*
Y184544D01*
X1520158Y179565D01*
Y159883D01*
X1530751Y149290D01*
X1532773D01*
X1537196Y144867D01*
Y135903D01*
X1542023Y131076D01*
X1548423D01*
X1549080Y130419D01*
X1553219D01*
X1553927Y131127D01*
X1558973D01*
X1560650Y129450D01*
Y125154D01*
X1567704Y118100D01*
X1573870D01*
X1575784Y120014D01*
X1582889D01*
X1586575Y123700D01*
X1590700D01*
X1593700Y120700D01*
X1598389D01*
X1598449Y120760D01*
G01X1478611Y209695D02*
X1477100Y208184D01*
Y205270D01*
X1480200Y202170D01*
Y184761D01*
X1478089Y182650D01*
G01X1487716Y218650D02*
X1488081Y218285D01*
Y183775D01*
X1492469Y179387D01*
G01X1475004Y246287D02*
Y249373D01*
X1476500Y250869D01*
Y255760D01*
X1477397Y256657D01*
G01X1487716Y218650D02*
Y219284D01*
X1485995Y221005D01*
Y237270D01*
X1476978Y246287D01*
X1475004D01*
G01X1469880Y507570D02*
X1470950Y506500D01*
X1473940D01*
X1475290Y505150D01*
X1491364D01*
X1496923Y499591D01*
X1504289D01*
X1504680Y499200D01*
X1504681D01*
X1508530Y495351D01*
X1510349D01*
X1516775Y488925D01*
Y487421D01*
G03X1517750Y485796I1950J65D01*
G02Y482416I-975J-1690D01*
G03Y479036I975J-1690D01*
G02Y475656I-975J-1690D01*
G03Y472276I975J-1690D01*
G02Y468896I-975J-1690D01*
G03X1516775Y467271I975J-1690D01*
G01Y467141D01*
G02X1515800Y465516I-1950J65D01*
G03Y462136I975J-1690D01*
G02X1516775Y460511I-975J-1690D01*
G01Y460381D01*
G03X1517750Y458756I1950J65D01*
G02X1518725Y457131I-975J-1690D01*
G01Y457066D01*
X1518675Y456907D01*
Y451425D01*
G01X1509200Y410450D02*
X1508374Y409624D01*
X1508000D01*
G02X1506050I-975J1690D01*
G03X1504100I-975J-1690D01*
G02X1502150I-975J1690D01*
G03X1500200I-975J-1690D01*
G01X1499548Y409248D01*
G02X1498254Y409462I-323J2066D01*
G01X1498130Y409527D01*
G03X1496304Y409462I-846J-1917D01*
G02X1495011Y409242I-980J1852D01*
G01X1494350Y409624D01*
G03X1492400I-975J-1690D01*
G02X1490450I-975J1690D01*
G03X1488500I-975J-1690D01*
G01X1485250Y408017D01*
G01X1518650Y448250D02*
X1518539D01*
X1515389Y451400D01*
G01X1521800D02*
X1518650Y448250D01*
G01X1513770Y404510D02*
X1519640D01*
X1521200Y406070D01*
Y411600D01*
X1523200Y413600D01*
X1524950D01*
G01X1547375Y245850D02*
X1541577Y251648D01*
Y254413D01*
X1531400Y264590D01*
Y274600D01*
X1533914Y277114D01*
Y286073D01*
G01X1560500Y350000D02*
X1552600Y342100D01*
Y327700D01*
X1554732Y325568D01*
Y312704D01*
X1551404Y309376D01*
G01X1559600Y490400D02*
X1565800Y496600D01*
X1567800D01*
X1569900Y498700D01*
Y500700D01*
X1568400Y502200D01*
Y503300D01*
G01X1602215Y363981D02*
Y363853D01*
X1596392Y358030D01*
Y326813D01*
X1592110Y322531D01*
Y322002D01*
G01X1766240Y70500D02*
X1749730D01*
X1748547Y71683D01*
X1731983D01*
X1727650Y67350D01*
X1724686D01*
X1723574Y68462D01*
Y71126D01*
X1721788Y72912D01*
X1705132D01*
X1702491Y75553D01*
X1700597D01*
X1700259Y75891D01*
X1691067D01*
X1690809Y76149D01*
X1690155D01*
X1689155Y77149D01*
Y77991D01*
G01X1713596Y175795D02*
X1712134D01*
X1710606Y177323D01*
X1707599D01*
X1707107Y177815D01*
X1704690D01*
X1704635Y177870D01*
X1676899D01*
X1675019Y175990D01*
X1674019D01*
G01X1837475Y573835D02*
X1838880Y572430D01*
X1854430D01*
X1855420Y571440D01*
X1862789D01*
X1864747Y573398D01*
X1888728D01*
X1904240Y588910D01*
Y593165D01*
X1910157Y599082D01*
X1923487D01*
X1930099Y592470D01*
Y587961D01*
X1931390Y586670D01*
X1935899D01*
X1939500Y583069D01*
Y558684D01*
X1943580Y554604D01*
X1947496D01*
X1960840Y541260D01*
Y527840D01*
X1947910Y514910D01*
Y505420D01*
X1943100Y500610D01*
Y476170D01*
X1924990Y458060D01*
Y447100D01*
X1922196Y444306D01*
X1906120D01*
X1901545Y439731D01*
X1725187D01*
X1725157Y439701D01*
X1723581D01*
X1723551Y439731D01*
X1675120D01*
G01X1738216Y548239D02*
X1737381D01*
X1729656Y555964D01*
X1702418D01*
X1698866Y559516D01*
X1667076D01*
X1665500Y561092D01*
X1655798D01*
X1653960Y562930D01*
G01X1843107Y97988D02*
X1835389Y90270D01*
X1826240D01*
X1816380Y80410D01*
X1804800D01*
X1801050Y84160D01*
X1797288D01*
X1785752Y72624D01*
X1768364D01*
X1766240Y70500D01*
G01X1918113Y93576D02*
X1918049D01*
X1916081Y95544D01*
Y99834D01*
X1907966Y107949D01*
X1906083D01*
X1891729Y93595D01*
X1875290D01*
X1861198Y107687D01*
Y115080D01*
X1859626Y116652D01*
X1849551D01*
X1842727Y109828D01*
X1814972D01*
X1810100Y114700D01*
G01X1789300Y520000D02*
X1790200Y519100D01*
X1807178D01*
X1810631Y522553D01*
X1819553D01*
X1822800Y525800D01*
X1826900D01*
X1831100Y521600D01*
X1836600D01*
G01X1793452Y586701D02*
X1796499D01*
X1802895Y580305D01*
X1810261D01*
X1813456Y583500D01*
G01D02*
X1813960D01*
X1816760Y580700D01*
X1830610D01*
X1837475Y573835D01*
G01X1900945Y1674D02*
X1893151D01*
X1891281Y3544D01*
Y38196D01*
X1894719Y41634D01*
X1900945D01*
G01X1877103Y60791D02*
X1877102D01*
X1874600Y63293D01*
Y87285D01*
X1862382Y99503D01*
X1844622D01*
X1843107Y97988D01*
G01X1932390Y590100D02*
X1933490D01*
X1937870Y594480D01*
G54D14*
X18228Y178386D03*
X-1969D03*
X44291D03*
G54D33*
G01X37739Y19501D02*
Y21092D01*
X41001Y24354D01*
X82919D01*
X84253Y25688D01*
Y82042D01*
X82195Y84100D01*
X59200D01*
X54400Y88900D01*
Y154606D01*
X47370Y161636D01*
X-2978D01*
X-20523Y179181D01*
Y238278D01*
X-12247Y246554D01*
Y301377D01*
X-19218Y308348D01*
Y341479D01*
X-9634Y351063D01*
X30783D01*
X37303Y357583D01*
Y407174D01*
X29038Y415439D01*
Y442358D01*
X25062Y446334D01*
X18383D01*
X-19861Y484578D01*
Y497011D01*
X-16766Y500106D01*
G01X43960Y20572D02*
X84396D01*
X87800Y23976D01*
Y83500D01*
X83796Y87504D01*
X61196D01*
X57804Y90896D01*
Y156843D01*
X49175Y165472D01*
X-1547D01*
X-17119Y181044D01*
Y236868D01*
X-8763Y245224D01*
Y303700D01*
X-15813Y310750D01*
Y338888D01*
X-7042Y347659D01*
X32533D01*
X40765Y355891D01*
Y408529D01*
X33297Y415997D01*
Y443399D01*
X26660Y450036D01*
X19495D01*
X-16457Y485988D01*
Y490273D01*
X-15000Y491730D01*
Y504496D01*
X-17302Y506798D01*
G01X40530Y20220D02*
X42609Y22299D01*
X83630D01*
X85955Y24624D01*
Y82747D01*
X82900Y85802D01*
X59905D01*
X56102Y89605D01*
Y155999D01*
X48620Y163481D01*
X-2252D01*
X-18821Y180050D01*
Y237573D01*
X-10465Y245929D01*
Y302002D01*
X-17515Y309052D01*
Y339327D01*
X-17516Y339328D01*
Y340614D01*
X-17515Y340615D01*
Y340737D01*
X-8891Y349361D01*
X31488D01*
X39063Y356936D01*
Y407823D01*
X31300Y415586D01*
Y442696D01*
X25662Y448334D01*
X18790D01*
X-18159Y485283D01*
Y496241D01*
X-17000Y497400D01*
X-16700D01*
G01X-5680Y524570D02*
X-5880D01*
X-8350Y522100D01*
X-15766D01*
X-18034Y519832D01*
Y511634D01*
X-17200Y510800D01*
G01X-16186Y519304D02*
X-15206Y518324D01*
Y513205D01*
X-11649Y509648D01*
X-3680D01*
X-3328Y509296D01*
Y494898D01*
X162Y491408D01*
X5002D01*
X8510Y487900D01*
X15392D01*
X18900Y491408D01*
X50492D01*
X52452Y489448D01*
X70348D01*
X86100Y505200D01*
G01X23228Y140591D02*
X25976Y137843D01*
X32684D01*
X37776Y132751D01*
Y97126D01*
X34000Y93350D01*
G01X17716Y140591D02*
X20247Y143122D01*
X35666D01*
X38831Y139957D01*
Y94331D01*
X35650Y91150D01*
G01X59731Y480066D02*
X58850Y479185D01*
Y476650D01*
X61521Y473979D01*
X69830D01*
X85462Y458347D01*
Y443835D01*
X45822Y404195D01*
Y354752D01*
X47441Y353133D01*
Y333273D01*
X51102Y329612D01*
X53368D01*
X55007Y327973D01*
Y321872D01*
X49526Y316391D01*
X49500D01*
Y303672D01*
X51700Y301472D01*
Y283200D01*
G01X50151Y281651D02*
Y267774D01*
X46066Y263689D01*
Y214747D01*
X54248Y206565D01*
Y203978D01*
X54247Y203977D01*
Y203023D01*
X60572Y196698D01*
X76372D01*
X87151Y185919D01*
Y184872D01*
G01X91952Y620900D02*
X90302Y622550D01*
X85259D01*
X84054Y621345D01*
Y616924D01*
X87657Y613321D01*
Y526982D01*
X68878Y508203D01*
Y496153D01*
X64157Y491432D01*
X52868D01*
X52139Y492161D01*
X18260D01*
X15109Y489010D01*
X9010D01*
X5859Y492161D01*
X2850D01*
X-255Y495266D01*
Y509274D01*
X-6712Y515731D01*
G01X5100Y478330D02*
X6676D01*
X9641Y481295D01*
X18353D01*
X23091Y476557D01*
X39294D01*
X45237Y482500D01*
X71970D01*
X78752Y475718D01*
X89023D01*
X91073Y477768D01*
Y479145D01*
X92326Y480398D01*
G01X2160Y479000D02*
X2750D01*
X3937Y480187D01*
X6812D01*
X8872Y482247D01*
X18748D01*
X23486Y477509D01*
X38899D01*
X44790Y483400D01*
X72417D01*
X79147Y476670D01*
X88628D01*
X89497Y477539D01*
Y479201D01*
G01X148901Y-50496D02*
X445509D01*
G02Y-53848I0J-1676D01*
G01X147382D01*
X145030Y-56200D01*
X64450D01*
X60500Y-52250D01*
G01X82300Y-16600D02*
X83034D01*
X87201Y-12433D01*
Y-3662D01*
X91668Y805D01*
X99028D01*
X104723Y6500D01*
X106700D01*
X116700Y16500D01*
Y32900D01*
X118300Y34500D01*
Y41000D01*
X122000Y44700D01*
Y67200D01*
X119800Y69400D01*
Y81300D01*
X118300Y82800D01*
Y107302D01*
X120533Y109535D01*
G01X88777Y-10586D02*
X93382Y-15191D01*
X452722D01*
X457207Y-19676D01*
X655035D01*
X658981Y-15730D01*
X663451D01*
X664588Y-14593D01*
Y-2664D01*
X676928Y9676D01*
X702323D01*
X703221Y8778D01*
Y8117D01*
X704514Y6824D01*
X705329D01*
X706284Y5869D01*
Y185D01*
X707440Y-971D01*
Y-14215D01*
X714825Y-21600D01*
X1300244D01*
X1302120Y-19724D01*
Y-14043D01*
X1299524Y-11447D01*
Y19396D01*
X1300500Y20372D01*
Y45600D01*
X1309976Y55076D01*
Y83024D01*
X1309700Y83300D01*
G01X88600Y302997D02*
X89200Y302397D01*
Y269474D01*
X81241Y261515D01*
Y212659D01*
X88500Y205400D01*
Y194820D01*
X94100Y189220D01*
Y183086D01*
X105693Y171493D01*
Y132275D01*
X103860Y130442D01*
Y126721D01*
X104735Y125846D01*
Y122401D01*
X110400Y116736D01*
Y99800D01*
X107804Y97204D01*
X89804D01*
X86600Y94000D01*
G01X92485Y105000D02*
X96722Y109237D01*
X98682D01*
X103917Y114472D01*
Y125600D01*
X103108Y126409D01*
Y130754D01*
X104600Y132246D01*
Y168877D01*
X88979Y184498D01*
Y189592D01*
X86249Y192322D01*
X82378D01*
X76850Y197850D01*
X61050D01*
X55400Y203500D01*
Y207043D01*
X47218Y215225D01*
Y263027D01*
X51303Y267112D01*
Y281076D01*
X53425Y283198D01*
G01X54600Y284373D02*
Y287200D01*
X72600Y305200D01*
Y310800D01*
G01X720300Y485800D02*
X720100Y486000D01*
X705150D01*
X704150Y485000D01*
X687450D01*
X680474Y491976D01*
X674914D01*
X672780Y494110D01*
X667332D01*
X666980Y494462D01*
Y497419D01*
X666628Y497771D01*
X665924D01*
X665572Y497419D01*
Y494462D01*
X665220Y494110D01*
X664516D01*
X664164Y494462D01*
Y497746D01*
X663812Y498098D01*
X663108D01*
X662756Y497746D01*
Y494462D01*
X662404Y494110D01*
X661700D01*
X661348Y494462D01*
Y497746D01*
X660996Y498098D01*
X660292D01*
X659940Y497746D01*
Y494462D01*
X659588Y494110D01*
X658884D01*
X658532Y494462D01*
Y497746D01*
X658180Y498098D01*
X657476D01*
X657124Y497746D01*
Y494462D01*
X656772Y494110D01*
X656068D01*
X655716Y494462D01*
Y497384D01*
X649208Y503892D01*
X630174D01*
X625443Y508623D01*
Y596450D01*
X629529Y600536D01*
X640715D01*
X645531Y605352D01*
Y611888D01*
X639808Y617611D01*
X620612D01*
X619099Y616098D01*
X380312D01*
X376902Y619508D01*
X362933D01*
X357734Y614309D01*
X345948D01*
X343948Y616309D01*
X104264D01*
X102236Y614281D01*
Y614167D01*
G01X91150Y618250D02*
X92120Y619220D01*
X92501D01*
X93130Y619849D01*
X345239D01*
X347375Y617713D01*
X355616D01*
X361093Y623190D01*
X378810D01*
X382470Y619530D01*
X617281D01*
X618767Y621016D01*
X642042D01*
X649380Y613678D01*
Y603649D01*
X642365Y596634D01*
X631455D01*
X628848Y594027D01*
Y510032D01*
X631584Y507296D01*
X650911D01*
X656507Y501700D01*
X667707D01*
X671707Y497700D01*
X674004D01*
X676324Y495380D01*
X681884D01*
X688860Y488404D01*
X702247D01*
X702415Y488572D01*
Y488573D01*
X703411Y489569D01*
X703412D01*
X703745Y489902D01*
X723038D01*
X723792Y489148D01*
G01X93800Y618111D02*
X344553D01*
X346653Y616011D01*
X356625D01*
X361824Y621210D01*
X377929D01*
X381339Y617800D01*
X618394D01*
X619907Y619313D01*
X620083D01*
X620084Y619314D01*
X640799D01*
X647417Y612696D01*
Y604831D01*
X641420Y598834D01*
X630234D01*
X627146Y595746D01*
Y510737D01*
X627145Y510736D01*
Y509328D01*
X630879Y505594D01*
X650206D01*
X656000Y499800D01*
X667200D01*
X671100Y495900D01*
X673397D01*
X675619Y493678D01*
X681179D01*
X688155Y486702D01*
X702952D01*
X704450Y488200D01*
X721301D01*
G01X731210Y-15134D02*
Y-12874D01*
X729756Y-11420D01*
X729723D01*
X727202Y-8899D01*
X715722D01*
X709696Y-2873D01*
Y439D01*
X708800Y1335D01*
Y17800D01*
X703652Y22948D01*
X687922D01*
X686704Y21730D01*
X680791D01*
X671673Y30848D01*
X665853D01*
X661010Y26005D01*
X650865D01*
X645984Y21124D01*
Y3488D01*
X646160Y3312D01*
Y2942D01*
X650400Y-1298D01*
Y-12400D01*
X646476Y-16324D01*
X466505D01*
X461995Y-11814D01*
X459768D01*
X459691Y-11737D01*
X459069D01*
X459068Y-11738D01*
X456005D01*
X452592Y-8325D01*
X449661D01*
X448369Y-9617D01*
X447576D01*
X445754Y-11439D01*
X432185D01*
X432147Y-11477D01*
X430841D01*
X430803Y-11439D01*
X405413D01*
X405375Y-11477D01*
X404069D01*
X404031Y-11439D01*
X398720D01*
X398682Y-11477D01*
X397376D01*
X397338Y-11439D01*
X396886D01*
X396090Y-10643D01*
Y-3660D01*
X396579Y-3171D01*
Y3727D01*
X396226Y4080D01*
Y10308D01*
X396511Y10593D01*
Y15328D01*
X394682Y17157D01*
G01Y607292D02*
Y607618D01*
X393000Y609300D01*
Y613739D01*
X393507Y614246D01*
X423244D01*
X426650Y610840D01*
X430241D01*
X431021Y611620D01*
X433648D01*
X434678Y610590D01*
X436684D01*
X437534Y611440D01*
X440421D01*
X440880Y610981D01*
X443481D01*
X443940Y611440D01*
X444034D01*
X446840Y614246D01*
X619867D01*
X621380Y615759D01*
X631741D01*
G01X421454Y-1817D02*
Y-1743D01*
X421455Y-1742D01*
Y9121D01*
G01X452865Y270081D02*
X454126Y268820D01*
X456179D01*
X457725Y267274D01*
X460239D01*
G01X492743Y257502D02*
X495460D01*
X497409Y255553D01*
X498733D01*
X499970Y256790D01*
X502825D01*
X504256Y255359D01*
X511463D01*
X513251Y257147D01*
X518352D01*
G01X498072Y249347D02*
Y250171D01*
X495353Y252890D01*
X493290D01*
X488382Y257798D01*
G01X464976Y266522D02*
X457222D01*
X455700Y265000D01*
X454100D01*
X452666Y263566D01*
X451109D01*
X450433Y264242D01*
X448955Y264854D01*
X447913Y265061D01*
X445625D01*
X444752Y264188D01*
G01X453250Y623320D02*
X453410D01*
X455258Y621472D01*
X616315D01*
X617711Y622868D01*
X644142D01*
X651279Y615731D01*
Y596991D01*
X657470Y590800D01*
X668800D01*
X670600Y592600D01*
X698600D01*
X709500Y603500D01*
Y611500D01*
X713500Y615500D01*
Y618000D01*
G01X456910Y623320D02*
X458006Y622224D01*
X615923D01*
X617719Y624020D01*
X644620D01*
X652690Y615950D01*
Y597210D01*
X657948Y591952D01*
X668322D01*
X670122Y593752D01*
X698122D01*
X708348Y603978D01*
Y613478D01*
X711144Y616274D01*
X711500D01*
G01X605510Y27899D02*
X603855Y29554D01*
Y53144D01*
X605510Y54799D01*
G01Y16999D02*
Y27899D01*
G01Y-9901D02*
X603855Y-8246D01*
Y15344D01*
X605510Y16999D01*
G01X647400Y-6900D02*
X647100Y-6600D01*
Y-5700D01*
X640000Y1400D01*
X624300D01*
X616100Y-6800D01*
X608400D01*
X605510Y-9690D01*
Y-9901D01*
G01Y9157D02*
Y-1743D01*
G01Y36057D02*
X607192Y34375D01*
Y10839D01*
X605510Y9157D01*
G01X647000Y-9500D02*
X648050D01*
X649200Y-8350D01*
Y-6000D01*
X640600Y2600D01*
X623100D01*
X615200Y-5300D01*
X608400D01*
X605510Y-2410D01*
Y-1743D01*
G01X639197Y490367D02*
X636130Y487300D01*
X626900D01*
X620747Y481147D01*
Y479790D01*
X612700Y471743D01*
Y445200D01*
X632200Y425700D01*
Y401700D01*
X622500Y392000D01*
Y291307D01*
X637435Y276372D01*
Y269475D01*
X634110Y266150D01*
X616470D01*
X607340Y257020D01*
Y241986D01*
X612436Y236890D01*
X622060D01*
X622294Y236656D01*
X622300D01*
X629396Y229560D01*
Y201414D01*
X652950Y177860D01*
X662994D01*
X667258Y173596D01*
Y123641D01*
X664563Y120946D01*
Y107886D01*
X666051Y106398D01*
Y85255D01*
X665146Y84350D01*
X660150D01*
X653200Y77400D01*
X649500D01*
X647255Y75155D01*
Y30263D01*
X648138Y29380D01*
X660157D01*
X665054Y34277D01*
X670227D01*
G01X618800Y100100D02*
X623780Y95120D01*
Y34820D01*
X635400Y23200D01*
X642500D01*
X647179Y27879D01*
X660786D01*
X665261Y32354D01*
X671939D01*
X681193Y23100D01*
X685688D01*
X686958Y24370D01*
X704030D01*
X712500Y15900D01*
X735800D01*
X740600Y20700D01*
X748153D01*
X751598Y17255D01*
X755000D01*
G01X605510Y65699D02*
X603855Y67354D01*
Y90944D01*
X605510Y92599D01*
G01Y54799D02*
Y65699D01*
G01Y46957D02*
Y36057D01*
G01Y73857D02*
X607192Y72175D01*
Y48639D01*
X605510Y46957D01*
G01Y84757D02*
Y73857D01*
G01X656100Y486900D02*
X656840D01*
X657740Y486000D01*
X661300D01*
X665710Y481590D01*
Y475870D01*
X659500Y469660D01*
Y419120D01*
X684980Y393640D01*
Y382790D01*
X692990Y374780D01*
Y288980D01*
X693748Y288222D01*
Y277708D01*
X689340Y273300D01*
X686320D01*
X677140Y264120D01*
Y259550D01*
X686542Y250148D01*
Y244348D01*
X681562Y239368D01*
X652762D01*
X645030Y247100D01*
X640090D01*
X638080Y245090D01*
Y234282D01*
X635162Y231364D01*
Y205352D01*
X652862Y187652D01*
X714126D01*
X728462Y173316D01*
Y82538D01*
X733671Y77329D01*
Y75412D01*
G01X683490Y282110D02*
X684288Y281312D01*
Y279115D01*
X683146Y277973D01*
Y274276D01*
X674600Y265730D01*
Y252400D01*
X676730Y250270D01*
X681312D01*
X683048Y248534D01*
Y245472D01*
X680938Y243362D01*
X652492D01*
X645652Y250202D01*
X639478D01*
X635768Y246492D01*
Y235162D01*
X632360Y231754D01*
Y203670D01*
X651268Y184762D01*
X711238D01*
X722948Y173052D01*
Y151805D01*
X725348Y149405D01*
Y77712D01*
X725347Y77711D01*
Y76528D01*
X729735Y72140D01*
X734962D01*
X736915Y70187D01*
Y63506D01*
X741262Y59159D01*
X741461D01*
X741661Y58959D01*
X747531D01*
X752848Y53642D01*
Y46059D01*
X753648Y45259D01*
Y29547D01*
X750700Y26599D01*
Y22488D01*
X753240Y19948D01*
X754752D01*
X756671Y18029D01*
Y13335D01*
X751856Y8520D01*
Y6958D01*
X756368Y2446D01*
Y-1058D01*
X755798Y-1628D01*
X754132D01*
X753882Y-1378D01*
Y-418D01*
X754600Y300D01*
G01X751900Y400D02*
X753070Y-770D01*
Y-1630D01*
X753820Y-2380D01*
X756110D01*
X757120Y-1370D01*
Y2758D01*
X752608Y7270D01*
Y8208D01*
X757423Y13023D01*
Y18363D01*
X757430Y18370D01*
X755100Y20700D01*
X753552D01*
X751452Y22800D01*
Y26287D01*
X754400Y29235D01*
Y45571D01*
X753600Y46371D01*
Y54237D01*
X747926Y59911D01*
X741574D01*
X737667Y63818D01*
Y70499D01*
X735266Y72900D01*
X730322D01*
X726299Y76923D01*
Y77316D01*
X726300Y77317D01*
Y149800D01*
X723900Y152200D01*
Y173447D01*
X711833Y185514D01*
X651580D01*
X633112Y203982D01*
Y231442D01*
X636520Y234850D01*
Y246180D01*
X639790Y249450D01*
X645340D01*
X652180Y242610D01*
X681250D01*
X683800Y245160D01*
Y249129D01*
X681707Y251222D01*
X677125D01*
X675552Y252795D01*
Y265335D01*
X684000Y273783D01*
Y277480D01*
X685240Y278720D01*
Y280990D01*
X686470Y282220D01*
G01X730923Y75315D02*
Y79013D01*
X727710Y82226D01*
Y173004D01*
X713814Y186900D01*
X652550D01*
X634410Y205040D01*
Y231676D01*
X637328Y234594D01*
Y245402D01*
X639778Y247852D01*
X645342D01*
X653074Y240120D01*
X681250D01*
X685790Y244660D01*
Y249836D01*
X676388Y259238D01*
Y264432D01*
X688240Y276284D01*
Y283710D01*
X686900Y285050D01*
Y293970D01*
X689520Y296590D01*
Y307791D01*
X689676Y307947D01*
Y309253D01*
X689520Y309409D01*
Y358200D01*
X685780Y361940D01*
Y369620D01*
X674135Y381265D01*
Y387035D01*
X651944Y409226D01*
Y454179D01*
X644461Y461662D01*
Y486340D01*
X642000Y488801D01*
Y491001D01*
X637501Y495500D01*
X633805D01*
X632653Y494348D01*
X631022D01*
X626122Y499248D01*
X626121D01*
X620748Y504621D01*
Y504622D01*
X617648Y507722D01*
Y534803D01*
X620526Y537681D01*
Y606626D01*
X625708Y611808D01*
Y613046D01*
X627262Y614600D01*
X630582D01*
X631741Y615759D01*
G01X643591Y266983D02*
X643125D01*
X639852Y270256D01*
Y287751D01*
X638046Y289557D01*
Y292611D01*
X627031Y303626D01*
Y387139D01*
X628027Y388135D01*
X628028D01*
X636052Y396159D01*
Y427297D01*
X617000Y446349D01*
Y461769D01*
X615639Y463130D01*
Y471339D01*
X618800Y474500D01*
G01X620400Y463990D02*
X620881Y463509D01*
Y457409D01*
X621233Y457057D01*
X622648D01*
X623000Y456705D01*
Y456001D01*
X622648Y455649D01*
X621052D01*
X620700Y455297D01*
Y454593D01*
X621052Y454241D01*
X622648D01*
X623000Y453889D01*
Y453185D01*
X622648Y452833D01*
X621052D01*
X620700Y452481D01*
Y447463D01*
X638459Y429704D01*
X638460D01*
X639456Y428708D01*
Y394749D01*
X630435Y385728D01*
Y305036D01*
X641451Y294020D01*
X645880D01*
X647100Y292800D01*
Y287400D01*
X645105Y285405D01*
Y278584D01*
X643500Y276979D01*
Y274868D01*
G01X642855Y269660D02*
X641684Y270831D01*
Y277570D01*
X643403Y279289D01*
Y284961D01*
X641639Y286725D01*
Y291425D01*
X628733Y304331D01*
Y386433D01*
X637754Y395454D01*
Y428002D01*
X618916Y446840D01*
Y462453D01*
X617341Y464028D01*
Y468974D01*
X618197Y469830D01*
X619010D01*
X619390Y469450D01*
G01X648025Y501575D02*
Y500422D01*
X649999Y498448D01*
Y496197D01*
X645708Y491906D01*
Y489931D01*
X651959Y483680D01*
Y459621D01*
X655078Y456502D01*
Y417422D01*
X683707Y388793D01*
Y381393D01*
X691900Y373200D01*
Y288601D01*
X692732Y287769D01*
Y283331D01*
X692051Y282650D01*
X691645D01*
X690048Y281053D01*
G01X646200Y499700D02*
X647400D01*
X649047Y498053D01*
Y496592D01*
X644756Y492301D01*
Y489536D01*
X651101Y483191D01*
Y459195D01*
X654126Y456170D01*
Y416874D01*
X682500Y388500D01*
Y381000D01*
X690948Y372552D01*
Y288352D01*
X691780Y287520D01*
Y283954D01*
X691428Y283602D01*
X690499D01*
X690048Y284053D01*
G01X629977Y613024D02*
X629315Y612362D01*
Y609435D01*
X623348Y603468D01*
Y531001D01*
X620452Y528105D01*
Y520395D01*
X623347Y517500D01*
Y508099D01*
X629406Y502040D01*
X647560D01*
X648025Y501575D01*
G01X627705Y611973D02*
X628455Y611223D01*
Y609922D01*
X622396Y603863D01*
Y531396D01*
X619500Y528500D01*
Y520000D01*
X622395Y517105D01*
Y507704D01*
X629011Y501088D01*
X644812D01*
X646200Y499700D01*
G01X701500Y505500D02*
X701100Y505900D01*
X655100D01*
X644419Y516581D01*
Y517480D01*
X637699Y524200D01*
X635800D01*
X630700Y529300D01*
Y578400D01*
X633100Y580800D01*
X639000D01*
X644500Y586300D01*
Y594400D01*
G01X710643Y505496D02*
X707149Y508990D01*
X702090D01*
X701037Y507937D01*
X660263D01*
X658900Y509300D01*
G01D02*
X653971D01*
X648790Y514481D01*
Y552890D01*
X657080Y561180D01*
Y576320D01*
X653630Y579770D01*
X650870D01*
X648180Y582460D01*
Y590702D01*
G01X703800Y507100D02*
X655000D01*
X647930Y514170D01*
Y553830D01*
X650330Y556230D01*
X650520D01*
X655760Y561470D01*
Y576570D01*
X653540Y578790D01*
X649340D01*
X645720Y582410D01*
Y591952D01*
X646760Y592992D01*
G01X713824Y-18333D02*
X716241Y-20750D01*
X1046613D01*
X1051479Y-15884D01*
X1266800D01*
X1271764Y-20848D01*
X1299932D01*
X1301363Y-19417D01*
Y-14780D01*
X1298700Y-12117D01*
Y19636D01*
X1299600Y20536D01*
Y52530D01*
X1296286Y55844D01*
Y67186D01*
X1301400Y72300D01*
Y75542D01*
X1304685Y78827D01*
G01X712796Y-16011D02*
X713756D01*
X717743Y-19998D01*
X1045735D01*
X1050801Y-14932D01*
X1267500D01*
X1272664Y-20096D01*
X1295704D01*
X1296744Y-19056D01*
Y-18491D01*
X1299369Y-15866D01*
Y-15680D01*
G01X701120Y19619D02*
X708019Y12720D01*
Y582D01*
X708944Y-343D01*
Y-6393D01*
X714730Y-12179D01*
X718974D01*
X725289Y-18494D01*
X1043474D01*
X1048540Y-13428D01*
X1270228D01*
X1275392Y-18592D01*
X1289008D01*
X1290300Y-17300D01*
Y-13971D01*
X1294160Y-10111D01*
Y-460D01*
X1292692Y1008D01*
G01X698470Y19669D02*
X707036Y11103D01*
Y497D01*
X708192Y-659D01*
Y-6772D01*
X714400Y-12980D01*
Y-15591D01*
X718055Y-19246D01*
X1045423D01*
X1050489Y-14180D01*
X1268826D01*
X1273990Y-19344D01*
X1295392D01*
X1295992Y-18744D01*
Y-15300D01*
X1297600Y-13692D01*
Y19600D01*
X1298550Y20550D01*
Y51950D01*
X1295534Y54966D01*
Y67734D01*
X1300600Y72800D01*
Y88522D01*
X1301219Y89141D01*
G01X697100Y90600D02*
X697700Y91200D01*
X721900D01*
X723900Y89200D01*
Y76345D01*
X727700Y72545D01*
Y63620D01*
X733513Y57807D01*
X746893D01*
X751600Y53100D01*
Y41000D01*
G01X724888Y188930D02*
X725936Y187882D01*
Y182194D01*
X732885Y175245D01*
Y96604D01*
X732164Y95883D01*
Y94577D01*
X732176Y94565D01*
Y93056D01*
X731910Y92790D01*
G01X800610Y415000D02*
Y408426D01*
X798609Y406425D01*
X777316D01*
X770633Y413108D01*
Y419257D01*
X768273Y421617D01*
X737024D01*
X718935Y403528D01*
Y384408D01*
X720714Y382629D01*
Y323298D01*
X720104Y322688D01*
Y322684D01*
X717596Y320176D01*
X717592D01*
X716312Y318896D01*
X710187D01*
X708907Y320176D01*
X705177D01*
X701720Y316719D01*
Y309644D01*
X702400Y308964D01*
Y289286D01*
X699400Y286286D01*
Y272850D01*
X707202Y265048D01*
Y261398D01*
X711998Y256602D01*
X719205D01*
X725828Y249979D01*
X726328D01*
G01X797200Y409830D02*
X797146Y409884D01*
X778749D01*
X774092Y414541D01*
Y420690D01*
X769706Y425076D01*
X735590D01*
X715531Y405017D01*
Y382998D01*
X717150Y381379D01*
Y324548D01*
X714902Y322300D01*
X711597D01*
X711314Y322583D01*
Y322584D01*
X710318Y323580D01*
X703522D01*
X698316Y318374D01*
Y308234D01*
X698946Y307604D01*
Y290646D01*
X695600Y287300D01*
Y271835D01*
X703768Y263667D01*
Y259924D01*
X710494Y253198D01*
X717795D01*
X720450Y250543D01*
Y249950D01*
G01X798500Y412600D02*
X798903Y412197D01*
Y409126D01*
X797904Y408127D01*
X778099D01*
X772390Y413836D01*
Y419985D01*
X769001Y423374D01*
X736295D01*
X717233Y404312D01*
Y383703D01*
X719012Y381924D01*
Y324003D01*
X715607Y320598D01*
X710892D01*
X709612Y321878D01*
X704228D01*
X700018Y317668D01*
Y308939D01*
X700648Y308309D01*
Y289941D01*
X697500Y286793D01*
Y272342D01*
X705470Y264372D01*
Y260640D01*
X711210Y254900D01*
X718500D01*
X723400Y250000D01*
G01X680300Y485700D02*
Y481114D01*
X714013Y447401D01*
X739933D01*
G01X675080Y485570D02*
Y481520D01*
X712604Y443996D01*
X714012D01*
X714013Y443997D01*
X728803D01*
X744112Y428688D01*
X745411Y428150D01*
X746890D01*
X747900Y429160D01*
Y431328D01*
X746151Y433077D01*
G01X746130Y430130D02*
X745961Y430299D01*
X745601D01*
X730201Y445699D01*
X713308D01*
X677800Y481207D01*
Y485600D01*
G01X676600Y501300D02*
X678200Y499700D01*
X683926D01*
X688026Y503800D01*
X716521D01*
X720131Y507410D01*
X722067D01*
X723858Y509201D01*
Y514835D01*
X728628Y519605D01*
X734141D01*
X740572Y526036D01*
X747531D01*
X751254Y529759D01*
Y535856D01*
X744562Y542548D01*
X740422D01*
X735443Y547527D01*
Y602608D01*
X736261Y603426D01*
Y613599D01*
X744291Y621629D01*
X752805D01*
X752822Y621646D01*
X1043490D01*
X1043507Y621629D01*
X1044052D01*
X1045232Y620449D01*
X1094191D01*
X1096940Y617700D01*
X1273576D01*
X1278627Y622751D01*
X1303305D01*
X1306016Y620040D01*
Y615945D01*
X1300724Y610653D01*
Y605774D01*
X1295510Y600560D01*
Y600479D01*
X1294929Y599898D01*
Y598944D01*
X1294930Y598943D01*
Y585327D01*
X1297250Y583007D01*
Y559665D01*
X1297139Y559554D01*
Y558600D01*
X1297140Y558599D01*
Y548850D01*
X1298470Y547520D01*
X1328581D01*
X1332114Y543987D01*
X1369087D01*
X1374570Y549470D01*
X1388224D01*
X1394390Y543304D01*
Y533836D01*
X1406226Y522000D01*
X1407180D01*
X1407181Y522001D01*
X1413162D01*
X1414761Y523600D01*
X1416110D01*
X1425500Y532990D01*
Y534510D01*
X1433000Y542010D01*
Y543706D01*
X1437318Y548024D01*
X1438893D01*
X1445092Y541825D01*
X1456157D01*
X1457062Y542730D01*
X1481610D01*
X1493762Y554882D01*
X1536804D01*
X1541178Y559256D01*
X1553775D01*
X1556696Y562177D01*
Y578264D01*
X1561332Y582900D01*
X1573099D01*
X1573699Y583500D01*
X1593700D01*
X1596922Y586722D01*
X1608578D01*
X1612800Y582500D01*
X1616800D01*
X1622330Y588030D01*
Y592325D01*
G01X1266162Y496404D02*
X1264523Y498043D01*
Y502413D01*
X1267196Y505086D01*
Y511157D01*
X1265747Y512606D01*
Y513394D01*
X1265748Y513395D01*
Y515495D01*
X1275395Y525142D01*
Y534872D01*
X1278993Y538470D01*
Y540657D01*
X1273872Y545778D01*
Y552292D01*
X1278632Y557052D01*
Y592089D01*
X1286171Y599628D01*
X1291208D01*
X1298820Y607240D01*
Y611443D01*
X1304112Y616735D01*
Y619250D01*
X1302515Y620847D01*
X1279417D01*
X1273957Y615387D01*
X1096243D01*
X1096241Y615385D01*
X1095645D01*
X1093380Y617650D01*
X1044878D01*
X1042848Y619680D01*
X1042762D01*
X1042700Y619742D01*
X753612D01*
X753550Y619680D01*
X753350D01*
X752000Y618330D01*
Y618130D01*
X751999Y618129D01*
Y617175D01*
X752000Y617174D01*
Y606001D01*
X747644Y601645D01*
X739135D01*
X737547Y600057D01*
Y548853D01*
X741740Y544660D01*
X745427D01*
X753158Y536929D01*
Y528969D01*
X748321Y524132D01*
X741362D01*
X734930Y517700D01*
X729570D01*
X728896Y517026D01*
Y516896D01*
X726118Y514118D01*
Y508767D01*
X722856Y505505D01*
X720920D01*
X717311Y501896D01*
X689682D01*
X685018Y497232D01*
X677092D01*
X674772Y499552D01*
X673248D01*
X671500Y501300D01*
G01X674000Y501200D02*
X674471D01*
X676923Y498748D01*
X684321D01*
X688421Y502848D01*
X716916D01*
X720526Y506458D01*
X722462D01*
X725026Y509022D01*
Y514373D01*
X727944Y517291D01*
Y517421D01*
X729175Y518652D01*
X734535D01*
X740967Y525084D01*
X747926D01*
X752206Y529364D01*
Y536534D01*
X745040Y543700D01*
X740900D01*
X736595Y548005D01*
Y602264D01*
X737240Y602909D01*
Y612945D01*
X744972Y620677D01*
X753200D01*
X753217Y620694D01*
X1043095D01*
X1043112Y620677D01*
X1043657D01*
X1045284Y619050D01*
X1093879D01*
X1096359Y616570D01*
X1273793D01*
X1279022Y621799D01*
X1302910D01*
X1305064Y619645D01*
Y616340D01*
X1299772Y611048D01*
Y606845D01*
X1291603Y598676D01*
X1286566D01*
X1279584Y591694D01*
Y556657D01*
X1275161Y552234D01*
Y545836D01*
X1279945Y541052D01*
Y538075D01*
X1276347Y534477D01*
Y524747D01*
X1266700Y515100D01*
Y513000D01*
X1268148Y511552D01*
Y506098D01*
X1273260Y500986D01*
Y497294D01*
X1271982Y496016D01*
X1269006D01*
G01X1026700Y1700D02*
X1026290Y1290D01*
Y-2600D01*
X1019674Y-9216D01*
Y-10197D01*
X1017690Y-12181D01*
X763483D01*
X763480Y-12180D01*
X756176Y-4876D01*
Y-4300D01*
G01X731210Y-15134D02*
X734720D01*
X737034Y-17448D01*
X1040922D01*
X1046000Y-12370D01*
G01X733740Y95230D02*
Y175638D01*
X726739Y182639D01*
Y187922D01*
X727628Y188811D01*
X727776D01*
G01X738648Y492050D02*
X736579Y494119D01*
Y517719D01*
X741840Y522980D01*
X748799D01*
X754310Y528491D01*
Y538850D01*
X750919Y542241D01*
Y594001D01*
X746070Y598850D01*
X739307D01*
G01X728373Y488356D02*
Y489484D01*
X728971Y490082D01*
Y492410D01*
X733398Y496837D01*
Y502638D01*
X729800Y506236D01*
Y510700D01*
X729000Y511500D01*
G01X731339Y489319D02*
X730346D01*
X729723Y489942D01*
Y492098D01*
X734150Y496525D01*
Y502950D01*
X730552Y506548D01*
Y510552D01*
X731600Y511600D01*
G01X733032Y604000D02*
X733101D01*
X734970Y605869D01*
Y615392D01*
X742359Y622781D01*
X752327D01*
X752344Y622798D01*
X1043968D01*
X1043985Y622781D01*
X1044530D01*
X1045710Y621601D01*
X1095311D01*
X1097578Y619334D01*
X1273046D01*
X1277799Y624087D01*
X1307284D01*
X1309707Y621664D01*
Y616573D01*
X1302200Y609066D01*
Y605539D01*
X1296082Y599421D01*
Y585805D01*
X1298719Y583168D01*
Y559504D01*
X1298292Y559077D01*
Y549808D01*
X1298906Y549194D01*
X1328541D01*
X1332480Y545255D01*
X1368695D01*
X1374280Y550840D01*
X1388250D01*
X1389370Y551960D01*
X1393230D01*
X1401562Y543628D01*
Y531198D01*
X1407820Y524940D01*
X1413040D01*
X1419600Y531500D01*
G01X753300Y593600D02*
X752827Y594073D01*
Y605074D01*
X753152Y605399D01*
Y617652D01*
X754090Y618590D01*
X1042222D01*
X1044444Y616368D01*
X1093032D01*
X1095167Y614233D01*
X1096719D01*
X1096721Y614235D01*
X1274435D01*
X1279895Y619695D01*
X1302037D01*
X1302960Y618772D01*
Y617213D01*
X1297668Y611921D01*
Y607718D01*
X1290730Y600780D01*
X1285693D01*
X1277480Y592567D01*
Y557530D01*
X1272720Y552770D01*
Y545180D01*
X1277200Y540700D01*
Y539100D01*
G01X1305171Y164767D02*
X1306827D01*
X1308901Y166841D01*
Y176829D01*
X1238845Y246885D01*
Y259433D01*
X1217698Y280580D01*
X1212979D01*
G01X1183605Y287965D02*
X1182417Y286777D01*
X1179939D01*
X1178750Y287966D01*
X1177448D01*
X1176259Y286777D01*
X1174068D01*
X1172119Y288726D01*
X1169802D01*
X1169428Y289100D01*
G01X1115113Y328123D02*
Y334153D01*
X1100217Y349049D01*
X1099737D01*
X1097797Y350989D01*
X1072799D01*
G01X956360Y345300D02*
Y350314D01*
G01X1310061Y165235D02*
X1309861Y165435D01*
Y176933D01*
X1239597Y247197D01*
Y259785D01*
X1218022Y281360D01*
X1211440D01*
G01X1195608Y349040D02*
X1197708Y346940D01*
X1199024D01*
X1200501Y348417D01*
X1202417D01*
X1208662Y342172D01*
X1218228D01*
X1237804Y322596D01*
Y291718D01*
X1261333Y268189D01*
Y261888D01*
X1284187Y239034D01*
X1288200D01*
X1315211Y212023D01*
X1332052D01*
X1334724Y209351D01*
Y209051D01*
G01X1143106Y347653D02*
X1143533Y347226D01*
X1144951D01*
X1146142Y348417D01*
X1148863D01*
X1150065Y347215D01*
X1150097D01*
X1150098Y347216D01*
X1152397D01*
X1152398Y347215D01*
X1152587D01*
X1153789Y348417D01*
X1155091D01*
X1158231Y345277D01*
X1164169D01*
X1167309Y348417D01*
X1169497D01*
X1170688Y347226D01*
X1171990D01*
X1173181Y348417D01*
X1175499D01*
X1177448Y350366D01*
X1178750D01*
X1180699Y348417D01*
X1182250D01*
X1184201Y346466D01*
X1186036D01*
X1187235Y345267D01*
X1189121D01*
X1190457Y346603D01*
X1192610D01*
X1194336Y344877D01*
X1195717D01*
X1197606Y342988D01*
X1199232D01*
X1200761Y344517D01*
X1204364D01*
X1207530Y341351D01*
X1217985D01*
X1237052Y322284D01*
Y291406D01*
X1260581Y267877D01*
Y261576D01*
X1283875Y238282D01*
X1287888D01*
X1319356Y206814D01*
X1335987D01*
X1338224Y209051D01*
G01X1288800Y233900D02*
X1287400Y235300D01*
X1285502D01*
X1259829Y260973D01*
Y267529D01*
X1236300Y291058D01*
Y321972D01*
X1221722Y336550D01*
X1207366D01*
X1205683Y338233D01*
G01X1263798Y133493D02*
Y129150D01*
X1264600Y128348D01*
Y123600D01*
X1264624Y123576D01*
Y121847D01*
X1267107Y119364D01*
X1269229D01*
X1271600Y116993D01*
Y106900D01*
X1273190Y105310D01*
Y65521D01*
X1263544Y55875D01*
Y43512D01*
X1271700Y35356D01*
Y-7251D01*
X1267474Y-11477D01*
X1072577D01*
X1069400Y-8300D01*
Y-3479D01*
X1071062Y-1817D01*
G01D02*
Y9120D01*
X1071064Y9122D01*
G01X1046000Y-12370D02*
X1046259Y-12629D01*
X1271029D01*
X1275100Y-16700D01*
X1285117D01*
X1286800Y-15017D01*
Y-13848D01*
X1285715Y-12763D01*
X1284393D01*
X1279000Y-7370D01*
Y34600D01*
X1283380Y38980D01*
X1294828D01*
X1296908Y36900D01*
G01X1045525Y15357D02*
X1046067Y14815D01*
Y10043D01*
X1045746Y9722D01*
Y-536D01*
X1045747Y-537D01*
Y-1427D01*
X1045867Y-1547D01*
Y-2853D01*
X1045746Y-2974D01*
Y-12116D01*
X1046000Y-12370D01*
G01X1092100Y264500D02*
X1092300Y264300D01*
X1096600D01*
X1100400Y268100D01*
X1101300D01*
X1106700Y273500D01*
X1112700D01*
X1113800Y272400D01*
X1124990D01*
X1128690Y268700D01*
X1132000D01*
X1134000Y266700D01*
X1134452D01*
X1139945Y261207D01*
X1145207D01*
G01X1089100Y264500D02*
X1090600Y266000D01*
Y268101D01*
X1092999Y270500D01*
X1093500D01*
X1100300Y277300D01*
X1104500D01*
X1106600Y279400D01*
X1111760D01*
X1112820Y278340D01*
X1115061D01*
X1117647Y280926D01*
X1120753D01*
X1124070Y277609D01*
X1125792D01*
X1126404Y278221D01*
X1127400D01*
G01X1150990Y272371D02*
X1151130D01*
G01X1092300Y267200D02*
Y267800D01*
X1100900Y276400D01*
X1105299D01*
X1107399Y278500D01*
X1111330D01*
X1112380Y277450D01*
X1116050D01*
X1118765Y280165D01*
G01X1120235D02*
X1125400Y275000D01*
X1128070D01*
X1130099Y272971D01*
X1131317D01*
X1132847Y274501D01*
X1135177D01*
X1136552Y273126D01*
X1138516D01*
X1139902Y274512D01*
X1142218D01*
X1144359Y272371D01*
G02X1145665Y271584I-59J-1575D01*
G03X1147595Y270422I2015J1163D01*
G01X1147724D01*
G02X1149045Y269634I-44J-1575D01*
G03X1150990Y268471I2015J1162D01*
G01X1151202D01*
X1154440Y268847D01*
G01X1089000Y267000D02*
Y268500D01*
X1095000Y274500D01*
Y280000D01*
X1096000Y281000D01*
X1110390D01*
X1113130Y283740D01*
X1118544D01*
X1118870Y284066D01*
X1120172D01*
X1121091Y283147D01*
Y282192D01*
X1124311Y278972D01*
G01X1164580Y274696D02*
X1160075D01*
G01X1114702Y291878D02*
Y292353D01*
X1114300Y292755D01*
Y297400D01*
X1113900Y297800D01*
G01X1095700Y265900D02*
X1099200Y269400D01*
X1101300D01*
X1106200Y274300D01*
X1114200D01*
X1115200Y273300D01*
X1125449D01*
X1128332Y270417D01*
X1135251D01*
X1137175Y268493D01*
X1138441D01*
X1140379Y266555D01*
X1141667D01*
X1143106Y265116D01*
X1144999D01*
X1146583Y266700D01*
X1148652D01*
G01X1095700Y268790D02*
X1097410Y270500D01*
X1101000D01*
X1105729Y275229D01*
X1115829D01*
X1117200Y276600D01*
X1119030D01*
X1121430Y274200D01*
X1127481D01*
X1129463Y272218D01*
X1132468D01*
X1133509Y271177D01*
X1135537D01*
X1136733Y272373D01*
X1140546D01*
X1140920Y272747D01*
G01X1107600Y271900D02*
X1109800Y269700D01*
X1114200D01*
X1115000Y270500D01*
X1117100D01*
X1118400Y269200D01*
X1120300D01*
X1121600Y270500D01*
X1125500D01*
X1128600Y267400D01*
X1131400D01*
X1133389Y265411D01*
X1134311D01*
X1142000Y257722D01*
Y255241D01*
X1144241Y253000D01*
X1144851D01*
X1146500Y251351D01*
Y250527D01*
X1147680Y249347D01*
G01X1116096Y295809D02*
Y294005D01*
G01X1344462Y209272D02*
X1341472D01*
X1337802Y205602D01*
X1319266D01*
X1295131Y229737D01*
X1289363D01*
X1259077Y260023D01*
Y266881D01*
X1234452Y291506D01*
Y309550D01*
X1218986Y325016D01*
X1200980D01*
X1199790Y323826D01*
X1196968D01*
X1195096Y325698D01*
X1193538D01*
X1192270Y326966D01*
X1191670D01*
X1188959Y329677D01*
X1187588D01*
X1186125Y331140D01*
X1183807D01*
X1182130Y332817D01*
X1181323D01*
X1179374Y334766D01*
X1176906D01*
X1175717Y333577D01*
X1173623D01*
X1172434Y334766D01*
X1170066D01*
X1168877Y333577D01*
X1166723D01*
X1165534Y334766D01*
X1163466D01*
X1162277Y333577D01*
X1159923D01*
X1158734Y334766D01*
X1156280D01*
X1155091Y333577D01*
X1153789D01*
X1152600Y334766D01*
X1149866D01*
X1148677Y333577D01*
X1146223D01*
X1145034Y334766D01*
X1143466D01*
X1142277Y333577D01*
X1139623D01*
X1138434Y334766D01*
X1136266D01*
X1134690Y333190D01*
X1133882D01*
X1130780Y330088D01*
Y329296D01*
G01X1144300Y317596D02*
X1146061D01*
X1148248Y318031D01*
X1149256Y318448D01*
X1149884Y319076D01*
X1150477Y319322D01*
X1151489D01*
X1152249Y319007D01*
X1152758Y318498D01*
X1154033Y317970D01*
X1154824D01*
X1156224Y318550D01*
X1156469Y318795D01*
X1157419Y319188D01*
X1158184D01*
X1158914Y318886D01*
X1159154Y318646D01*
X1160789Y317969D01*
X1161631D01*
X1162697Y318411D01*
X1162964Y318678D01*
X1164278Y319222D01*
X1164888D01*
X1165738Y318870D01*
X1165983Y318625D01*
G01X1169835Y318603D02*
X1170050Y318818D01*
X1170998Y319211D01*
X1171687D01*
X1172660Y318808D01*
X1172987Y318481D01*
X1174264Y317952D01*
X1175062D01*
X1176346Y318484D01*
X1177114Y319252D01*
X1178259D01*
X1180468Y318337D01*
X1180757Y318048D01*
X1182166Y317464D01*
X1182958Y316672D01*
X1184000Y316240D01*
X1185212Y315738D01*
X1186417Y314533D01*
X1189518Y313248D01*
X1190514Y312252D01*
X1192614Y311382D01*
X1193293Y310703D01*
X1194563Y310177D01*
X1195529D01*
X1196357Y310520D01*
X1197238Y311401D01*
X1230971D01*
X1233300Y309072D01*
Y290964D01*
X1257925Y266339D01*
Y259026D01*
X1283720Y233231D01*
Y223870D01*
G01X1300300Y169900D02*
X1293870Y176330D01*
X1258830D01*
X1252888Y170388D01*
X1239429D01*
X1232967Y176850D01*
X1226200D01*
X1224688Y178362D01*
Y221489D01*
X1227362Y224163D01*
Y248738D01*
X1212059Y264041D01*
Y265206D01*
X1209993Y267272D01*
G01X1223100Y178180D02*
Y223163D01*
X1226100Y226163D01*
Y247677D01*
X1210897Y262880D01*
G01X1267959Y47245D02*
X1273266D01*
X1274148Y46363D01*
Y-5778D01*
X1282252Y-13882D01*
Y-14747D01*
G01X1268111Y58040D02*
X1268149D01*
X1268686Y57503D01*
X1269670D01*
X1271900Y55273D01*
Y50500D01*
X1275300Y47100D01*
Y-5300D01*
X1284524Y-14524D01*
X1284859D01*
G01X1260737Y133877D02*
X1262030Y135170D01*
X1266430D01*
X1273200Y128400D01*
Y107700D01*
X1285200Y95700D01*
X1290400D01*
X1296400Y89700D01*
Y76022D01*
X1298422Y74000D01*
G01X1327900Y142918D02*
Y146556D01*
X1324630Y149826D01*
X1312719D01*
X1311197Y148304D01*
X1306584D01*
X1300695Y142415D01*
X1292659D01*
X1282226Y152848D01*
X1274838D01*
X1269979Y157707D01*
X1265300D01*
X1262566Y154973D01*
X1261800D01*
G01X1287790Y156575D02*
X1301453D01*
X1303518Y158640D01*
Y165417D01*
X1305622Y167521D01*
X1306804D01*
X1307985Y168702D01*
Y175263D01*
X1305188Y178060D01*
X1252050D01*
X1250385Y176395D01*
X1246655D01*
G01X1277978Y491571D02*
X1277987D01*
Y491562D01*
X1277019D01*
X1276787Y491330D01*
X1262330D01*
X1257600Y496060D01*
Y504870D01*
X1260130Y507400D01*
Y523330D01*
X1261690Y524890D01*
X1267453D01*
X1271500Y528937D01*
Y553120D01*
X1276170Y557790D01*
Y592321D01*
X1285381Y601532D01*
X1290332D01*
X1296916Y608116D01*
Y612233D01*
X1297680Y612997D01*
Y614211D01*
X1296295Y615596D01*
G01X1255120Y555144D02*
X1253500Y553524D01*
Y519620D01*
X1255120Y518000D01*
G01Y537034D02*
X1256696Y535458D01*
Y511734D01*
X1255120Y510158D01*
G01X1271300Y510600D02*
X1272043D01*
X1273791Y512348D01*
X1278158D01*
X1284405Y506101D01*
X1293231D01*
X1293738Y506608D01*
X1299760D01*
X1303652Y510500D01*
X1322500D01*
X1328400Y504600D01*
X1336082D01*
X1337821Y506339D01*
X1356539D01*
X1357950Y507750D01*
X1370124D01*
X1371630Y509256D01*
X1397979D01*
X1398831Y508404D01*
X1416496D01*
X1422850Y514758D01*
Y522820D01*
X1430720Y530690D01*
X1432090D01*
X1435598Y534198D01*
Y542098D01*
X1438794Y545294D01*
X1439123D01*
G01X1274576Y510235D02*
X1274987Y510646D01*
X1277453D01*
X1283700Y504399D01*
X1293936D01*
X1294443Y504906D01*
X1300527D01*
X1304011Y508390D01*
X1321637D01*
X1327129Y502898D01*
X1336787D01*
X1338526Y504637D01*
X1357436D01*
X1358847Y506048D01*
X1370829D01*
X1372335Y507554D01*
X1397273D01*
X1398125Y506702D01*
X1417202D01*
X1417494Y506994D01*
Y506995D01*
X1425130Y514631D01*
Y522390D01*
X1431728Y528988D01*
X1432795D01*
X1437300Y533493D01*
Y541393D01*
X1438692Y542785D01*
X1438799D01*
G01X1262843Y497553D02*
Y496791D01*
X1265904Y493730D01*
X1271993D01*
X1278080Y499817D01*
X1294381D01*
X1295916Y501352D01*
X1303052D01*
X1306196Y504496D01*
X1319533D01*
X1327329Y496700D01*
X1337300D01*
X1338700Y498100D01*
Y499200D01*
X1340583Y501083D01*
X1359182D01*
X1360589Y502490D01*
X1372300D01*
X1373810Y504000D01*
X1395800D01*
X1396652Y503148D01*
X1419848D01*
X1434500Y517800D01*
Y525514D01*
X1442010Y533024D01*
Y537489D01*
X1445140Y540619D01*
X1456579D01*
X1456633Y540673D01*
X1456635D01*
X1457538Y541576D01*
X1482343D01*
X1494497Y553730D01*
X1537282D01*
X1541656Y558104D01*
X1564604D01*
X1568800Y562300D01*
Y576900D01*
X1574213Y582313D01*
X1594733D01*
X1597520Y585100D01*
X1607300D01*
X1611400Y581000D01*
X1617400D01*
X1625500Y589100D01*
Y591700D01*
X1620150Y597050D01*
Y614120D01*
X1625778Y619748D01*
X1692222D01*
X1698448Y613522D01*
Y590048D01*
X1696300Y587900D01*
Y578350D01*
X1698850Y575800D01*
X1722510D01*
X1724093Y577383D01*
X1733884D01*
X1740001Y583500D01*
X1742924D01*
X1761054Y601630D01*
X1766770D01*
X1769490Y598910D01*
X1773700D01*
X1778240Y603450D01*
X1787050D01*
X1800500Y590000D01*
X1827935D01*
X1829909Y588026D01*
Y587876D01*
X1834703Y583082D01*
Y582153D01*
X1837534Y579322D01*
G01X1255120Y593600D02*
X1253500Y591980D01*
Y556764D01*
X1255120Y555144D01*
G01Y574834D02*
X1256696Y573258D01*
Y538610D01*
X1255120Y537034D01*
G01X1277137Y547393D02*
X1278643D01*
X1279474Y548224D01*
X1281075D01*
X1284747Y544552D01*
X1290905D01*
X1294148Y547795D01*
Y577852D01*
X1293290Y578710D01*
Y581160D01*
G01X1279318Y545212D02*
Y546720D01*
X1279870Y547272D01*
X1280928D01*
X1284600Y543600D01*
X1291300D01*
X1295090Y547390D01*
Y579360D01*
G01X1301384Y618119D02*
X1283119D01*
X1277350Y612350D01*
Y600550D01*
X1270400Y593600D01*
G01X1410600Y9100D02*
X1408900Y7400D01*
X1397502D01*
X1391214Y1112D01*
Y-15662D01*
X1385245Y-21631D01*
X1306039D01*
X1303774Y-19366D01*
Y-18842D01*
G01X1355500Y83000D02*
Y81756D01*
X1355148Y81404D01*
X1342576D01*
X1335680Y88300D01*
X1324800D01*
X1307000Y106100D01*
Y126000D01*
X1312500Y131500D01*
X1324203D01*
X1326026Y133323D01*
G01X1359500Y83000D02*
X1358120D01*
X1355372Y80252D01*
X1342098D01*
X1335450Y86900D01*
X1324500D01*
X1306048Y105352D01*
Y126598D01*
X1311950Y132500D01*
X1322203D01*
X1323026Y133323D01*
G01X1362000Y209300D02*
Y204629D01*
X1342584Y185213D01*
Y142976D01*
X1337468Y137860D01*
X1330530D01*
X1329919Y137249D01*
X1325563D01*
X1324952Y137860D01*
X1308415D01*
X1299605Y129050D01*
Y116991D01*
X1296682Y114068D01*
Y103818D01*
X1315448Y85052D01*
Y83832D01*
X1317456Y81824D01*
X1318276D01*
X1319848Y80252D01*
X1327889D01*
X1327890Y80253D01*
X1329658D01*
X1333054Y76857D01*
Y70354D01*
X1328000Y65300D01*
X1327500D01*
G01X1356926Y209100D02*
Y204548D01*
X1333315Y180937D01*
Y179648D01*
X1333667Y179296D01*
X1335448D01*
X1335800Y178944D01*
Y178240D01*
X1335448Y177888D01*
X1333667D01*
X1333315Y177536D01*
Y176832D01*
X1333667Y176480D01*
X1335448D01*
X1335800Y176128D01*
Y175424D01*
X1335448Y175072D01*
X1333667D01*
X1333315Y174720D01*
Y174016D01*
X1333667Y173664D01*
X1335448D01*
X1335800Y173312D01*
Y172608D01*
X1335448Y172256D01*
X1333667D01*
X1333315Y171904D01*
Y145459D01*
X1328509Y140653D01*
X1326973D01*
X1326362Y141264D01*
X1307005D01*
X1296200Y130459D01*
Y118400D01*
X1293278Y115478D01*
Y102408D01*
X1312043Y83643D01*
Y82423D01*
X1316046Y78420D01*
X1316866D01*
X1318496Y76790D01*
X1328244D01*
X1329552Y75482D01*
Y72871D01*
X1327467Y70786D01*
G01X1359500Y209200D02*
Y204550D01*
X1337659Y182709D01*
Y142572D01*
X1334649Y139562D01*
X1329825D01*
X1329214Y138951D01*
X1326268D01*
X1325657Y139562D01*
X1307710D01*
X1297903Y129755D01*
Y117696D01*
X1294980Y114773D01*
Y103113D01*
X1313746Y84347D01*
Y83127D01*
X1316751Y80122D01*
X1317571D01*
X1319143Y78550D01*
X1328891D01*
X1331254Y76187D01*
Y71054D01*
X1328200Y68000D01*
X1327500D01*
G01X1317195Y87098D02*
X1314690Y89603D01*
Y94880D01*
X1304896Y104674D01*
Y127076D01*
X1305600Y127780D01*
Y127850D01*
X1313758Y136008D01*
X1324184D01*
X1324795Y135397D01*
X1330687D01*
X1331190Y135900D01*
X1372400D01*
X1375100Y133200D01*
X1396599D01*
X1399400Y130399D01*
Y126400D01*
G01X1584000Y-16100D02*
X1574108Y-6208D01*
X1570638D01*
X1567250Y-2820D01*
X1505020D01*
X1502272Y-72D01*
X1481772D01*
X1479464Y2236D01*
Y7693D01*
X1479417Y7740D01*
Y8038D01*
X1479400Y8055D01*
Y8393D01*
X1469314Y18479D01*
X1462059D01*
X1452891Y27647D01*
X1413701D01*
X1403640Y37708D01*
Y47370D01*
X1404970Y48700D01*
Y75631D01*
X1400427Y80174D01*
Y91834D01*
X1399514Y92747D01*
X1389638D01*
X1387681Y90790D01*
Y83183D01*
X1386284Y81786D01*
X1374131D01*
X1371317Y84600D01*
X1364000D01*
X1358500Y79100D01*
X1340800D01*
X1334600Y85300D01*
X1322600D01*
X1320976Y83676D01*
X1318224D01*
X1317300Y84600D01*
G01X1487367Y465256D02*
Y464223D01*
X1487764Y463826D01*
X1489475D01*
G01X1486123Y465436D02*
X1486615Y464944D01*
Y464099D01*
X1486206Y463690D01*
X1485030D01*
G01X1390100Y457500D02*
Y455678D01*
X1397430Y448348D01*
Y426840D01*
X1392586Y421996D01*
X1349660D01*
X1340116Y412452D01*
Y412451D01*
X1339120Y411455D01*
X1318743D01*
X1315157Y415041D01*
Y415048D01*
X1315118Y415087D01*
Y419606D01*
X1315157Y419645D01*
Y419737D01*
X1316820Y421400D01*
G01X1319320Y418900D02*
Y415792D01*
X1320253Y414859D01*
X1337709D01*
X1348250Y425400D01*
X1385750D01*
X1388100Y427750D01*
Y450500D01*
X1390100Y452500D01*
G01X1316820Y418900D02*
Y415792D01*
X1319455Y413157D01*
X1338414D01*
X1348955Y423698D01*
X1389497D01*
X1392165Y426366D01*
Y444565D01*
X1395100Y447500D01*
G01X1439822Y537382D02*
X1439003Y536563D01*
Y532789D01*
X1433499Y527285D01*
X1432556D01*
X1426832Y521561D01*
Y513632D01*
X1418200Y505000D01*
X1397420D01*
X1396568Y505852D01*
X1373042D01*
X1371532Y504342D01*
X1359641D01*
X1358234Y502935D01*
X1339231D01*
X1337492Y501196D01*
X1326424D01*
X1321120Y506500D01*
X1305550D01*
X1302254Y503204D01*
X1295148D01*
X1294252Y502308D01*
X1288919D01*
X1288508Y501897D01*
X1287770D01*
G01X1341050Y498275D02*
X1342706Y499931D01*
X1359832D01*
X1361239Y501338D01*
X1372778D01*
X1374288Y502848D01*
X1395322D01*
X1396174Y501996D01*
X1421296D01*
X1437473Y518173D01*
Y524027D01*
X1436358Y525142D01*
G01X1327956Y545655D02*
X1331490Y542121D01*
X1340533D01*
X1349864Y532790D01*
X1368900D01*
X1370850Y530840D01*
X1395756D01*
X1407884Y518712D01*
Y512751D01*
G01X1344761Y498282D02*
X1344943Y498100D01*
X1359084D01*
X1361570Y500586D01*
X1373090D01*
X1374256Y501752D01*
X1395354D01*
X1395862Y501244D01*
X1439856D01*
X1449884Y491216D01*
Y487592D01*
X1449568Y487276D01*
G01X1540477Y620308D02*
X1537930D01*
X1534238Y624000D01*
X1467500D01*
X1464127Y620627D01*
X1446266D01*
X1438459Y612820D01*
Y593279D01*
X1442533Y589205D01*
Y585791D01*
X1453613Y574711D01*
Y567783D01*
X1451760Y565930D01*
X1442842D01*
X1439833Y562921D01*
Y555108D01*
X1421176Y536451D01*
Y530847D01*
X1420253Y529924D01*
X1419088D01*
X1413352Y524188D01*
X1406732D01*
X1400810Y530110D01*
Y534191D01*
X1398145Y536856D01*
Y545981D01*
X1394798Y549328D01*
X1390595D01*
G01X1454902Y273603D02*
X1456500Y272005D01*
Y264980D01*
X1459547Y261933D01*
X1482143D01*
X1487287Y256789D01*
Y253909D01*
X1493894Y247302D01*
Y223812D01*
X1494942Y222764D01*
Y221247D01*
X1494941Y221246D01*
Y220624D01*
X1495337Y220228D01*
Y184285D01*
X1503290Y176332D01*
Y166730D01*
X1504706Y165314D01*
Y164871D01*
G01X1725474Y69250D02*
Y70748D01*
X1722234Y73988D01*
X1705578D01*
X1702937Y76629D01*
X1701043D01*
X1697905Y79767D01*
X1682220D01*
X1678778Y83209D01*
X1666303D01*
X1659736Y89776D01*
X1658924D01*
X1656059Y92641D01*
X1631405D01*
X1622046Y102000D01*
X1611779D01*
X1610063Y103716D01*
X1602105D01*
X1602104Y103715D01*
X1601946D01*
X1600899Y102668D01*
X1600654D01*
X1600653Y102667D01*
X1599347D01*
X1599346Y102668D01*
X1597932D01*
X1596766Y103834D01*
X1592133D01*
X1590814Y105153D01*
X1587200D01*
X1586385Y105968D01*
X1575953D01*
X1575476Y105491D01*
X1557536D01*
X1556527Y106500D01*
X1544783D01*
X1542383Y108900D01*
X1531872D01*
X1529122Y111650D01*
X1526993D01*
X1525788Y110445D01*
X1522969D01*
X1519630Y113784D01*
Y125420D01*
X1515900Y129150D01*
Y133150D01*
X1516578Y133828D01*
Y139619D01*
X1511781Y144416D01*
X1510045D01*
X1504353Y150108D01*
X1499294D01*
X1498315Y151087D01*
Y159476D01*
X1500436Y161597D01*
Y163128D01*
X1499864Y163700D01*
Y177630D01*
X1493833Y183661D01*
Y219604D01*
X1493127Y220310D01*
Y221874D01*
X1489372Y225629D01*
Y248510D01*
X1488390Y249492D01*
X1484794D01*
X1484006Y250280D01*
X1483979D01*
X1483105Y251154D01*
Y254808D01*
X1478285Y259628D01*
X1471055D01*
X1469327Y257900D01*
X1455800D01*
X1454000Y259700D01*
G01X1494939Y159500D02*
X1493585D01*
X1485100Y167985D01*
Y211399D01*
X1478118Y218381D01*
Y229335D01*
X1463481Y243972D01*
Y245044D01*
X1455275Y253250D01*
X1454947D01*
X1454024Y254173D01*
Y255676D01*
X1453400Y256300D01*
X1452500D01*
X1448100Y260700D01*
Y264799D01*
X1447107Y265792D01*
Y315123D01*
X1447133Y315149D01*
Y315155D01*
X1448603Y316625D01*
Y317696D01*
G01X1461300Y270400D02*
X1462964Y268736D01*
Y265689D01*
X1465014Y263639D01*
X1482640D01*
X1488791Y257488D01*
Y255289D01*
X1495398Y248682D01*
Y224436D01*
X1496446Y223388D01*
Y221247D01*
X1498823Y218870D01*
Y216500D01*
X1496651Y214328D01*
Y184035D01*
X1505072Y175614D01*
Y166734D01*
X1506282Y165524D01*
Y164032D01*
X1500703Y158453D01*
Y158233D01*
G01X1520150Y127600D02*
X1518650D01*
X1516850Y129400D01*
Y132300D01*
X1517330Y132780D01*
Y139932D01*
X1512094Y145168D01*
X1510357D01*
X1504664Y150861D01*
X1499605D01*
X1499067Y151399D01*
Y159164D01*
X1501189Y161286D01*
Y163645D01*
X1500616Y164218D01*
Y177942D01*
X1494585Y183973D01*
Y219916D01*
X1494189Y220312D01*
Y221558D01*
X1494190Y221559D01*
Y222452D01*
X1492841Y223801D01*
Y238291D01*
X1490124Y241008D01*
Y248822D01*
X1484500Y254446D01*
X1484478Y254499D01*
X1478597Y260380D01*
X1469911D01*
X1468260Y258729D01*
X1460450D01*
X1454056Y265123D01*
Y266169D01*
G01X1454902Y301948D02*
Y300998D01*
X1456372Y299528D01*
Y288742D01*
X1455302Y287672D01*
X1454293D01*
X1453432Y286811D01*
Y276144D01*
X1454311Y275265D01*
X1455319D01*
X1456395Y274189D01*
Y273181D01*
X1457443Y272133D01*
X1458450D01*
X1459572Y271011D01*
Y263645D01*
X1460408Y262809D01*
X1482367D01*
X1488039Y257137D01*
Y254221D01*
X1494646Y247614D01*
Y224124D01*
X1495694Y223076D01*
Y220935D01*
X1497237Y219392D01*
Y217281D01*
G01X1677573Y86930D02*
X1677098D01*
X1674123Y89905D01*
X1668507D01*
X1664196Y94216D01*
X1660998D01*
X1660023Y93241D01*
X1658558D01*
X1655050Y96749D01*
X1645601D01*
X1640989Y101361D01*
X1627465D01*
X1625885Y102941D01*
X1612126D01*
X1610514Y104553D01*
X1602069D01*
X1600803Y105819D01*
X1599100D01*
X1597974Y104693D01*
X1592824D01*
X1589153Y108364D01*
X1585128D01*
X1584016Y107252D01*
X1563037D01*
X1561409Y108880D01*
X1543467D01*
X1542499Y109848D01*
X1531988D01*
X1529434Y112402D01*
X1526681D01*
X1525476Y111197D01*
X1523631D01*
X1520600Y114228D01*
Y124100D01*
X1521800Y125300D01*
Y130035D01*
X1518082Y133753D01*
Y140244D01*
X1505824Y152502D01*
Y161119D01*
X1507034Y162329D01*
Y165836D01*
X1506500Y166370D01*
Y175250D01*
X1497471Y184279D01*
Y184901D01*
X1497472Y184902D01*
Y200605D01*
X1499597Y202730D01*
Y216721D01*
X1499598Y216722D01*
Y223399D01*
X1500261Y224062D01*
Y225368D01*
X1496150Y229479D01*
Y249263D01*
X1489565Y255848D01*
Y260547D01*
X1485375Y264737D01*
X1469312D01*
X1462179Y271870D01*
X1460856D01*
X1459700Y273026D01*
Y280333D01*
X1458661Y281372D01*
X1457651D01*
X1456500Y282523D01*
Y284604D01*
X1454902Y286202D01*
G01X1464351Y276753D02*
X1466029Y275075D01*
Y270254D01*
X1467904Y268379D01*
X1470438D01*
X1473225Y265592D01*
X1485584D01*
X1489032Y262144D01*
X1495349D01*
X1495351Y262142D01*
X1496305D01*
X1496306Y262143D01*
X1496357D01*
X1500863Y257637D01*
Y254527D01*
X1496902Y250566D01*
Y229791D01*
X1501013Y225680D01*
Y223750D01*
X1500384Y223121D01*
Y202372D01*
X1498224Y200212D01*
Y184590D01*
X1507299Y175515D01*
Y166635D01*
X1507786Y166148D01*
Y162017D01*
X1506576Y160807D01*
Y152814D01*
X1518835Y140555D01*
Y139933D01*
X1518834Y139932D01*
Y134065D01*
X1522552Y130347D01*
Y126712D01*
X1522553Y126711D01*
Y126089D01*
X1522552Y126088D01*
Y124988D01*
X1521740Y124176D01*
Y115317D01*
X1524284Y112773D01*
G01X1451753Y298798D02*
X1450100Y297145D01*
Y264554D01*
X1449422Y263876D01*
Y260442D01*
X1452812Y257052D01*
X1455707D01*
X1457224Y255535D01*
Y252576D01*
X1464444Y245356D01*
Y244716D01*
X1479759Y229401D01*
Y224801D01*
X1479700D01*
G01X1445427Y292526D02*
X1443900Y294053D01*
Y312647D01*
X1445746Y314493D01*
Y315782D01*
X1446998Y317034D01*
Y318848D01*
X1448329Y320179D01*
X1455028D01*
X1469649Y334800D01*
X1472500D01*
G01X1499225Y391034D02*
X1497590Y392669D01*
X1488780D01*
X1487320Y391209D01*
Y389969D01*
X1482996Y385645D01*
X1481392D01*
X1480199Y384452D01*
Y377298D01*
X1473217Y370316D01*
X1472341D01*
X1469378Y367353D01*
Y349304D01*
X1474175Y344507D01*
Y333508D01*
X1473561Y332894D01*
X1469409D01*
X1455708Y319193D01*
X1453250D01*
X1451753Y317696D01*
G01X1485909Y384885D02*
X1485152Y384128D01*
Y382217D01*
X1485153Y382216D01*
Y380953D01*
X1483352Y379152D01*
Y377979D01*
X1483351Y377978D01*
Y377850D01*
X1474314Y368813D01*
X1472964D01*
X1471048Y366897D01*
Y352250D01*
X1477727Y345571D01*
Y334038D01*
X1470529Y326840D01*
X1466755D01*
X1460300Y320385D01*
Y317867D01*
X1458483Y316050D01*
X1457477D01*
X1456450Y315023D01*
Y314015D01*
X1455485Y313050D01*
X1454476D01*
X1453432Y312006D01*
Y307638D01*
X1454293Y306777D01*
X1455419D01*
X1456582Y305614D01*
Y304489D01*
X1456598Y304473D01*
Y302575D01*
X1456581Y302558D01*
Y301340D01*
X1456598Y301323D01*
Y301263D01*
X1457517Y300344D01*
X1458915D01*
X1459675Y299584D01*
Y293055D01*
X1461819Y290911D01*
X1464870D01*
X1468000Y287781D01*
Y277323D01*
X1470073Y275250D01*
X1478451D01*
X1480098Y273603D01*
G01X1458052Y308247D02*
X1461853D01*
X1462900Y307200D01*
Y305726D01*
X1462881Y305707D01*
Y304489D01*
X1462900Y304470D01*
Y302576D01*
X1462881Y302557D01*
Y301339D01*
X1462900Y301320D01*
Y301100D01*
X1463600Y300400D01*
X1465600D01*
X1466400Y299600D01*
Y294900D01*
X1468700Y292600D01*
X1476700D01*
X1478700Y290600D01*
Y286883D01*
X1478628Y286811D01*
Y279972D01*
X1479300Y279300D01*
X1479900D01*
X1481200Y278000D01*
Y277730D01*
X1481568Y277362D01*
Y275632D01*
X1481917Y275283D01*
X1486938D01*
X1494267Y267954D01*
Y267333D01*
X1494600Y267000D01*
X1494616D01*
X1496216Y265400D01*
X1500948D01*
X1506488Y259860D01*
Y258588D01*
X1504300Y256400D01*
Y251000D01*
X1501000Y247700D01*
Y236500D01*
X1503317Y234183D01*
Y222794D01*
X1502688Y222165D01*
Y202646D01*
X1503433Y201901D01*
Y182827D01*
X1510638Y175622D01*
Y166240D01*
G01X1540175Y387654D02*
Y383625D01*
X1542100Y381700D01*
Y379801D01*
X1539979Y377680D01*
Y376287D01*
X1539602Y375910D01*
X1485410D01*
X1476110Y366610D01*
Y364736D01*
X1475330Y363956D01*
Y351274D01*
X1479983Y346621D01*
Y323785D01*
X1474698Y318500D01*
X1470285D01*
X1466349Y314564D01*
Y303946D01*
X1464351Y301948D01*
G01X1547975Y387654D02*
X1546405Y386084D01*
X1543424D01*
X1542400Y387108D01*
Y387650D01*
X1540826Y389224D01*
X1539524D01*
X1538100Y387800D01*
Y387000D01*
X1536655Y385555D01*
Y384355D01*
X1534300Y382000D01*
Y380598D01*
X1533026Y379324D01*
X1486824D01*
X1484854Y377354D01*
Y376689D01*
X1475476Y367311D01*
X1473588D01*
X1472880Y366603D01*
Y352660D01*
X1479231Y346309D01*
Y329183D01*
X1471826Y321778D01*
Y321127D01*
X1470903Y320204D01*
X1469740D01*
X1462436Y312900D01*
X1459555D01*
X1458052Y311397D01*
G01X1536275Y387654D02*
X1534465Y385844D01*
X1533674D01*
X1532755Y384925D01*
Y384383D01*
X1530872Y382500D01*
X1488311D01*
X1484103Y378292D01*
Y377203D01*
X1474962Y368062D01*
X1473276D01*
X1472128Y366914D01*
Y352348D01*
X1478479Y345997D01*
Y330028D01*
X1471956Y323505D01*
X1469604D01*
X1469498Y323399D01*
X1469097D01*
X1469052Y323354D01*
X1467868D01*
X1465400Y320886D01*
Y318745D01*
X1462671Y316016D01*
X1460593D01*
X1459522Y314945D01*
Y313937D01*
X1458452Y312867D01*
X1457443D01*
X1456582Y312006D01*
Y307168D01*
X1456973Y306777D01*
X1458909D01*
X1459664Y306022D01*
Y301169D01*
X1460513Y300320D01*
X1462120D01*
X1462763Y299677D01*
Y294105D01*
X1463813Y293055D01*
X1464634D01*
X1468751Y288938D01*
Y288094D01*
X1468752Y288093D01*
Y279720D01*
X1470120Y278352D01*
X1472199D01*
X1473798Y276753D01*
G01X1485156Y385196D02*
X1484400Y384440D01*
Y381799D01*
X1482601Y380000D01*
Y378500D01*
X1473665Y369564D01*
X1472652D01*
X1470130Y367042D01*
Y350974D01*
X1475908Y345196D01*
Y334177D01*
X1470929Y329198D01*
X1466777D01*
X1457326Y319747D01*
X1457325D01*
X1456607Y319029D01*
Y317323D01*
X1455384Y316100D01*
X1454377D01*
X1453223Y314946D01*
Y313937D01*
X1452153Y312867D01*
X1451144D01*
X1450283Y312006D01*
Y301339D01*
X1451144Y300478D01*
X1453222D01*
X1454902Y298798D01*
G01X1491425Y446926D02*
X1490974D01*
X1489900Y448000D01*
X1480100D01*
X1474775Y442675D01*
X1458300D01*
G01X1438390Y527175D02*
X1439505Y526060D01*
Y502811D01*
X1452000Y490316D01*
Y487411D01*
X1452188Y487223D01*
G01X1441409Y561117D02*
X1443844Y558682D01*
Y545260D01*
X1446327Y542777D01*
X1455407D01*
X1456350Y543720D01*
X1481080D01*
X1493194Y555834D01*
X1536409D01*
X1540783Y560208D01*
X1553380D01*
X1555744Y562572D01*
Y578659D01*
X1560947Y583862D01*
X1569595D01*
X1573233Y587500D01*
X1592399D01*
X1596500Y591601D01*
Y618950D01*
X1599050Y621500D01*
X1692100D01*
X1699600Y614000D01*
Y600041D01*
X1700176Y599465D01*
Y578676D01*
X1699600Y578100D01*
G01X1520100Y3500D02*
X1522300D01*
X1523900Y5100D01*
X1528229D01*
X1529224Y4105D01*
Y2847D01*
X1530367Y1704D01*
X1575796D01*
X1579700Y-2200D01*
X1593500D01*
X1598152Y-6852D01*
X1656102D01*
X1662178Y-776D01*
X1674603D01*
X1677376Y1997D01*
Y4351D01*
X1679335Y6310D01*
X1736413D01*
X1738748Y8645D01*
Y10245D01*
X1740805Y12302D01*
X1773463D01*
X1782143Y3622D01*
X1795591D01*
X1796221Y4252D01*
X1809890D01*
X1812691Y7053D01*
X1817854D01*
X1820120Y9319D01*
Y10423D01*
X1821171Y11474D01*
Y15188D01*
X1815150Y21209D01*
Y26650D01*
G01X1516900Y3500D02*
X1520600Y-200D01*
X1529706D01*
X1529707Y-201D01*
X1531285D01*
X1531286Y-200D01*
X1567701D01*
X1571605Y-4104D01*
X1592710D01*
X1597362Y-8756D01*
X1656892D01*
X1662968Y-2680D01*
X1675393D01*
X1676949Y-1124D01*
X1801524D01*
X1803476Y-3076D01*
X1805623D01*
X1807475Y-1224D01*
X1826130D01*
X1827100Y-254D01*
Y6100D01*
X1828312Y7312D01*
Y13594D01*
X1833309Y18591D01*
X1838249D01*
X1841289Y21631D01*
G01X1514400Y3500D02*
X1519568Y-1668D01*
X1567728D01*
X1571116Y-5056D01*
X1592315D01*
X1596967Y-9708D01*
X1598467D01*
X1598468Y-9709D01*
X1599256D01*
X1599257Y-9708D01*
X1657287D01*
X1663363Y-3632D01*
X1676697D01*
X1682065Y-9000D01*
X1823701D01*
X1829096Y-3605D01*
Y-510D01*
X1830452Y846D01*
Y9749D01*
X1829900Y10301D01*
Y10735D01*
X1829888D01*
G01X1843426Y9528D02*
X1841250Y7452D01*
X1834476D01*
X1832571Y5547D01*
Y5518D01*
X1832570Y5517D01*
Y4729D01*
X1832571Y4728D01*
Y271D01*
X1831000Y-1300D01*
Y-4400D01*
X1824448Y-10952D01*
X1681323D01*
X1675907Y-5536D01*
X1664153D01*
X1650973Y-18716D01*
X1650337D01*
X1650336Y-18717D01*
X1649548D01*
X1649547Y-18716D01*
X1616369D01*
X1611905Y-14252D01*
X1594695D01*
X1589219Y-19728D01*
X1570881D01*
X1568948Y-17795D01*
Y-7495D01*
X1566377Y-4924D01*
X1507976D01*
X1506300Y-6600D01*
G01X1849027Y34426D02*
X1846674Y32073D01*
X1846573D01*
X1843256Y28756D01*
Y21249D01*
X1834476Y12469D01*
Y9647D01*
X1831500Y6671D01*
Y547D01*
X1830048Y-905D01*
Y-4005D01*
X1824053Y-10000D01*
X1681718D01*
X1676302Y-4584D01*
X1663758D01*
X1650578Y-17764D01*
X1616764D01*
X1612300Y-13300D01*
X1594300D01*
X1588824Y-18776D01*
X1571276D01*
X1569900Y-17400D01*
Y-7100D01*
X1566772Y-3972D01*
X1504172D01*
X1501424Y-1224D01*
X1485776D01*
X1482000Y-5000D01*
G01X1511100Y186275D02*
X1518845Y178530D01*
Y158771D01*
X1529009Y148607D01*
Y145618D01*
X1536071Y138556D01*
Y135328D01*
X1541399Y130000D01*
X1544000D01*
X1546000Y128000D01*
X1552099D01*
X1555676Y124423D01*
Y123283D01*
G01X1553500Y121000D02*
X1553149Y121351D01*
X1549649D01*
X1542925Y128075D01*
X1541624D01*
X1541623Y128076D01*
X1541159D01*
X1534567Y134668D01*
Y137932D01*
X1527505Y144994D01*
Y147983D01*
X1517189Y158299D01*
Y176372D01*
X1508772Y184789D01*
Y189031D01*
X1512348Y192607D01*
Y192649D01*
X1512438Y192739D01*
Y196399D01*
X1509575Y199262D01*
Y211325D01*
X1510370Y212120D01*
Y219811D01*
X1508707Y221474D01*
Y243367D01*
X1508074Y244000D01*
Y247704D01*
X1511448Y251078D01*
Y270099D01*
X1501500Y280047D01*
Y280161D01*
X1501499Y280162D01*
Y281116D01*
X1501500Y281117D01*
Y284429D01*
X1503371Y286300D01*
Y289767D01*
X1505082Y291478D01*
Y298206D01*
X1501004Y302284D01*
Y307684D01*
X1499717Y308971D01*
Y313337D01*
X1495509Y317545D01*
Y332691D01*
X1493800Y334400D01*
Y339690D01*
X1495310Y341200D01*
X1495810D01*
G01X1501550Y293750D02*
X1500000Y292200D01*
X1493465D01*
X1491311Y290046D01*
Y280168D01*
X1496178Y275301D01*
X1497312D01*
X1497319Y275294D01*
X1498425D01*
X1500400Y273319D01*
Y269533D01*
X1508792Y261141D01*
Y252180D01*
X1505418Y248806D01*
Y242000D01*
X1506051Y241367D01*
Y222258D01*
X1504992Y221199D01*
Y203602D01*
X1505739Y202855D01*
Y200947D01*
X1505737Y200945D01*
Y183783D01*
X1514333Y175187D01*
Y161636D01*
X1511420Y158723D01*
Y153348D01*
X1522753Y142015D01*
Y138383D01*
X1526600Y134536D01*
Y131469D01*
X1532621Y125448D01*
X1538582D01*
X1540382Y123648D01*
X1543352D01*
X1553057Y113943D01*
X1574966D01*
X1576751Y115728D01*
X1589540D01*
X1591500Y113768D01*
Y110907D01*
X1595163Y107244D01*
X1597144D01*
X1598152Y108252D01*
X1601241D01*
X1603676Y110687D01*
X1621573D01*
X1622145Y110115D01*
X1622210D01*
X1628423Y103902D01*
X1648444D01*
X1652200Y100146D01*
X1657354D01*
X1658100Y99400D01*
G01X1476761Y152725D02*
Y147939D01*
X1487672Y137028D01*
Y114037D01*
X1489394Y112315D01*
X1490178D01*
G01X1480098Y295649D02*
X1481568Y294179D01*
X1490179D01*
X1491513Y295513D01*
X1502016D01*
X1503126Y294403D01*
Y292021D01*
X1501527Y290422D01*
Y289176D01*
X1501563Y289140D01*
Y287834D01*
X1501527Y287798D01*
Y287030D01*
X1499365Y284868D01*
X1494871D01*
X1492130Y282127D01*
Y280825D01*
X1494323Y278632D01*
Y278457D01*
X1496373Y276407D01*
X1497591D01*
X1497618Y276380D01*
X1499028D01*
X1501352Y274056D01*
Y269928D01*
X1509744Y261536D01*
Y251785D01*
X1506370Y248411D01*
Y242500D01*
X1507003Y241867D01*
Y220631D01*
X1505944Y219572D01*
Y203997D01*
X1506691Y203250D01*
Y200552D01*
X1506689Y200550D01*
Y184178D01*
X1515285Y175582D01*
Y157489D01*
X1519152Y153622D01*
Y149585D01*
X1524734Y144003D01*
Y141537D01*
X1525657Y140614D01*
X1525658D01*
X1527573Y138699D01*
Y131847D01*
X1533020Y126400D01*
X1538977D01*
X1540777Y124600D01*
X1543900D01*
X1552828Y115672D01*
X1574877D01*
X1575885Y116680D01*
X1590401D01*
X1592880Y114201D01*
Y112033D01*
X1592877Y112030D01*
Y110724D01*
X1595606Y107995D01*
X1596832D01*
X1597841Y109004D01*
X1600894D01*
X1605806Y113916D01*
X1619407D01*
X1622457Y110866D01*
X1625647D01*
X1625688Y110825D01*
X1630504D01*
X1630984Y110345D01*
Y107697D01*
X1632574Y106107D01*
G01X1526728Y124168D02*
Y123066D01*
X1528289Y121505D01*
Y120691D01*
X1537980Y111000D01*
X1542977D01*
X1543945Y110032D01*
X1562136D01*
X1563764Y108404D01*
X1578041D01*
X1581242Y111605D01*
X1583664D01*
X1585753Y109516D01*
X1589631D01*
X1593630Y105517D01*
X1597595D01*
X1598677Y106599D01*
X1601891D01*
X1603256Y107964D01*
X1608569D01*
X1612719Y103814D01*
X1626383D01*
X1627985Y102212D01*
X1643701D01*
X1647988Y97925D01*
X1655634D01*
X1656759Y96800D01*
X1662300D01*
X1664500Y99000D01*
G01X1513900Y218000D02*
X1512600D01*
X1511759Y217159D01*
Y212141D01*
X1510800Y211182D01*
Y199101D01*
X1513403Y196498D01*
Y192598D01*
X1509524Y188719D01*
Y185101D01*
X1517941Y176684D01*
Y176558D01*
X1518093Y176406D01*
Y158459D01*
X1528257Y148295D01*
Y145306D01*
X1535319Y138244D01*
Y134980D01*
X1541471Y128828D01*
X1543672D01*
X1549924Y122576D01*
X1554153D01*
X1555076Y121653D01*
Y120924D01*
X1559376Y116624D01*
X1574482D01*
X1576104Y118246D01*
X1590655D01*
X1598190Y110711D01*
G01X1493069Y152834D02*
X1493710Y153475D01*
Y155627D01*
X1496515Y158432D01*
Y160371D01*
X1495734Y161152D01*
Y163834D01*
X1498360Y166460D01*
Y177006D01*
X1489292Y186074D01*
Y219937D01*
X1487425Y221804D01*
Y238371D01*
X1481881Y243915D01*
Y247481D01*
X1482400Y248000D01*
G01X1493268Y293943D02*
X1492412Y293087D01*
X1491780D01*
X1487935Y289242D01*
Y279082D01*
X1488585Y278432D01*
X1491415D01*
X1494823Y275024D01*
Y273477D01*
X1496678Y271622D01*
X1496681D01*
X1507640Y260663D01*
Y252658D01*
X1502152Y247170D01*
Y237848D01*
X1504469Y235531D01*
Y222316D01*
X1503840Y221687D01*
Y203124D01*
X1504586Y202378D01*
Y201424D01*
X1504585Y201423D01*
Y183305D01*
X1513181Y174709D01*
Y162114D01*
X1510268Y159201D01*
Y152870D01*
X1521601Y141537D01*
Y134558D01*
X1530116Y126043D01*
Y123128D01*
X1535730Y117514D01*
X1542926D01*
X1547649Y112791D01*
X1575444D01*
X1577229Y114576D01*
X1583175D01*
X1586999Y110752D01*
X1590025D01*
X1594335Y106442D01*
X1597405D01*
X1598463Y107500D01*
X1601725D01*
X1603016Y108791D01*
X1608806D01*
X1613031Y104566D01*
X1626695D01*
X1628151Y103110D01*
X1645487D01*
X1648000Y100597D01*
G01X1499472Y250370D02*
X1499500Y250342D01*
Y236000D01*
X1502148Y233352D01*
Y226175D01*
X1502165Y226158D01*
Y223272D01*
X1501536Y222643D01*
Y201575D01*
X1502202Y200909D01*
Y182242D01*
X1508500Y175944D01*
Y167064D01*
X1508938Y166626D01*
Y161131D01*
X1507728Y159921D01*
Y153434D01*
X1508242Y152920D01*
X1520370Y140959D01*
Y134159D01*
X1528844Y125685D01*
Y122679D01*
X1535174Y116349D01*
X1542461D01*
X1546658Y112152D01*
X1547449Y111355D01*
X1563074D01*
X1564119Y110310D01*
X1571951D01*
X1572395Y110754D01*
G01X1491438Y221137D02*
Y220579D01*
X1492794Y219223D01*
Y216318D01*
X1490500Y214024D01*
Y185930D01*
X1499112Y177318D01*
Y163388D01*
X1499684Y162816D01*
Y161909D01*
X1497563Y159788D01*
Y158416D01*
X1494462Y155315D01*
Y153576D01*
X1495385Y152653D01*
X1496691D01*
X1497563Y151781D01*
Y149528D01*
X1496150Y148115D01*
G01X1530101Y132671D02*
X1532270D01*
X1533517Y133918D01*
Y137461D01*
X1520304Y150674D01*
Y154100D01*
X1516437Y157967D01*
Y176060D01*
X1507841Y184656D01*
Y200072D01*
X1507843Y200074D01*
Y203728D01*
X1507096Y204475D01*
Y218172D01*
X1507524Y218600D01*
G01X1514265Y355542D02*
Y353531D01*
X1513526Y352792D01*
Y341702D01*
X1523500Y331728D01*
Y330170D01*
X1520830Y327500D01*
Y306437D01*
X1521954Y305313D01*
Y282063D01*
X1523876Y280141D01*
Y278027D01*
X1523660Y277811D01*
Y256676D01*
X1526004Y254332D01*
X1527985D01*
X1533837Y248480D01*
Y242853D01*
X1529904Y238920D01*
Y234385D01*
X1529905Y234384D01*
Y231981D01*
X1527386Y229462D01*
Y226771D01*
X1521603Y220988D01*
Y215322D01*
X1524093Y212832D01*
Y168231D01*
X1526312Y166012D01*
X1536309D01*
X1539519Y162802D01*
Y148761D01*
X1540740Y147540D01*
X1541092D01*
X1541178Y147454D01*
X1542484D01*
X1542570Y147540D01*
X1560720D01*
X1565972Y142288D01*
Y134035D01*
X1565944Y134007D01*
Y132701D01*
X1566907Y131738D01*
X1569466D01*
X1571632Y133904D01*
X1583153D01*
X1583919Y133138D01*
X1592084D01*
X1593241Y134295D01*
G01X1598300Y116477D02*
X1600345Y118522D01*
Y121654D01*
X1598999Y123000D01*
X1594874D01*
X1592678Y125196D01*
X1585642D01*
X1583114Y122668D01*
X1570582D01*
X1560179Y133071D01*
Y139263D01*
X1559625Y139817D01*
X1557585D01*
X1557508Y139894D01*
X1557328D01*
X1556646Y140576D01*
X1552043D01*
X1546389Y134922D01*
X1540737D01*
X1538750Y136909D01*
Y146698D01*
X1536326Y149122D01*
Y159424D01*
X1531242Y164508D01*
X1526936D01*
X1526934Y164506D01*
X1526312D01*
X1526311Y164507D01*
X1525689D01*
X1522589Y167607D01*
Y168718D01*
X1522587Y168720D01*
Y175932D01*
X1522588Y175933D01*
Y176555D01*
X1522589Y176556D01*
Y212208D01*
X1520099Y214698D01*
Y221612D01*
X1525403Y226916D01*
Y230413D01*
X1528400Y233410D01*
Y239544D01*
X1531500Y242644D01*
Y245083D01*
X1529778Y246805D01*
Y250411D01*
X1527361Y252828D01*
X1525380D01*
X1522155Y256053D01*
Y274204D01*
X1518872Y277487D01*
Y285343D01*
X1519582Y286053D01*
Y286129D01*
X1519876Y286423D01*
Y304595D01*
X1519200Y305271D01*
Y313079D01*
X1516090Y316189D01*
Y317811D01*
X1517509Y319230D01*
X1518740D01*
X1519200Y319690D01*
Y331486D01*
X1510851Y339835D01*
Y340113D01*
G01X1557981Y141470D02*
X1557514Y141937D01*
X1550342D01*
X1546700Y138295D01*
X1540207D01*
X1539502Y139000D01*
Y147481D01*
X1537186Y149797D01*
Y159628D01*
X1531554Y165260D01*
X1526624D01*
X1526623Y165259D01*
X1526001D01*
X1523341Y167919D01*
Y169030D01*
X1523340Y169031D01*
Y176243D01*
X1523341Y176244D01*
Y212520D01*
X1520851Y215010D01*
Y221300D01*
X1526271Y226720D01*
Y229859D01*
X1529152Y232740D01*
Y239232D01*
X1532285Y242365D01*
Y245441D01*
X1530580Y247146D01*
Y250673D01*
X1527673Y253580D01*
X1525692D01*
X1522907Y256365D01*
Y274580D01*
X1519624Y277863D01*
Y284459D01*
X1520880Y285715D01*
Y305131D01*
X1520000Y306011D01*
Y334164D01*
X1512614Y341550D01*
Y349013D01*
X1511000Y350627D01*
G01X1516872Y208863D02*
X1515722Y210013D01*
Y211154D01*
X1515370Y211506D01*
X1513152D01*
X1512800Y211858D01*
Y212562D01*
X1513152Y212914D01*
X1515370D01*
X1515722Y213266D01*
Y213970D01*
X1515370Y214322D01*
X1513152D01*
X1512800Y214674D01*
Y215378D01*
X1513152Y215730D01*
X1515370D01*
X1515722Y216082D01*
Y220115D01*
X1513962Y221875D01*
Y225092D01*
X1514314Y225444D01*
X1518848D01*
X1519200Y225796D01*
Y226500D01*
X1518848Y226852D01*
X1514314D01*
X1513962Y227204D01*
Y227908D01*
X1514314Y228260D01*
X1521848D01*
X1522200Y228612D01*
Y229316D01*
X1521848Y229668D01*
X1514314D01*
X1513962Y230020D01*
Y230724D01*
X1514314Y231076D01*
X1521848D01*
X1522200Y231428D01*
Y232132D01*
X1521848Y232484D01*
X1521099D01*
X1520747Y232836D01*
Y236948D01*
X1520395Y237300D01*
X1519691D01*
X1519339Y236948D01*
Y232836D01*
X1518987Y232484D01*
X1514314D01*
X1513962Y232836D01*
Y235885D01*
X1513447Y236400D01*
X1512717D01*
X1512202Y235885D01*
Y222515D01*
X1511687Y222000D01*
X1510957D01*
X1510442Y222515D01*
Y236642D01*
X1511650Y237850D01*
X1516036D01*
X1518189Y240003D01*
Y241309D01*
X1517685Y241813D01*
Y250925D01*
X1516052Y252558D01*
Y270633D01*
X1506945Y279740D01*
Y288369D01*
X1509000Y290424D01*
Y295000D01*
X1512520Y298520D01*
Y304585D01*
X1512005Y305100D01*
X1511275D01*
X1510760Y304585D01*
Y299615D01*
X1510245Y299100D01*
X1509515D01*
X1509000Y299615D01*
Y307660D01*
X1508360Y308300D01*
Y309712D01*
X1506459Y311613D01*
X1504752D01*
X1504400Y311965D01*
Y312669D01*
X1504752Y313021D01*
X1506459D01*
X1506811Y313373D01*
Y315082D01*
X1506459Y315434D01*
X1504828D01*
X1504476Y315786D01*
Y316490D01*
X1504828Y316842D01*
X1506459D01*
X1506811Y317194D01*
Y317898D01*
X1506459Y318250D01*
X1505679D01*
X1505327Y318602D01*
Y319306D01*
X1505679Y319658D01*
X1506459D01*
X1506811Y320010D01*
Y322889D01*
X1506275Y323425D01*
X1505779D01*
X1504095Y321740D01*
X1503599D01*
X1503099Y322240D01*
Y322736D01*
X1504783Y324421D01*
Y324917D01*
X1506060Y326194D01*
Y331590D01*
X1503460Y334190D01*
Y340080D01*
X1498310Y345230D01*
X1490212D01*
X1486884Y348558D01*
Y353785D01*
X1490055Y356956D01*
Y358791D01*
X1488479Y360367D01*
G01X1507200Y356000D02*
X1509600D01*
X1514268Y360668D01*
X1515512D01*
X1517233Y358947D01*
Y354208D01*
X1515030Y352005D01*
Y342326D01*
X1521633Y335723D01*
X1526456D01*
X1529113Y333066D01*
Y329208D01*
X1521593Y321688D01*
Y308546D01*
X1525100Y305039D01*
Y292837D01*
X1523836Y291573D01*
Y289902D01*
X1523835Y289901D01*
Y287203D01*
X1523836Y287202D01*
Y282915D01*
X1523835Y282914D01*
Y281878D01*
X1524628Y281085D01*
Y277715D01*
X1524412Y277499D01*
Y256988D01*
X1526316Y255084D01*
X1528297D01*
X1534589Y248792D01*
Y242541D01*
X1530656Y238608D01*
Y234697D01*
X1530657Y234696D01*
Y231106D01*
X1528254Y228703D01*
Y226575D01*
X1524976Y223297D01*
Y171556D01*
X1527222Y169310D01*
X1534075D01*
X1540457Y162928D01*
Y159741D01*
X1551863Y148335D01*
X1560989D01*
X1567803Y141521D01*
X1569242D01*
X1575880Y134883D01*
X1583385D01*
X1588613Y140111D01*
X1594123D01*
X1599785Y134449D01*
Y133015D01*
X1600900Y131900D01*
G01X1510800Y193330D02*
Y196973D01*
X1508593Y199180D01*
Y199760D01*
X1508595Y199762D01*
Y204040D01*
X1508547Y204088D01*
Y211361D01*
X1509100Y211914D01*
Y219909D01*
X1507955Y221054D01*
Y242867D01*
X1507322Y243500D01*
Y248016D01*
X1510696Y251390D01*
Y265803D01*
X1502444Y274055D01*
Y274854D01*
X1498199Y279099D01*
Y279163D01*
X1498105Y279257D01*
Y280563D01*
X1500605Y283063D01*
Y284684D01*
X1502593Y286672D01*
Y290053D01*
X1504330Y291790D01*
Y297894D01*
X1499557Y302667D01*
Y306828D01*
X1497944Y308441D01*
Y311136D01*
X1496213Y312867D01*
X1488937D01*
X1487867Y311797D01*
Y310788D01*
X1487006Y309927D01*
X1485788D01*
X1484927Y310788D01*
Y312866D01*
X1483247Y314546D01*
G01X1864904Y114735D02*
Y115347D01*
X1860871Y119380D01*
X1854921D01*
X1844614Y129687D01*
X1827066D01*
X1817118Y119739D01*
X1815532D01*
X1815520Y119751D01*
X1811209D01*
X1811197Y119739D01*
X1811139D01*
X1806402Y115002D01*
Y109024D01*
X1793370Y95992D01*
X1772925D01*
X1768043Y91110D01*
X1766323D01*
X1763232Y88019D01*
X1753899D01*
X1750677Y84797D01*
X1712158D01*
X1709920Y87035D01*
X1707870D01*
X1706432Y88473D01*
X1702696D01*
X1701289Y89880D01*
X1684505D01*
X1680708Y93677D01*
X1679118D01*
X1676464Y96331D01*
X1671920D01*
X1662032Y106219D01*
X1655377D01*
X1653011Y108585D01*
Y112953D01*
X1651948Y114016D01*
X1637119D01*
X1633970Y117165D01*
X1620436D01*
X1618365Y119236D01*
Y119253D01*
X1617502Y120116D01*
X1617485D01*
X1617286Y120315D01*
X1606223D01*
X1604396Y122142D01*
Y131444D01*
X1594277Y141563D01*
X1587825D01*
X1583221Y136959D01*
X1577210D01*
X1564216Y149953D01*
X1553299D01*
X1553298Y149952D01*
X1552262D01*
X1541810Y160404D01*
Y163670D01*
X1534863Y170617D01*
X1528682D01*
X1526955Y172344D01*
Y223255D01*
X1531909Y228209D01*
Y235215D01*
X1531908Y235216D01*
Y238089D01*
X1535841Y242022D01*
Y249311D01*
X1528816Y256336D01*
X1527164D01*
X1525664Y257836D01*
Y276980D01*
X1525880Y277196D01*
Y281604D01*
X1525088Y282396D01*
Y287721D01*
X1525087Y287722D01*
Y289382D01*
X1525088Y289383D01*
Y291054D01*
X1526900Y292866D01*
G01X1525650Y248700D02*
X1523170D01*
X1518356Y253514D01*
Y271589D01*
X1510600Y279345D01*
Y283971D01*
X1513476Y286847D01*
Y291003D01*
X1512182Y292297D01*
Y293317D01*
G01X1496030Y267665D02*
X1495677D01*
X1484910Y278432D01*
X1482638D01*
X1481600Y279470D01*
Y290700D01*
X1478418Y293882D01*
Y296373D01*
X1477672Y297119D01*
X1472939D01*
X1472328Y297730D01*
Y312006D01*
X1473189Y312867D01*
X1474780D01*
X1481226Y319313D01*
Y326925D01*
X1484100Y329799D01*
Y330115D01*
G01X1516613Y240656D02*
X1516433Y240836D01*
Y250547D01*
X1514355Y252625D01*
Y270700D01*
X1505793Y279262D01*
Y288847D01*
X1507800Y290854D01*
Y300160D01*
X1503542Y304418D01*
Y309012D01*
X1502236Y310318D01*
Y314674D01*
X1497920Y318990D01*
Y329429D01*
X1501448Y332957D01*
Y336762D01*
X1500120Y338090D01*
Y338730D01*
X1497710Y341140D01*
Y342470D01*
X1496127Y344053D01*
X1489759D01*
X1485732Y348080D01*
Y355020D01*
X1488479Y357767D01*
G01X1513900Y218000D02*
Y218840D01*
X1511989Y220751D01*
X1510878D01*
X1509459Y222170D01*
Y238819D01*
X1510739Y240099D01*
X1512790D01*
G01X1497997Y338546D02*
X1500296Y336247D01*
Y333605D01*
X1496720Y330029D01*
Y318046D01*
X1501084Y313682D01*
Y309431D01*
X1502156Y308359D01*
Y302762D01*
X1506248Y298670D01*
Y290932D01*
X1504548Y289232D01*
Y285847D01*
X1502652Y283951D01*
Y280639D01*
X1512696Y270595D01*
Y247572D01*
X1509800Y244676D01*
G01X1610591Y140688D02*
X1605687D01*
X1602225Y144150D01*
X1588101D01*
X1585721Y141770D01*
X1574317D01*
X1564882Y151205D01*
X1552780D01*
X1543062Y160923D01*
Y165220D01*
X1536416Y171866D01*
X1535385D01*
X1535382Y171869D01*
X1529201D01*
X1528207Y172863D01*
Y219193D01*
X1530296Y221282D01*
Y224825D01*
X1533161Y227690D01*
Y235734D01*
X1533160Y235735D01*
Y237570D01*
X1537093Y241503D01*
Y252536D01*
X1526916Y262713D01*
Y276461D01*
X1527657Y277202D01*
Y278557D01*
X1527800Y278700D01*
X1527657D01*
G01X1476948Y273603D02*
X1478500Y272051D01*
X1487175D01*
X1487888Y271338D01*
Y269710D01*
X1492350Y265248D01*
X1492539D01*
X1493539Y264248D01*
X1499053D01*
X1504072Y259229D01*
X1504772D01*
G01X1502165Y251200D02*
Y259505D01*
X1498374Y263296D01*
X1497573D01*
X1497571Y263294D01*
X1496783D01*
X1496782Y263295D01*
X1495828D01*
X1495827Y263296D01*
X1493144D01*
X1487628Y268812D01*
X1472291D01*
X1470649Y270454D01*
G01X1523580Y237960D02*
Y238542D01*
X1525311Y240273D01*
Y245910D01*
X1527226Y247825D01*
Y249353D01*
X1526303Y250276D01*
X1523224D01*
X1519603Y253897D01*
Y272196D01*
X1513906Y277893D01*
Y285647D01*
X1514628Y286369D01*
Y289719D01*
X1516298Y291389D01*
Y304431D01*
X1511191Y309538D01*
Y314164D01*
X1509364Y315991D01*
Y326563D01*
X1508372Y327555D01*
Y334542D01*
X1509136Y335306D01*
Y349374D01*
X1507154Y351356D01*
Y353100D01*
G01X1488479Y362967D02*
X1491207Y360239D01*
Y356478D01*
X1488036Y353307D01*
Y349036D01*
X1490592Y346480D01*
X1503019D01*
X1506640Y342859D01*
Y340290D01*
X1505170Y338820D01*
Y336280D01*
X1507220Y334230D01*
Y325712D01*
X1508212Y324720D01*
Y315513D01*
X1510039Y313686D01*
Y308696D01*
X1513672Y305063D01*
Y298042D01*
X1510264Y294634D01*
Y285265D01*
X1509448Y284449D01*
Y278867D01*
X1517204Y271111D01*
Y253036D01*
X1519148Y251092D01*
Y247577D01*
X1520876Y245849D01*
Y243704D01*
X1520413Y243241D01*
Y239498D01*
G01X1526936Y307015D02*
Y300311D01*
X1529228Y298019D01*
Y290688D01*
X1527092Y288552D01*
Y284874D01*
X1529985Y281981D01*
Y276836D01*
X1528820Y275671D01*
Y263520D01*
X1538997Y253343D01*
Y240413D01*
X1535617Y237033D01*
Y234063D01*
X1540517Y229163D01*
Y207447D01*
X1537001Y203931D01*
Y186835D01*
X1536484Y186318D01*
Y182582D01*
X1536486Y182580D01*
Y181780D01*
X1541945Y176321D01*
X1551940D01*
X1561860Y166401D01*
X1568699D01*
X1569500Y165600D01*
X1577386D01*
X1585386Y157600D01*
X1588176D01*
G01X1708350Y175050D02*
X1706661Y176739D01*
X1687739D01*
X1679079Y168079D01*
X1668973D01*
X1661963Y161069D01*
X1660221D01*
X1659503Y160351D01*
Y158593D01*
X1658972Y158062D01*
X1654225D01*
X1653211Y157048D01*
Y152831D01*
X1652090Y151710D01*
X1646618D01*
X1640500Y157828D01*
X1623225D01*
X1621651Y156254D01*
Y152677D01*
X1620702Y151728D01*
X1617515D01*
X1617512Y151725D01*
X1616288D01*
X1616285Y151728D01*
X1613246D01*
X1612157Y150639D01*
Y148977D01*
X1611768Y148588D01*
X1602551D01*
X1600944Y150195D01*
X1585500D01*
X1577945Y157750D01*
X1561067D01*
X1559016Y159801D01*
Y164937D01*
X1554185Y169768D01*
X1551678D01*
X1548177Y173269D01*
X1542030D01*
X1533700Y181599D01*
Y203671D01*
X1536576Y206547D01*
Y224434D01*
X1534704Y226306D01*
Y237484D01*
X1538245Y241025D01*
Y253031D01*
X1528068Y263208D01*
Y275983D01*
X1529233Y277148D01*
Y281669D01*
X1526340Y284562D01*
Y288864D01*
X1528476Y291000D01*
Y297707D01*
X1525929Y300254D01*
Y305274D01*
X1522846Y308357D01*
Y314522D01*
X1523935Y315611D01*
Y318901D01*
G01X1517367Y349964D02*
Y347102D01*
X1522589Y341880D01*
Y339524D01*
X1524790Y337323D01*
X1526122D01*
X1526123Y337324D01*
X1526745D01*
X1526746Y337323D01*
X1526984D01*
X1531250Y333057D01*
Y327379D01*
X1527193Y323322D01*
Y317646D01*
X1531330Y313509D01*
Y311247D01*
X1531331Y311246D01*
Y310624D01*
X1531330Y310623D01*
Y306923D01*
X1531331Y306922D01*
Y306300D01*
X1530016Y304985D01*
Y300423D01*
X1531484Y298955D01*
Y298836D01*
X1531485Y298835D01*
Y298213D01*
X1531484Y298212D01*
Y289316D01*
X1532241Y288559D01*
Y276963D01*
X1530324Y275046D01*
Y264144D01*
X1540501Y253967D01*
Y250603D01*
X1545495Y245609D01*
Y242138D01*
X1548464Y239169D01*
Y228207D01*
X1545090Y224833D01*
Y205825D01*
X1541108Y201843D01*
Y185620D01*
X1540248Y184760D01*
Y183338D01*
X1542011Y181575D01*
X1562875D01*
X1566531Y177919D01*
X1583832D01*
X1592544Y169207D01*
X1602378D01*
X1602820Y169649D01*
X1617414D01*
X1617677Y169912D01*
X1617678D01*
X1618949Y171183D01*
X1619571D01*
X1619572Y171182D01*
X1620305D01*
X1620307Y171184D01*
X1620929D01*
X1621104Y171009D01*
X1635591D01*
X1637566Y169034D01*
X1644866D01*
X1646540Y167360D01*
X1650060D01*
X1651536Y165884D01*
G01X1665063Y172608D02*
X1662138Y175533D01*
X1656859D01*
X1656858Y175532D01*
X1648943D01*
X1648942Y175533D01*
X1646101D01*
X1646083Y175551D01*
X1619988D01*
X1619970Y175533D01*
X1619934D01*
X1618690Y174289D01*
X1617210D01*
X1617209Y174288D01*
X1616587D01*
X1616586Y174289D01*
X1615986D01*
X1615985Y174288D01*
X1615363D01*
X1614400Y175251D01*
X1592437D01*
X1592436Y175250D01*
X1591548D01*
X1591324Y175474D01*
X1590777D01*
X1583055Y183196D01*
X1564496D01*
X1563700Y182400D01*
X1542250D01*
X1541000Y183650D01*
Y184448D01*
X1541860Y185308D01*
Y185310D01*
X1542300Y185750D01*
Y201391D01*
X1549445Y208536D01*
Y246404D01*
X1542653Y253196D01*
Y254859D01*
X1533568Y263944D01*
Y269568D01*
X1537008Y273008D01*
Y288922D01*
X1533248Y292682D01*
Y292760D01*
X1532236Y293772D01*
Y297900D01*
X1532237Y297901D01*
Y298523D01*
X1532238Y298524D01*
Y299146D01*
X1532236Y299148D01*
Y299267D01*
X1530768Y300735D01*
Y304673D01*
X1532083Y305988D01*
Y307234D01*
X1532082Y307235D01*
Y310311D01*
X1532084Y310313D01*
Y310935D01*
X1532083Y310936D01*
Y311558D01*
X1532082Y311559D01*
Y322232D01*
X1530748Y323566D01*
Y325813D01*
X1532001Y327066D01*
Y327186D01*
X1532002Y327187D01*
Y333369D01*
X1527296Y338075D01*
X1527058D01*
X1527057Y338076D01*
X1525811D01*
X1525810Y338075D01*
X1525632D01*
X1523341Y340366D01*
Y342920D01*
X1520000Y346261D01*
Y354027D01*
X1520352Y354379D01*
X1520429D01*
G01X1558950Y363050D02*
Y363642D01*
X1557426Y365166D01*
Y365174D01*
X1553450Y369150D01*
X1489750D01*
X1486189Y365589D01*
Y356560D01*
X1484748Y355119D01*
Y347252D01*
X1490290Y341710D01*
Y329214D01*
X1488050Y326974D01*
Y313750D01*
X1487376Y313076D01*
X1485788D01*
X1484927Y313937D01*
Y314973D01*
X1483800Y316100D01*
X1479450D01*
X1475350Y312000D01*
Y303000D01*
X1474298Y301948D01*
X1473798D01*
G01X1530500Y287700D02*
X1529980Y288220D01*
Y298331D01*
X1528512Y299799D01*
Y308983D01*
X1527747Y309748D01*
X1524478D01*
X1523598Y310628D01*
Y314210D01*
X1525673Y316285D01*
Y323830D01*
X1530010Y328167D01*
Y333233D01*
X1526768Y336475D01*
X1521945D01*
X1515782Y342638D01*
Y351693D01*
X1517985Y353896D01*
Y359259D01*
X1515452Y361792D01*
X1510292D01*
X1507200Y358700D01*
G01X1858686Y180377D02*
X1858388Y180079D01*
X1853781D01*
X1843708Y190152D01*
X1728335D01*
X1716918Y201569D01*
X1699949D01*
X1699948Y201570D01*
X1696481D01*
X1696480Y201569D01*
X1686714D01*
X1686713Y201570D01*
X1682984D01*
X1679752Y198338D01*
Y194822D01*
X1672752Y187822D01*
X1655057D01*
X1651044Y183809D01*
Y182743D01*
X1647232Y178931D01*
X1625460D01*
X1624192Y180199D01*
X1620311D01*
X1619467Y179355D01*
X1619466D01*
X1619465Y179354D01*
X1617535D01*
X1616012Y180877D01*
X1612249D01*
X1609965Y178593D01*
X1594332D01*
X1586640Y186285D01*
X1549849D01*
X1544300Y191834D01*
Y200697D01*
X1551349Y207746D01*
Y247194D01*
X1544562Y253981D01*
Y255644D01*
X1535472Y264734D01*
Y268778D01*
X1539100Y272406D01*
Y295471D01*
X1534426Y300145D01*
Y306259D01*
X1532834Y307851D01*
Y309999D01*
X1532836Y310001D01*
Y311247D01*
X1532835Y311248D01*
Y311870D01*
X1532834Y311871D01*
Y322544D01*
X1531500Y323878D01*
Y325501D01*
X1532753Y326754D01*
Y326874D01*
X1532754Y326875D01*
Y333681D01*
X1527608Y338827D01*
X1527370D01*
X1527369Y338828D01*
X1525943D01*
X1524278Y340493D01*
Y343409D01*
X1521218Y346469D01*
Y352581D01*
X1522005Y353368D01*
Y361436D01*
X1522476Y361907D01*
G01X1514925Y358844D02*
X1516129D01*
X1516481Y358492D01*
Y354520D01*
X1514278Y352317D01*
Y342014D01*
X1521352Y334940D01*
X1522645D01*
X1527537Y330048D01*
G01X1551875Y401174D02*
Y397095D01*
X1550830Y396050D01*
X1547390D01*
X1546405Y395065D01*
Y393255D01*
X1547800Y391860D01*
Y390270D01*
X1548740Y389330D01*
X1552870D01*
X1554000Y388200D01*
Y386900D01*
X1555395Y385505D01*
Y382735D01*
X1553445Y380785D01*
Y380243D01*
X1552000Y378798D01*
Y377368D01*
X1549734Y375102D01*
X1485881D01*
X1476880Y366101D01*
Y364093D01*
X1476587Y363800D01*
Y352184D01*
X1480347Y348424D01*
X1482176D01*
X1489480Y341120D01*
Y329468D01*
X1486600Y326588D01*
Y320600D01*
X1484926Y318926D01*
Y316978D01*
X1486397Y315507D01*
Y314546D01*
G01X1533589Y366361D02*
Y366542D01*
X1531779Y368352D01*
X1496875D01*
X1496490Y367967D01*
Y353500D01*
X1495627Y352637D01*
X1489915D01*
G01X1875850Y567200D02*
X1877299Y565751D01*
Y564822D01*
X1880821Y561300D01*
X1895618D01*
X1901500Y555418D01*
Y545671D01*
X1893029Y537200D01*
X1885177D01*
X1880887Y532910D01*
Y499784D01*
X1876024Y494921D01*
X1874091D01*
X1861898Y482728D01*
X1861869D01*
X1860272Y481131D01*
Y481102D01*
X1853022Y473852D01*
X1834000D01*
X1829124Y468976D01*
X1734200D01*
X1728606Y474570D01*
X1714569D01*
X1710774Y478365D01*
X1686622D01*
X1685563Y479424D01*
X1668538D01*
X1666462Y481500D01*
X1654800D01*
X1653500Y480200D01*
X1650100D01*
X1648068Y482232D01*
X1622158D01*
X1619910Y484480D01*
X1613618D01*
X1606089Y476951D01*
Y472319D01*
X1593012Y459242D01*
Y451573D01*
X1591939Y450500D01*
X1583250D01*
X1575750Y443000D01*
G01X1576425Y442575D02*
X1582825Y448975D01*
X1592175D01*
X1594562Y451362D01*
Y459538D01*
X1606841Y471817D01*
Y476639D01*
X1613930Y483728D01*
X1619598D01*
X1621846Y481480D01*
X1642320D01*
X1646000Y477800D01*
X1651279D01*
X1652812Y479333D01*
X1666867D01*
X1667928Y478272D01*
X1685085D01*
X1686144Y477213D01*
X1710296D01*
X1722080Y465429D01*
X1827207D01*
X1834054Y472276D01*
X1837300D01*
G01X1854868Y184667D02*
X1848131Y191404D01*
X1728854D01*
X1717436Y202822D01*
X1712317D01*
X1712316Y202821D01*
X1700468D01*
X1700467Y202822D01*
X1695962D01*
X1695961Y202821D01*
X1687233D01*
X1687232Y202822D01*
X1682465D01*
X1678499Y198856D01*
Y197820D01*
X1678500Y197819D01*
Y195341D01*
X1672233Y189074D01*
X1634846D01*
X1633540Y187768D01*
Y184741D01*
X1633161Y184362D01*
Y184304D01*
X1629290Y180433D01*
X1626084D01*
X1623262Y183255D01*
X1617334D01*
X1616463Y182384D01*
X1611628D01*
X1611617Y182373D01*
X1611378D01*
X1611377Y182372D01*
X1605826D01*
X1605825Y182373D01*
X1604227D01*
X1603300Y183300D01*
X1593202D01*
X1587864Y188638D01*
X1561188D01*
X1559246Y190580D01*
X1556860D01*
X1556200Y191240D01*
Y200529D01*
X1556201Y200530D01*
Y202190D01*
X1555700Y202691D01*
Y248600D01*
X1550580Y253720D01*
Y277712D01*
X1544042Y284250D01*
Y305408D01*
X1540500Y308950D01*
Y315251D01*
X1537824Y317927D01*
Y321053D01*
X1538477Y321706D01*
Y326515D01*
X1539982Y328020D01*
Y333237D01*
X1538477Y334742D01*
Y337640D01*
X1531582Y344535D01*
X1529676D01*
X1525532Y348679D01*
Y350253D01*
X1525561D01*
G01X1478607Y359082D02*
X1481106Y361581D01*
Y366455D01*
X1482592Y367941D01*
X1483712D01*
X1487927Y372156D01*
X1487928D01*
X1488353Y372581D01*
X1554644D01*
X1554999Y372936D01*
X1555000D01*
X1556752Y374688D01*
Y374689D01*
X1557725Y375662D01*
Y377514D01*
G01X1559675Y401174D02*
Y396675D01*
X1559000Y396000D01*
X1558500D01*
X1557500Y395000D01*
Y393500D01*
X1556000Y392000D01*
Y390000D01*
X1557500Y388500D01*
Y386500D01*
X1556151Y385151D01*
Y383349D01*
X1557500Y382000D01*
Y380000D01*
X1556000Y378500D01*
Y375000D01*
X1554688Y373688D01*
X1487131D01*
X1480219Y366776D01*
Y363277D01*
X1478612Y361670D01*
G01X1529829Y362655D02*
Y357051D01*
X1523946Y351168D01*
Y348273D01*
X1529092Y343127D01*
X1530998D01*
X1536775Y337350D01*
Y321775D01*
X1536372Y321372D01*
Y314149D01*
X1538598Y311923D01*
Y308770D01*
X1542634Y304734D01*
Y283474D01*
X1549328Y276780D01*
Y253172D01*
X1554400Y248100D01*
Y201948D01*
X1551300Y198848D01*
X1549603D01*
X1547900Y197145D01*
Y191863D01*
X1548178Y191585D01*
Y190880D01*
G01X1524746Y356717D02*
X1523157Y355128D01*
Y352758D01*
X1522370Y351971D01*
Y347155D01*
X1527879Y341646D01*
Y340446D01*
X1535271Y333054D01*
Y322570D01*
X1534868Y322167D01*
Y313525D01*
X1536995Y311398D01*
Y308245D01*
X1540400Y304840D01*
Y272076D01*
X1536747Y268423D01*
Y265089D01*
X1545714Y256122D01*
Y254486D01*
X1552702Y247498D01*
Y206769D01*
X1545910Y199977D01*
G01X1546000Y197400D02*
X1547091D01*
X1550487Y200796D01*
Y202684D01*
X1553596Y205793D01*
Y247804D01*
X1548576Y252824D01*
Y275024D01*
X1541882Y281718D01*
Y304422D01*
X1537846Y308458D01*
Y311611D01*
X1535620Y313837D01*
Y321684D01*
X1536023Y322087D01*
Y337038D01*
X1530686Y342375D01*
X1528780D01*
X1523177Y347978D01*
Y351463D01*
X1524746Y353032D01*
Y354217D01*
G01X1561925Y192675D02*
X1564824Y195574D01*
Y241676D01*
X1552132Y254368D01*
Y278356D01*
X1550572Y279916D01*
Y289863D01*
X1545676Y294759D01*
Y305969D01*
X1542088Y309557D01*
Y321513D01*
X1540402Y323199D01*
Y325988D01*
X1541534Y327120D01*
Y333881D01*
X1540402Y335013D01*
Y350107D01*
X1540700Y350405D01*
Y366000D01*
X1539900Y366800D01*
X1536600D01*
X1534348Y364548D01*
X1523989D01*
X1520994Y367543D01*
X1502503D01*
X1500040Y365080D01*
Y349460D01*
X1498730Y348150D01*
X1491699D01*
X1489838Y350011D01*
G01X1563575Y387654D02*
X1562543Y386622D01*
X1560838Y385638D01*
G03X1560051Y384322I787J-1364D01*
G01Y384226D01*
G03X1560838Y382910I1574J48D01*
G02X1562001Y380975I-1163J-2016D01*
G01Y380813D01*
G02X1560838Y378878I-2326J81D01*
G03X1560051Y377562I787J-1364D01*
G01Y373163D01*
X1557541Y370653D01*
X1557117D01*
X1557116Y370652D01*
X1488970D01*
X1485322Y367004D01*
Y361693D01*
X1483740Y360111D01*
Y359550D01*
G01X1483664Y362914D02*
X1481930Y364648D01*
Y366215D01*
X1482904Y367189D01*
X1484024D01*
X1488239Y371404D01*
X1556804D01*
X1559295Y373895D01*
Y377518D01*
X1559299Y377514D01*
Y377595D01*
G02X1560462Y379530I2326J-81D01*
G03X1561249Y380846I-787J1364D01*
G01Y380942D01*
G03X1560462Y382258I-1574J-48D01*
G02X1559299Y384193I1163J2016D01*
G01Y384355D01*
G02X1560462Y386290I2326J-81D01*
G01X1561500Y386889D01*
Y388500D01*
X1560000Y390000D01*
Y392000D01*
X1562000Y394000D01*
Y395500D01*
X1564294Y397794D01*
X1565525D01*
G01X1753807Y548183D02*
X1748424Y542800D01*
X1738838D01*
X1731735Y549903D01*
X1720065D01*
X1712962Y542800D01*
X1688226D01*
X1683258Y537832D01*
Y533852D01*
X1681591Y532185D01*
X1678456D01*
X1676387Y534254D01*
X1672043D01*
X1667587Y529798D01*
X1643374D01*
X1642132Y531040D01*
X1633146D01*
X1631498Y532688D01*
X1616562D01*
X1610988Y527114D01*
Y522365D01*
X1604927Y516304D01*
X1585157D01*
X1581089Y520372D01*
X1541972D01*
X1535800Y514200D01*
Y495619D01*
X1528994Y488813D01*
G01X1522625Y470651D02*
Y470521D01*
G02X1521650Y468896I-1950J65D01*
G03X1520675Y467271I975J-1690D01*
G01Y467141D01*
G02X1519700Y465516I-1950J65D01*
G01X1516775Y463826D01*
G01X1524575D02*
X1523245D01*
X1523017Y464054D01*
G02X1523788Y465190I1558J-228D01*
G01X1533159Y488546D02*
X1538400Y493787D01*
Y513100D01*
X1543368Y518068D01*
X1580133D01*
X1584201Y514000D01*
X1606263D01*
X1613292Y521029D01*
Y525202D01*
X1618445Y530355D01*
X1629320D01*
X1631975Y527700D01*
G01X1520675Y463826D02*
X1522005D01*
X1522261Y464082D01*
G02X1523412Y465842I2313J-256D01*
G01X1532675Y489126D02*
X1537100Y493551D01*
Y513430D01*
X1542890Y519220D01*
X1580611D01*
X1584679Y515152D01*
X1605405D01*
X1612140Y521887D01*
Y525680D01*
X1617967Y531507D01*
X1630397D01*
X1634633Y527271D01*
Y525871D01*
X1637370Y523134D01*
X1651628D01*
X1654042Y520720D01*
X1690106D01*
X1694931Y525545D01*
X1717046D01*
X1723553Y532052D01*
X1760019D01*
X1763615Y535648D01*
Y538043D01*
X1761776Y539882D01*
Y568792D01*
X1758700Y571868D01*
Y581429D01*
X1777847Y600576D01*
X1787424D01*
X1787500Y600500D01*
G01X1482958Y486118D02*
X1478889Y490187D01*
X1475755D01*
X1470643Y495299D01*
G01X1527600Y3500D02*
Y3124D01*
X1529972Y752D01*
X1575401D01*
X1579305Y-3152D01*
X1593105D01*
X1597757Y-7804D01*
X1656497D01*
X1662573Y-1728D01*
X1674998D01*
X1678458Y1732D01*
Y3516D01*
X1680300Y5358D01*
X1736808D01*
X1739700Y8250D01*
Y9850D01*
X1741200Y11350D01*
X1772351D01*
X1781101Y2600D01*
X1795916D01*
X1796616Y3300D01*
X1810285D01*
X1813086Y6101D01*
X1818249D01*
X1821072Y8924D01*
Y10028D01*
X1822123Y11079D01*
Y15583D01*
X1817075Y20631D01*
Y24125D01*
X1821000Y28050D01*
X1821364D01*
X1821365Y28051D01*
X1822153D01*
X1822154Y28050D01*
X1825150D01*
X1834788Y37688D01*
X1839324D01*
X1839704Y38068D01*
X1854035D01*
X1856007Y36096D01*
X1868782D01*
X1875040Y42354D01*
Y43903D01*
X1878310Y47173D01*
Y55810D01*
X1880150Y57650D01*
Y60979D01*
X1889321Y70150D01*
X1911075D01*
X1930991Y90066D01*
Y101513D01*
X1937496Y108018D01*
Y121337D01*
X1936300Y122533D01*
Y135475D01*
X1933169Y138606D01*
X1920738D01*
X1916172Y143172D01*
Y143676D01*
X1912900Y146948D01*
X1911875D01*
X1911874Y146949D01*
X1911086D01*
X1911085Y146948D01*
X1902224D01*
X1901076Y148096D01*
X1898980D01*
X1896284Y145400D01*
X1878808D01*
X1874323Y149885D01*
X1866646D01*
X1859548Y156983D01*
Y158417D01*
X1855505Y162460D01*
X1842975D01*
X1839873Y159358D01*
G01X1580398Y5400D02*
X1584822Y976D01*
X1599526D01*
X1601102Y-600D01*
G01X1568488Y164058D02*
X1577842D01*
X1585879Y156021D01*
X1602468D01*
X1603557Y154932D01*
X1618468D01*
X1620100Y153300D01*
G01X1562150Y160700D02*
X1579800D01*
X1585366Y155134D01*
X1600966D01*
X1604300Y151800D01*
X1612255D01*
X1613741Y153286D01*
G01X1535425Y188016D02*
X1535734Y187707D01*
Y186632D01*
X1535732Y186630D01*
Y182270D01*
X1535734Y182268D01*
Y181468D01*
X1541633Y175569D01*
X1542332D01*
X1542333Y175568D01*
X1542955D01*
X1542956Y175569D01*
X1551469D01*
X1560331Y166707D01*
Y160290D01*
X1561497Y159124D01*
X1578479D01*
X1583572Y154031D01*
X1600398D01*
X1604292Y150137D01*
G01X1607401Y146947D02*
X1605954Y145500D01*
X1572217D01*
X1565192Y152525D01*
X1554489D01*
X1551000Y156014D01*
Y160099D01*
X1536549Y174550D01*
X1531431D01*
X1529989Y175992D01*
Y176011D01*
X1529726Y176274D01*
Y180674D01*
X1529725Y180675D01*
Y182328D01*
X1529726Y182329D01*
Y213714D01*
X1531935Y215923D01*
Y224160D01*
G01X1600182Y148562D02*
X1598420Y146800D01*
X1572547D01*
X1565387Y153960D01*
X1558769D01*
X1530878Y181851D01*
Y203078D01*
X1535000Y207200D01*
G01X1651536Y112341D02*
X1649970Y110775D01*
X1637327D01*
X1634086Y114016D01*
X1620874D01*
X1617793Y117097D01*
X1604876D01*
X1603256Y118717D01*
Y121762D01*
X1601018Y124000D01*
X1596000D01*
X1593028Y126972D01*
X1584067D01*
X1580784Y123689D01*
X1570625D01*
X1560974Y133340D01*
Y141971D01*
X1558674Y144271D01*
X1551612D01*
X1547165Y139824D01*
X1541481D01*
X1541434Y139871D01*
G01X1534400Y296029D02*
Y293160D01*
X1538160Y289400D01*
Y272530D01*
X1534720Y269090D01*
Y264422D01*
X1543810Y255332D01*
Y253669D01*
X1550597Y246882D01*
Y208058D01*
X1543548Y201009D01*
Y191522D01*
X1549537Y185533D01*
X1585729D01*
X1593420Y177842D01*
X1610278D01*
X1612562Y180126D01*
X1615700D01*
X1617223Y178603D01*
X1619778D01*
X1620591Y179416D01*
X1623912D01*
X1625148Y178180D01*
X1647544D01*
X1648879Y179515D01*
X1650113D01*
X1651000Y178628D01*
G01X1657835Y165884D02*
X1654687D01*
X1651432Y169139D01*
X1646411D01*
X1644950Y170600D01*
X1639600D01*
X1635400Y174800D01*
X1620300D01*
X1616825Y171325D01*
X1602370D01*
X1601754Y170709D01*
X1593741D01*
X1582790Y181660D01*
X1566876D01*
X1566486Y181270D01*
G01X1623276Y165798D02*
Y164976D01*
X1621600Y163300D01*
Y162100D01*
X1620753Y161253D01*
X1603153D01*
X1602600Y160700D01*
X1589322D01*
X1577392Y172630D01*
X1565786D01*
X1560148Y178268D01*
X1544073D01*
X1544072Y178267D01*
X1543450D01*
X1543449Y178266D01*
X1542827D01*
X1542825Y178268D01*
X1542126D01*
X1537990Y182404D01*
Y183026D01*
X1537991Y183027D01*
Y183203D01*
X1537989Y183205D01*
Y183827D01*
X1537990Y183828D01*
Y185074D01*
X1537991Y185075D01*
Y185697D01*
X1538852Y186558D01*
Y202887D01*
X1542021Y206056D01*
Y229787D01*
X1537972Y233836D01*
Y236000D01*
G01X1571501Y180031D02*
X1583170D01*
X1593243Y169958D01*
X1602066D01*
X1602508Y170400D01*
X1617102D01*
X1618636Y171934D01*
X1619993D01*
X1619995Y171936D01*
X1621241D01*
X1621416Y171761D01*
X1623791D01*
X1624966Y172936D01*
G01X1559675Y407934D02*
X1561031D01*
X1562786Y406179D01*
X1570021D01*
X1572945Y403255D01*
Y393437D01*
X1575913Y390469D01*
Y376830D01*
X1571951Y372868D01*
Y364849D01*
X1573026Y363774D01*
Y340466D01*
X1571622Y339062D01*
Y336942D01*
X1572372Y336192D01*
Y328728D01*
X1567402Y323758D01*
Y318612D01*
X1571702Y314312D01*
Y306984D01*
X1570344Y305626D01*
Y301978D01*
X1567579Y299213D01*
Y289491D01*
X1556644Y278556D01*
Y261532D01*
X1562800Y255376D01*
X1568067D01*
X1570071Y257380D01*
X1573000D01*
X1577376Y253004D01*
Y218289D01*
X1608056Y187609D01*
Y184771D01*
G01X1541325Y245090D02*
X1540846Y244611D01*
Y232702D01*
X1543018Y230530D01*
Y205989D01*
X1539604Y202575D01*
Y186246D01*
X1538743Y185385D01*
Y182715D01*
X1542438Y179020D01*
X1543137D01*
X1543138Y179019D01*
X1543760D01*
X1543761Y179020D01*
X1560460D01*
X1566098Y173382D01*
X1578140D01*
X1589722Y161800D01*
X1600164D01*
X1602664Y164300D01*
X1615306D01*
X1616891Y165885D01*
G01X1709900Y187300D02*
X1709100Y186500D01*
X1706400D01*
X1705338Y187562D01*
Y193805D01*
X1702039Y197104D01*
X1690040D01*
X1688650Y195714D01*
Y190974D01*
X1686576Y188900D01*
X1683263D01*
X1682778Y189385D01*
X1682331D01*
X1682330Y189384D01*
X1677283D01*
X1672370Y184471D01*
X1672341Y184500D01*
X1659774D01*
X1658234Y182960D01*
Y177534D01*
X1656984Y176284D01*
X1656547D01*
X1656546Y176283D01*
X1649255D01*
X1649254Y176284D01*
X1646413D01*
X1646395Y176302D01*
X1619676D01*
X1619658Y176284D01*
X1618142D01*
X1616898Y175040D01*
X1615674D01*
X1614712Y176002D01*
X1591860D01*
X1583914Y183948D01*
X1543280D01*
X1543100Y184128D01*
G01X1570289Y384368D02*
X1571668D01*
X1573155Y382881D01*
Y378185D01*
X1564274Y369304D01*
Y351545D01*
X1559800Y347071D01*
Y334300D01*
X1555737Y330237D01*
Y326937D01*
X1558920Y323754D01*
Y313616D01*
X1557265Y311961D01*
Y302051D01*
X1561332Y297984D01*
Y289903D01*
X1560153Y288724D01*
X1558800D01*
X1554580Y284504D01*
Y280748D01*
X1553636Y279804D01*
Y260064D01*
X1561300Y252400D01*
Y247457D01*
X1566328Y242429D01*
Y228060D01*
X1598006Y196382D01*
Y192421D01*
G01X1530500Y287700D02*
Y282530D01*
X1530737Y282293D01*
Y276524D01*
X1529572Y275359D01*
Y263832D01*
X1539749Y253655D01*
Y240025D01*
X1536384Y236660D01*
Y234360D01*
X1541269Y229475D01*
Y206368D01*
X1538100Y203199D01*
Y186870D01*
X1537239Y186009D01*
Y185387D01*
X1537238Y185386D01*
Y184140D01*
X1537237Y184139D01*
Y182893D01*
X1537238Y182892D01*
Y182092D01*
X1541814Y177516D01*
X1542513D01*
X1542516Y177513D01*
X1543138D01*
X1543139Y177514D01*
X1543761D01*
X1543762Y177515D01*
X1544384D01*
X1544385Y177516D01*
X1553209D01*
X1556701Y174024D01*
X1559710D01*
X1563103Y170631D01*
X1570331D01*
X1571500Y171800D01*
X1575607D01*
X1587607Y159800D01*
X1601600D01*
X1603400Y158000D01*
X1620800D01*
X1621700Y158900D01*
Y160500D01*
X1622300Y161100D01*
X1623900D01*
X1624782Y161982D01*
Y163280D01*
X1625802Y164300D01*
X1631073D01*
X1635788Y159585D01*
G01X1654638Y159685D02*
X1654006D01*
X1652321Y158000D01*
X1650852D01*
X1650061Y157209D01*
Y156023D01*
X1648998Y154960D01*
X1647490D01*
X1646880Y155570D01*
Y157170D01*
X1646050Y158000D01*
X1641586D01*
X1640413Y159173D01*
Y160196D01*
X1639549Y161060D01*
X1638527D01*
X1637351Y162236D01*
Y163258D01*
X1636199Y164410D01*
X1635176D01*
X1632226Y167360D01*
X1606381D01*
X1604254Y165233D01*
X1601306D01*
X1600921Y164848D01*
X1594281D01*
X1583937Y175192D01*
X1566858D01*
G01X1637870Y195077D02*
Y193869D01*
X1632288Y188287D01*
Y184494D01*
X1628978Y181184D01*
X1626396D01*
X1623823Y183757D01*
Y185713D01*
X1622741Y186795D01*
X1619123D01*
X1617925Y185597D01*
Y185051D01*
X1616069Y183195D01*
X1606067D01*
X1605500Y183762D01*
Y186419D01*
X1601959Y189960D01*
X1596938D01*
X1594900Y191998D01*
Y198424D01*
X1565576Y227748D01*
Y242024D01*
X1552884Y254716D01*
Y278668D01*
X1551324Y280228D01*
Y291900D01*
X1554752Y295328D01*
X1554775D01*
G01X1549693Y196707D02*
X1552800Y193600D01*
Y191200D01*
X1556963Y187037D01*
X1587473D01*
X1592210Y182300D01*
X1603001D01*
X1605957Y179344D01*
X1609652D01*
X1611936Y181628D01*
X1616324D01*
X1617847Y180105D01*
X1619153D01*
X1619292Y180244D01*
X1619293D01*
X1619999Y180950D01*
X1624504D01*
X1625772Y179682D01*
X1635143D01*
X1636952Y181491D01*
Y186032D01*
X1638204Y187284D01*
X1642121D01*
X1642457Y186948D01*
G01X1557787Y192236D02*
X1559623D01*
X1561719Y190140D01*
X1591582D01*
X1593218Y191776D01*
G01X1573950Y338050D02*
X1573977Y338023D01*
Y328205D01*
X1568906Y323134D01*
Y319236D01*
X1573208Y314934D01*
Y306252D01*
X1572237Y305281D01*
Y292021D01*
X1558148Y277932D01*
Y262352D01*
X1559248Y261252D01*
X1571748D01*
X1578880Y254120D01*
Y242704D01*
X1596488Y225096D01*
Y210133D01*
X1606645Y199976D01*
X1639824D01*
X1640850Y198950D01*
Y195822D01*
X1646346Y190326D01*
X1671714D01*
X1676924Y195536D01*
Y196731D01*
G01X1584233Y427947D02*
Y426667D01*
X1574507Y416941D01*
Y393234D01*
X1576664Y391077D01*
Y366422D01*
X1573778Y363536D01*
Y340107D01*
X1572374Y338703D01*
Y337397D01*
X1573124Y336647D01*
Y328416D01*
X1568154Y323446D01*
Y318924D01*
X1572454Y314624D01*
Y306562D01*
X1571485Y305593D01*
Y302055D01*
X1568331Y298901D01*
Y289179D01*
X1557396Y278244D01*
Y261848D01*
X1558744Y260500D01*
X1564080D01*
X1565140Y259440D01*
Y257790D01*
X1565970Y256960D01*
X1567840D01*
X1569632Y258752D01*
X1572692D01*
X1578128Y253316D01*
Y242392D01*
X1594981Y225539D01*
Y205290D01*
X1613403Y186868D01*
X1613593D01*
X1615553Y184908D01*
G01X1564427Y311083D02*
X1566820Y308690D01*
Y289796D01*
X1555892Y278868D01*
Y261220D01*
X1562488Y254624D01*
X1569324D01*
X1570500Y255800D01*
X1571876D01*
G01X1598028Y256422D02*
X1597422D01*
X1590491Y249491D01*
X1582509D01*
X1580700Y251300D01*
Y254340D01*
X1572380Y262660D01*
X1559832D01*
X1559556Y262936D01*
Y277348D01*
X1574008Y291800D01*
Y303996D01*
X1574616Y304604D01*
Y316645D01*
X1572371Y318890D01*
Y324607D01*
X1576074Y328310D01*
Y359600D01*
G01X1570318Y238116D02*
Y239971D01*
X1565688Y244601D01*
Y250936D01*
X1563504Y253120D01*
X1561864D01*
X1554388Y260596D01*
Y279492D01*
X1555332Y280436D01*
Y284146D01*
X1558900Y287714D01*
X1560207D01*
X1562084Y289591D01*
Y300378D01*
X1562072Y300390D01*
Y327003D01*
X1569211Y334142D01*
G01X1572700Y239400D02*
X1566440Y245660D01*
Y251248D01*
X1563816Y253872D01*
X1562176D01*
X1555140Y260908D01*
Y279180D01*
X1556280Y280320D01*
Y284009D01*
X1559147Y286876D01*
X1560453D01*
X1562836Y289259D01*
Y300788D01*
X1562824Y300800D01*
Y325155D01*
X1569211Y331542D01*
G01X1603050Y432523D02*
X1601304Y430777D01*
Y414768D01*
X1593400Y406864D01*
Y403201D01*
X1590580Y400381D01*
Y396344D01*
X1588071Y393835D01*
Y366321D01*
X1584924Y363174D01*
Y350875D01*
X1589467Y346332D01*
X1590303D01*
X1594760Y341875D01*
Y329943D01*
X1592077Y327260D01*
X1591554D01*
X1587884Y323590D01*
Y311592D01*
X1585472Y309180D01*
Y306569D01*
X1589670Y302371D01*
Y294978D01*
X1592178Y292470D01*
Y291827D01*
X1592177Y291826D01*
Y291204D01*
X1614582Y268799D01*
Y223489D01*
X1622674Y215397D01*
X1631545D01*
X1633556Y217408D01*
X1650688D01*
X1652467Y215629D01*
X1657519D01*
X1659643Y213505D01*
G01X1587800Y308200D02*
X1591788Y312188D01*
Y316878D01*
X1599372Y324462D01*
Y352855D01*
X1607412Y360895D01*
G01X1564411Y315210D02*
Y323191D01*
X1570868Y329648D01*
Y335568D01*
X1567780Y338656D01*
Y346980D01*
X1567793Y346993D01*
Y357433D01*
X1568810Y358450D01*
Y371026D01*
X1575162Y377378D01*
Y385628D01*
X1573136Y387654D01*
X1571375D01*
G01X1569425Y397794D02*
X1568132Y396501D01*
G02X1567476Y396229I-656J655D01*
G01X1567470D01*
X1566688Y395778D01*
G03X1565901Y394462I787J-1364D01*
G01Y394333D01*
G02X1564738Y392398I-2326J81D01*
G03Y389670I787J-1364D01*
G02X1565901Y387735I-1163J-2016D01*
G02X1565860Y387209I-2303J-85D01*
G02X1564738Y385638I-2283J445D01*
G03Y382910I787J-1364D01*
G02X1565901Y380975I-1163J-2016D01*
G01Y379786D01*
X1567123Y378564D01*
Y375636D01*
X1562770Y371283D01*
Y357383D01*
X1560910Y355523D01*
X1556634D01*
X1555300Y354189D01*
Y350700D01*
X1553200Y348600D01*
Y346300D01*
X1549900Y343000D01*
Y327029D01*
X1550493Y326436D01*
Y321840D01*
X1549573Y320920D01*
Y318928D01*
X1550799Y317702D01*
Y313096D01*
X1548668Y310965D01*
Y308520D01*
X1548807Y308381D01*
Y308082D01*
X1557457Y299432D01*
Y288457D01*
X1553600Y284600D01*
Y282400D01*
X1552900Y281700D01*
G01X1577486Y307621D02*
Y305482D01*
X1575416Y303412D01*
Y289790D01*
X1576500Y288706D01*
Y288500D01*
X1577500Y287500D01*
X1583000D01*
X1594480Y276020D01*
Y264072D01*
X1600000Y258552D01*
Y255882D01*
X1597118Y253000D01*
X1596000D01*
X1594648Y251648D01*
Y230204D01*
X1597961Y226891D01*
Y210846D01*
X1608079Y200728D01*
X1642269D01*
X1649930Y193067D01*
X1669849D01*
G01X1585560Y421324D02*
X1582321D01*
X1576457Y415460D01*
Y393585D01*
X1578570Y391472D01*
Y363985D01*
X1579938Y362617D01*
Y347562D01*
X1586122Y341378D01*
Y330104D01*
X1578970Y322952D01*
Y312637D01*
X1581500Y310107D01*
Y307093D01*
X1581499Y307092D01*
Y305222D01*
X1581500Y305221D01*
Y304448D01*
X1580290Y303238D01*
Y299260D01*
X1582110Y297440D01*
X1582680D01*
X1584289Y295831D01*
Y292911D01*
X1586474Y290726D01*
Y289459D01*
X1606090Y269843D01*
Y261832D01*
X1604186Y259928D01*
Y246309D01*
X1600292Y242415D01*
Y237214D01*
X1602850Y234656D01*
Y219595D01*
X1606176Y216269D01*
Y212269D01*
X1613384Y205061D01*
X1652268D01*
X1653348Y203981D01*
X1672083D01*
X1676184Y208082D01*
X1720175D01*
X1722653Y205604D01*
X1843646D01*
X1847200Y202050D01*
G01X1603000Y435500D02*
X1600152Y432652D01*
Y424652D01*
X1592900Y417400D01*
Y412100D01*
X1593900Y411100D01*
Y408500D01*
X1592600Y407200D01*
Y403500D01*
X1589259Y400159D01*
Y396761D01*
X1588198Y395700D01*
X1585700D01*
X1584400Y394400D01*
Y392400D01*
X1585719Y391081D01*
Y365033D01*
X1583698Y363012D01*
Y349122D01*
X1587240Y345580D01*
X1589991D01*
X1594008Y341563D01*
Y330255D01*
X1591765Y328012D01*
X1590478D01*
X1585962Y323496D01*
Y319090D01*
X1587132Y317920D01*
Y311904D01*
X1584600Y309372D01*
Y307001D01*
X1584599Y307000D01*
Y306378D01*
X1588910Y302067D01*
Y294674D01*
X1591425Y292159D01*
Y290892D01*
X1613806Y268511D01*
Y219494D01*
X1615362Y217938D01*
Y213507D01*
G01X1609051Y243415D02*
X1612218Y246582D01*
Y263192D01*
X1612690Y263664D01*
Y268563D01*
X1590673Y290580D01*
Y291847D01*
X1588140Y294380D01*
Y301773D01*
X1583756Y306157D01*
Y309592D01*
X1585356Y311192D01*
X1585352Y311196D01*
Y314441D01*
X1583903Y315890D01*
Y317263D01*
X1584655Y318015D01*
Y323253D01*
X1590166Y328764D01*
X1591453D01*
X1593256Y330567D01*
Y341251D01*
X1589679Y344828D01*
X1586928D01*
X1582946Y348810D01*
Y363324D01*
X1584967Y365345D01*
Y390634D01*
X1583580Y392021D01*
Y400120D01*
X1581639Y402061D01*
Y402685D01*
X1581638Y402686D01*
Y405592D01*
X1584166Y408120D01*
X1587814D01*
X1591147Y411453D01*
Y417947D01*
X1597760Y424560D01*
Y443460D01*
X1600400Y446100D01*
G01X1883350Y202410D02*
X1882806Y201866D01*
X1872680D01*
X1869787Y204759D01*
X1849587D01*
X1842443Y211903D01*
Y215410D01*
X1838238Y219615D01*
X1830418D01*
X1826527Y215724D01*
X1718479D01*
X1713845Y211090D01*
X1686162D01*
X1683020Y214232D01*
X1670884D01*
X1666793Y210141D01*
X1657144D01*
X1655033Y212252D01*
X1632744D01*
X1630310Y209818D01*
X1612668D01*
X1609127Y213359D01*
Y217359D01*
X1606172Y220314D01*
Y235375D01*
X1603148Y238399D01*
Y241952D01*
X1607538Y246342D01*
X1608638D01*
X1610540Y248244D01*
Y255050D01*
X1608400Y257190D01*
Y270725D01*
X1589169Y289956D01*
Y291223D01*
X1586545Y293847D01*
Y296920D01*
X1583500Y299965D01*
Y300560D01*
G01X1883539Y199813D02*
X1882438Y200914D01*
X1871827D01*
X1868734Y204007D01*
X1849275D01*
X1849269Y204013D01*
X1848986D01*
X1841491Y211508D01*
Y215015D01*
X1837843Y218663D01*
X1830813D01*
X1826922Y214772D01*
X1718591D01*
X1714157Y210338D01*
X1683337D01*
X1680395Y213280D01*
X1671279D01*
X1667388Y209389D01*
X1656760D01*
X1654849Y211300D01*
X1633139D01*
X1630705Y208866D01*
X1612273D01*
X1608175Y212964D01*
Y216964D01*
X1605220Y219919D01*
Y234980D01*
X1602196Y238004D01*
Y241995D01*
X1602396Y242195D01*
Y242264D01*
X1605730Y245598D01*
Y258980D01*
X1607630Y260880D01*
Y270431D01*
X1588388Y289673D01*
Y290940D01*
X1585793Y293535D01*
Y296511D01*
X1583358Y298946D01*
X1582806D01*
X1581924Y299828D01*
Y301544D01*
X1583500Y303120D01*
G01X1559500Y290300D02*
Y298752D01*
X1549420Y308832D01*
Y310653D01*
X1553256Y314489D01*
Y324956D01*
X1551124Y327088D01*
Y342712D01*
X1554696Y346284D01*
Y347256D01*
X1563522Y356082D01*
Y368635D01*
X1563523D01*
Y369616D01*
X1568014Y374107D01*
Y378653D01*
X1569045Y379684D01*
Y382412D01*
X1568719Y382738D01*
Y385448D01*
X1569045Y385774D01*
Y388305D01*
X1566316Y391034D01*
X1565525D01*
G01X1611761Y216250D02*
X1607338Y220673D01*
Y235839D01*
X1604300Y238877D01*
Y242040D01*
X1607850Y245590D01*
X1608950D01*
X1611466Y248106D01*
Y263504D01*
X1611870Y263908D01*
Y268319D01*
X1589921Y290268D01*
Y291535D01*
X1587370Y294086D01*
Y301479D01*
X1583003Y305846D01*
Y306468D01*
X1583004Y306469D01*
Y310004D01*
X1584600Y311600D01*
Y313972D01*
X1582940Y315632D01*
Y317415D01*
X1583523Y317998D01*
Y323185D01*
X1589854Y329516D01*
X1591141D01*
X1592504Y330879D01*
Y340750D01*
X1589178Y344076D01*
X1586616D01*
X1582194Y348498D01*
Y363921D01*
X1584215Y365942D01*
Y390286D01*
X1580406Y394095D01*
Y396827D01*
X1580434Y396855D01*
Y406283D01*
X1586127Y411976D01*
X1587000D01*
G01X1571450Y359650D02*
X1568545Y356745D01*
Y338955D01*
X1571620Y335880D01*
Y329040D01*
X1566650Y324070D01*
Y318300D01*
X1566910Y318040D01*
Y315117D01*
G01X1667356Y213096D02*
Y213235D01*
X1665806Y214785D01*
X1660843D01*
X1655952Y219676D01*
X1634760D01*
X1631233Y216149D01*
X1622986D01*
X1615334Y223801D01*
Y269111D01*
X1592930Y291515D01*
Y292782D01*
X1590440Y295272D01*
Y302665D01*
X1586224Y306881D01*
Y308868D01*
X1588636Y311280D01*
Y316235D01*
X1597868Y325467D01*
Y355569D01*
X1612404Y370105D01*
Y383588D01*
X1610887Y385105D01*
Y407036D01*
X1612825Y408974D01*
G01X1864464Y198466D02*
X1864390Y198540D01*
Y199210D01*
X1860382Y203218D01*
X1848532D01*
X1845386Y206364D01*
X1722957D01*
X1720487Y208834D01*
X1682713D01*
X1679771Y211776D01*
X1671903D01*
X1664860Y204733D01*
X1654551D01*
X1653471Y205813D01*
X1613696D01*
X1607023Y212486D01*
Y216486D01*
X1604068Y219441D01*
Y234502D01*
X1601044Y237526D01*
Y242081D01*
X1604938Y245975D01*
Y259616D01*
X1606860Y261538D01*
Y270137D01*
X1587456Y289541D01*
Y290808D01*
X1585041Y293223D01*
Y296199D01*
X1583047Y298193D01*
X1582476D01*
X1581050Y299619D01*
Y302934D01*
X1582252Y304136D01*
Y305533D01*
X1582251Y305534D01*
Y306780D01*
X1582252Y306781D01*
Y310419D01*
X1579750Y312921D01*
Y321673D01*
X1588345Y330268D01*
X1590829D01*
X1591752Y331191D01*
Y340438D01*
X1588867Y343323D01*
X1586305D01*
X1581442Y348186D01*
Y363240D01*
X1580078Y364604D01*
Y392170D01*
X1578063Y394185D01*
Y413828D01*
X1583183Y418948D01*
X1588112D01*
X1594976Y425812D01*
Y436942D01*
X1591446Y440472D01*
G01X1588870Y440546D02*
Y439730D01*
X1591300Y437300D01*
Y436001D01*
X1591824Y435477D01*
Y423724D01*
X1587800Y419700D01*
X1582600D01*
X1577311Y414411D01*
Y393873D01*
X1579322Y391862D01*
Y364297D01*
X1580690Y362929D01*
Y347874D01*
X1586975Y341589D01*
Y336125D01*
X1590176Y332924D01*
Y331844D01*
G01X1560024Y329200D02*
X1561600Y330776D01*
Y340171D01*
X1561424Y340347D01*
Y343413D01*
X1567041Y349030D01*
Y355459D01*
X1565287Y357213D01*
Y368930D01*
X1574228Y377871D01*
Y383353D01*
X1571521Y386060D01*
X1570680D01*
X1569805Y386935D01*
Y388585D01*
X1571430Y390210D01*
Y392138D01*
X1569805Y393763D01*
Y395065D01*
X1569866Y395126D01*
Y395432D01*
X1571372Y396938D01*
Y398172D01*
X1568370Y401174D01*
X1567475D01*
G01X1927064Y207564D02*
X1925419Y205919D01*
X1915676D01*
X1906344Y196587D01*
X1897642D01*
X1897153Y197076D01*
X1894656D01*
X1891819Y194239D01*
X1865268D01*
X1862824Y196683D01*
Y199287D01*
X1859688Y202423D01*
X1859470D01*
X1859465Y202428D01*
X1852595D01*
X1852590Y202423D01*
X1850994D01*
X1849037Y200466D01*
X1842035D01*
X1838492Y204009D01*
X1722626D01*
X1719305Y207330D01*
X1680596D01*
X1677172Y203906D01*
X1673216D01*
X1672539Y203229D01*
X1652775D01*
X1651872Y204132D01*
X1611540D01*
X1602098Y213574D01*
Y234344D01*
X1599540Y236902D01*
Y242727D01*
X1603167Y246354D01*
Y265910D01*
X1602353Y266724D01*
Y268557D01*
X1603784Y269988D01*
Y271085D01*
X1581287Y293582D01*
Y294244D01*
X1579510Y296021D01*
Y303522D01*
X1580748Y304760D01*
Y304909D01*
X1580747Y304910D01*
Y307404D01*
X1580748Y307405D01*
Y309795D01*
X1578196Y312347D01*
Y323242D01*
X1585370Y330416D01*
Y341066D01*
X1579186Y347250D01*
Y362305D01*
X1577818Y363673D01*
Y391160D01*
X1575705Y393273D01*
Y393307D01*
X1575258Y393754D01*
Y415740D01*
X1583353Y423835D01*
X1587559D01*
G01X1600552Y261281D02*
X1600537D01*
X1597112Y264706D01*
Y264769D01*
X1595970Y265911D01*
Y276530D01*
X1583356Y289144D01*
X1578054D01*
X1576824Y290374D01*
Y302828D01*
X1579339Y305343D01*
Y308516D01*
X1576788Y311067D01*
Y316465D01*
X1573779Y319474D01*
Y323847D01*
X1578342Y328410D01*
Y336047D01*
X1581090Y338795D01*
G01X1672265Y473600D02*
X1671125Y474740D01*
X1658918D01*
X1657626Y473448D01*
X1646416D01*
X1640640Y479224D01*
X1619609D01*
X1619083Y478698D01*
X1612092D01*
X1609178Y475784D01*
Y466944D01*
X1613218Y462904D01*
Y461224D01*
X1604176Y452182D01*
Y443634D01*
X1598920Y438378D01*
Y424520D01*
X1592000Y417600D01*
Y411900D01*
X1593050Y410850D01*
Y408750D01*
X1591200Y406900D01*
X1587671D01*
X1585348Y404577D01*
Y399749D01*
X1587683Y397414D01*
G01X1923500Y579500D02*
X1923400D01*
X1919629Y575729D01*
Y561471D01*
X1935029Y546071D01*
Y539795D01*
X1937967Y536857D01*
Y525911D01*
X1932003Y519947D01*
X1928006D01*
X1923419Y515360D01*
X1921760D01*
X1913900Y507500D01*
X1894299D01*
X1888000Y501201D01*
Y484346D01*
X1879561Y475907D01*
Y470572D01*
X1872730Y463741D01*
X1848833D01*
X1847052Y461960D01*
X1835553D01*
X1834133Y460540D01*
X1720857D01*
X1708121Y473276D01*
X1684118D01*
X1682466Y471624D01*
X1671935D01*
X1669571Y473988D01*
X1659230D01*
X1657938Y472696D01*
X1646104D01*
X1640328Y478472D01*
X1619921D01*
X1619395Y477946D01*
X1612404D01*
X1609930Y475472D01*
Y468604D01*
X1612405Y466129D01*
X1616972D01*
X1617500Y465601D01*
Y463036D01*
X1606080Y451616D01*
Y447529D01*
X1606079Y447528D01*
Y445034D01*
X1606080Y445033D01*
Y442844D01*
X1605751Y442515D01*
Y439780D01*
X1605752Y439779D01*
Y431538D01*
X1605328Y431114D01*
Y411380D01*
X1604348Y410400D01*
X1598000D01*
X1594200Y406600D01*
Y402874D01*
X1591332Y400006D01*
Y395550D01*
X1588823Y393041D01*
Y363792D01*
X1587684Y362653D01*
G01X1586500Y358400D02*
X1588194Y360094D01*
X1589223D01*
X1589575Y360446D01*
Y392417D01*
X1592084Y394926D01*
Y399694D01*
X1600424Y408034D01*
X1603046D01*
X1606082Y411070D01*
Y430804D01*
X1606504Y431226D01*
Y442204D01*
X1606832Y442532D01*
Y445345D01*
X1606831Y445346D01*
Y447216D01*
X1606832Y447217D01*
Y447774D01*
X1619158Y460100D01*
X1623620D01*
X1631918Y468398D01*
X1633811D01*
X1637357Y471944D01*
X1658250D01*
X1659531Y473225D01*
X1669270D01*
X1671623Y470872D01*
X1682778D01*
X1684430Y472524D01*
X1707809D01*
X1720545Y459788D01*
X1834445D01*
X1835865Y461208D01*
X1847364D01*
X1849145Y462989D01*
X1874289D01*
X1881103Y469803D01*
Y475931D01*
X1889000Y483828D01*
Y500500D01*
X1895000Y506500D01*
X1914100D01*
X1922208Y514608D01*
X1923878D01*
X1928270Y519000D01*
X1932720D01*
X1939110Y525390D01*
Y537910D01*
X1943000Y541800D01*
Y543800D01*
X1940500Y546300D01*
X1939800D01*
G01X1923600Y575500D02*
X1921133Y573033D01*
Y562738D01*
X1927507Y556364D01*
X1932465D01*
X1935529Y553300D01*
X1936500D01*
X1946500Y543300D01*
Y530652D01*
X1933344Y517496D01*
X1928894D01*
X1924502Y513104D01*
X1923114D01*
X1912810Y502800D01*
X1904052D01*
X1898000Y496748D01*
Y490700D01*
X1883613Y476313D01*
Y466084D01*
X1879014Y461485D01*
X1849769D01*
X1847988Y459704D01*
X1836489D01*
X1835069Y458284D01*
X1719921D01*
X1707185Y471020D01*
X1685054D01*
X1683402Y469368D01*
X1670999D01*
X1668646Y471721D01*
X1660155D01*
X1658874Y470440D01*
X1637981D01*
X1634435Y466894D01*
X1632542D01*
X1624196Y458548D01*
X1619734D01*
X1608336Y447150D01*
Y446593D01*
X1608335Y446592D01*
Y445970D01*
X1608336Y445969D01*
Y441908D01*
X1608009Y441581D01*
Y430603D01*
X1607586Y430180D01*
Y410446D01*
X1603670Y406530D01*
X1601048D01*
X1593588Y399070D01*
Y389434D01*
X1591115Y386961D01*
Y357880D01*
X1589911Y356676D01*
X1588276D01*
X1586500Y354900D01*
G01X1926600Y559500D02*
X1926602D01*
X1928986Y557116D01*
X1932777D01*
X1935493Y554400D01*
X1936500D01*
X1949676Y541224D01*
Y537176D01*
X1948400Y535900D01*
Y530424D01*
X1938900Y520924D01*
Y505820D01*
X1934376Y501296D01*
X1905732D01*
X1899772Y495336D01*
Y486494D01*
X1887791Y474513D01*
Y468134D01*
X1879638Y459981D01*
X1850393D01*
X1848612Y458200D01*
X1837113D01*
X1835693Y456780D01*
X1719297D01*
X1706561Y469516D01*
X1685678D01*
X1684026Y467864D01*
X1670375D01*
X1668022Y470217D01*
X1660779D01*
X1659498Y468936D01*
X1638605D01*
X1635058Y465389D01*
X1633165D01*
X1625000Y457224D01*
Y449800D01*
X1623600Y448400D01*
X1612271D01*
X1609840Y445969D01*
Y441284D01*
X1609513Y440957D01*
Y429979D01*
X1609090Y429556D01*
Y409822D01*
X1604294Y405026D01*
X1601672D01*
X1595092Y398446D01*
Y388810D01*
X1592619Y386337D01*
Y354734D01*
X1590535Y352650D01*
X1589565D01*
X1587911Y350996D01*
X1587032D01*
G01X1547975Y394414D02*
X1548216D01*
X1549830Y392800D01*
X1553200D01*
X1553850Y393450D01*
Y395050D01*
X1555600Y396800D01*
Y398344D01*
X1557896Y400640D01*
Y402011D01*
X1559160Y403275D01*
G01X1582600Y389300D02*
X1580830Y391070D01*
Y392498D01*
X1578902Y394426D01*
Y410730D01*
X1583354Y415182D01*
X1584282D01*
X1586400Y417300D01*
X1588984D01*
X1595828Y424144D01*
Y438672D01*
X1592400Y442100D01*
X1590750D01*
X1589774Y443076D01*
Y445953D01*
X1590697Y446876D01*
X1591628D01*
X1598100Y453348D01*
Y462012D01*
X1607593Y471505D01*
Y476327D01*
X1614242Y482976D01*
X1619286D01*
X1621534Y480728D01*
X1641264D01*
X1645292Y476700D01*
X1651243D01*
X1652943Y478400D01*
X1666736D01*
X1667616Y477520D01*
X1684773D01*
X1685832Y476461D01*
X1709984D01*
X1721768Y464677D01*
X1827744D01*
X1833767Y470700D01*
X1851500D01*
X1858900Y478100D01*
X1871800D01*
X1877400Y483700D01*
Y494798D01*
X1881677Y499075D01*
Y523676D01*
X1887566Y529565D01*
X1891160D01*
X1892903Y531308D01*
Y535444D01*
X1907416Y549957D01*
X1915793D01*
X1922000Y543750D01*
G01X1536275Y394414D02*
Y398505D01*
X1538370Y400600D01*
Y401970D01*
X1539210Y402810D01*
X1555981D01*
X1557725Y404554D01*
G01X1546182Y355446D02*
X1551906D01*
X1554140Y357680D01*
X1559593D01*
X1560866Y358953D01*
Y363512D01*
X1560867Y363513D01*
Y371506D01*
X1563044Y373683D01*
Y376712D01*
X1563195Y376863D01*
Y379197D01*
X1563575Y379577D01*
Y380894D01*
G01X1590037Y432515D02*
X1588102Y434450D01*
X1564998D01*
X1563950Y433402D01*
G01X1565145Y401887D02*
Y400855D01*
X1567283Y398717D01*
G02X1567454Y398304I-413J-413D01*
G01Y397895D01*
G02X1566755Y396686I-1395J0D01*
G01X1566312Y396430D01*
G03X1565149Y394495I1163J-2016D01*
G01Y394366D01*
G02X1564362Y393050I-1574J48D01*
G03Y389019I1163J-2015D01*
G02X1565150Y387708I-787J-1365D01*
G02X1565122Y387353I-1552J-56D01*
G02X1564363Y386289I-1546J300D01*
G03X1564362Y382259I1162J-2015D01*
G02X1564803Y381881I-788J-1365D01*
G02X1565149Y380894I-1235J-987D01*
G01Y379692D01*
X1563955Y378498D01*
Y373531D01*
X1561618Y371194D01*
Y358160D01*
X1560133Y356675D01*
X1555201D01*
X1550972Y352446D01*
X1543528D01*
G01X1842400Y516800D02*
X1841300Y517900D01*
Y525100D01*
X1834200Y532200D01*
X1822300D01*
X1813480Y541020D01*
X1803220D01*
X1787800Y525600D01*
Y520700D01*
X1786800Y519700D01*
X1777300D01*
X1774100Y516500D01*
X1764800D01*
X1762700Y518600D01*
X1745500D01*
X1738000Y511100D01*
X1723244D01*
X1708299Y496155D01*
X1686088D01*
X1675690Y506553D01*
X1669148D01*
X1669147Y506552D01*
X1657208D01*
X1653556Y502900D01*
X1582700D01*
X1575900Y509700D01*
X1569700D01*
X1566800Y506800D01*
Y501400D01*
X1566200Y500800D01*
Y499200D01*
X1555900Y488900D01*
Y486700D01*
X1553700Y484500D01*
Y482900D01*
X1551600Y480800D01*
Y479600D01*
X1550100Y478100D01*
Y476900D01*
X1548200Y475000D01*
Y473700D01*
X1546200Y471700D01*
Y470100D01*
X1544100Y468000D01*
Y466400D01*
X1542100Y464400D01*
Y463300D01*
X1539246Y460446D01*
X1538225D01*
G01X1559675Y407934D02*
X1561274Y409533D01*
X1570232D01*
X1573568Y412869D01*
Y418223D01*
X1581939Y426594D01*
G01X1792805Y574675D02*
X1792826Y574654D01*
Y574126D01*
X1790218Y571518D01*
Y558332D01*
X1791828Y556722D01*
Y543105D01*
X1781904Y533181D01*
Y528834D01*
X1775227Y522157D01*
X1771343D01*
X1768600Y524900D01*
X1762400D01*
X1758700Y521200D01*
X1744600D01*
X1739128Y515728D01*
X1706118D01*
X1705418Y515028D01*
X1698407D01*
X1697187Y513808D01*
X1659530D01*
X1654576Y508854D01*
X1644084D01*
X1642601Y510337D01*
X1642565D01*
X1641949Y510953D01*
X1638050D01*
X1630782Y518221D01*
X1625855D01*
X1615508Y507874D01*
X1581655D01*
X1577421Y512108D01*
X1560857D01*
X1558280Y509531D01*
Y497414D01*
X1555858Y494992D01*
X1553341D01*
X1553225Y494876D01*
X1553224D01*
X1548615Y490267D01*
Y490266D01*
X1547600Y489251D01*
G01X1543700Y488770D02*
Y491300D01*
X1551230Y498830D01*
Y510589D01*
X1551229Y510590D01*
Y511544D01*
X1554097Y514412D01*
X1578617D01*
X1582775Y510254D01*
X1608457D01*
X1613795Y515592D01*
X1618286D01*
X1627622Y524928D01*
G01X1803900Y491500D02*
Y488203D01*
X1799145Y483448D01*
X1784082D01*
X1779962Y479328D01*
X1731991D01*
X1730298Y481021D01*
X1709923D01*
X1706093Y484851D01*
X1700846D01*
X1698335Y482340D01*
X1686931D01*
X1673607Y495664D01*
X1669464D01*
X1665329Y491529D01*
X1649372D01*
X1642331Y484488D01*
X1623094D01*
X1620508Y487074D01*
X1612953D01*
X1603833Y477954D01*
Y475139D01*
X1598225Y469531D01*
X1584073D01*
X1573150Y458608D01*
Y454526D01*
X1571949Y453325D01*
G01X1584200Y462610D02*
Y463320D01*
X1585418Y464538D01*
X1596430D01*
X1605337Y473445D01*
Y477330D01*
X1613474Y485467D01*
X1619987D01*
X1622470Y482984D01*
X1647447D01*
X1650792Y486329D01*
X1669199D01*
X1670104Y485424D01*
X1681193D01*
X1687100Y479517D01*
X1729674D01*
X1731367Y477824D01*
X1780033D01*
X1785243Y472614D01*
X1796682D01*
X1800499Y476431D01*
X1807551D01*
X1812330Y471652D01*
X1829662D01*
X1835879Y477869D01*
X1853422D01*
X1871856Y496303D01*
X1875732D01*
X1878728Y499299D01*
Y511778D01*
X1875946Y514560D01*
Y526903D01*
X1875942Y526907D01*
Y528213D01*
X1875946Y528217D01*
Y532576D01*
X1882270Y538900D01*
X1892500D01*
X1898850Y545250D01*
G01X1574126Y453575D02*
Y458520D01*
X1584385Y468779D01*
X1598537D01*
X1604585Y474827D01*
Y477642D01*
X1613162Y486219D01*
X1620299D01*
X1622782Y483736D01*
X1642643D01*
X1649684Y490777D01*
X1668084D01*
X1669608Y489253D01*
X1678954D01*
X1686950Y481257D01*
X1698042D01*
X1699030Y480269D01*
X1729986D01*
X1731679Y478576D01*
X1780345D01*
X1784821Y474100D01*
X1795784D01*
X1798867Y477183D01*
X1808914D01*
X1813693Y472404D01*
X1828210D01*
X1835365Y479559D01*
X1852195D01*
X1869966Y497330D01*
X1875695D01*
X1877976Y499611D01*
Y506320D01*
X1874277Y510019D01*
Y540943D01*
X1873510Y541710D01*
G01X1580370Y462090D02*
X1578550Y460270D01*
Y454483D01*
X1573317Y449250D01*
G01X1530425Y467206D02*
Y471392D01*
X1531063Y472030D01*
G01X1536794Y488813D02*
X1539730Y491749D01*
Y512659D01*
X1543887Y516816D01*
X1579614D01*
X1583682Y512748D01*
X1606782D01*
X1614544Y520510D01*
Y524683D01*
X1618964Y529103D01*
X1625444D01*
X1626518Y528029D01*
G01X1757478Y548192D02*
X1756293Y549377D01*
X1754842D01*
X1754460Y549759D01*
X1753154D01*
X1752772Y549377D01*
X1751809D01*
X1746466Y544034D01*
X1739234D01*
X1732213Y551055D01*
X1719587D01*
X1712566Y544034D01*
X1687830D01*
X1682106Y538310D01*
Y534330D01*
X1681113Y533337D01*
X1678934D01*
X1676865Y535406D01*
X1671565D01*
X1667109Y530950D01*
X1643852D01*
X1642610Y532192D01*
X1633624D01*
X1631516Y534300D01*
X1616484D01*
X1609836Y527652D01*
Y522843D01*
X1604449Y517456D01*
X1585635D01*
X1581567Y521524D01*
X1541494D01*
X1534276Y514306D01*
X1534275D01*
X1534020Y514051D01*
Y511930D01*
G01X1534325Y467206D02*
Y470864D01*
X1535179Y471718D01*
G01X1541215Y490082D02*
X1545710Y494577D01*
Y511722D01*
X1549552Y515564D01*
X1579095D01*
X1583063Y511596D01*
X1607260D01*
X1615796Y520132D01*
Y523344D01*
X1619643Y527191D01*
X1624942D01*
X1625680Y526453D01*
X1626918D01*
X1626969Y526504D01*
X1628275D01*
X1635738Y519041D01*
X1650441D01*
X1652218Y517264D01*
X1695753D01*
X1696973Y518484D01*
X1703984D01*
X1707337Y521837D01*
X1718228D01*
X1724987Y528596D01*
X1762879D01*
X1767071Y532788D01*
Y539477D01*
X1765232Y541316D01*
Y567798D01*
X1765934Y568500D01*
X1770771D01*
X1776955Y574684D01*
X1784384D01*
X1788300Y578600D01*
Y585100D01*
G01X1545418Y489353D02*
Y490177D01*
X1551958Y496717D01*
X1555946D01*
X1557128Y497899D01*
Y510009D01*
X1560379Y513260D01*
X1578139D01*
X1582297Y509102D01*
X1608935D01*
X1614273Y514440D01*
X1619300D01*
X1626754Y521894D01*
X1628873D01*
X1630159Y520608D01*
G01X1549368Y489956D02*
X1553536Y494124D01*
X1556054D01*
X1559480Y497550D01*
Y509101D01*
X1561335Y510956D01*
X1576943D01*
X1581177Y506722D01*
X1616210D01*
X1626557Y517069D01*
X1628654D01*
X1635922Y509801D01*
X1641471D01*
X1643308Y507964D01*
X1643344D01*
X1643606Y507702D01*
X1655054D01*
X1660008Y512656D01*
X1697665D01*
X1698885Y513876D01*
X1706004D01*
X1706704Y514576D01*
X1739786D01*
X1745084Y519874D01*
X1759274D01*
X1762100Y522700D01*
X1763500D01*
X1764400Y521800D01*
Y520501D01*
X1766305Y518596D01*
X1773296D01*
X1783057Y528357D01*
Y531496D01*
X1799881Y548320D01*
Y555192D01*
X1806902Y562213D01*
X1827187D01*
X1830634Y558766D01*
X1849204D01*
X1850196Y557774D01*
X1854156D01*
X1854278Y557652D01*
X1854284D01*
X1856900Y555036D01*
X1858073D01*
X1858085Y555024D01*
X1858212D01*
X1860962Y557774D01*
X1861428D01*
X1873426Y569772D01*
X1888645D01*
X1907122Y588249D01*
Y592086D01*
X1911212Y596176D01*
X1922057D01*
X1927671Y590562D01*
Y586954D01*
X1927769Y586856D01*
Y563884D01*
X1932281Y559372D01*
X1935093D01*
X1942489Y551976D01*
X1946525D01*
X1949000Y549501D01*
Y545700D01*
X1953476Y541224D01*
Y530436D01*
X1946400Y523360D01*
Y508144D01*
X1941424Y503168D01*
Y479024D01*
X1939000Y476600D01*
G01X1584970Y472370D02*
X1586829Y470511D01*
X1597858D01*
X1602498Y475151D01*
Y477937D01*
X1602881Y478320D01*
Y478349D01*
X1612559Y488027D01*
X1613347D01*
X1613348Y488026D01*
X1620903D01*
X1623489Y485440D01*
X1641936D01*
X1648977Y492481D01*
X1662081D01*
X1671200Y501600D01*
X1673638D01*
X1680100Y495138D01*
Y490518D01*
X1685042Y485576D01*
X1688153D01*
X1688998Y484731D01*
X1696395D01*
X1698354Y486690D01*
Y486873D01*
G01X1535565Y591658D02*
Y590220D01*
X1537225Y588560D01*
X1545640D01*
X1549475Y584725D01*
X1564393D01*
X1565389Y585721D01*
G01X1821261Y170012D02*
X1822591Y168682D01*
X1834208D01*
X1835356Y169830D01*
Y171756D01*
X1837293Y173693D01*
X1849825D01*
X1852444Y171074D01*
X1860752D01*
X1861254Y171576D01*
X1865476D01*
X1868500Y174600D01*
X1871729D01*
X1882447Y163882D01*
X1890334D01*
X1891952Y165500D01*
X1930100D01*
X1940768Y154832D01*
Y146140D01*
X1945500Y141408D01*
Y134304D01*
X1938448Y127252D01*
Y112321D01*
X1939527Y111242D01*
Y95736D01*
X1912037Y68246D01*
X1890663D01*
X1885600Y63183D01*
Y38675D01*
X1879530Y32605D01*
Y31222D01*
X1866682Y18374D01*
X1846460D01*
X1843768Y15682D01*
Y12733D01*
X1845602Y10899D01*
Y8356D01*
X1843746Y6500D01*
X1834871D01*
X1833523Y5152D01*
Y-124D01*
X1831996Y-1651D01*
Y-5104D01*
X1825200Y-11900D01*
Y-14645D01*
X1820969Y-18876D01*
X1687900D01*
X1675512Y-6488D01*
X1664548D01*
X1651368Y-19668D01*
X1650732D01*
X1650730Y-19670D01*
X1649942D01*
X1649941Y-19669D01*
X1649153D01*
X1649152Y-19668D01*
X1615974D01*
X1611510Y-15204D01*
X1599646D01*
X1597504Y-17346D01*
G01X1826900Y40400D02*
Y39387D01*
X1823966Y36453D01*
Y34833D01*
X1821307Y32174D01*
X1817871D01*
X1813148Y27451D01*
Y21581D01*
X1820019Y14710D01*
Y11952D01*
X1818968Y10901D01*
Y9797D01*
X1817376Y8205D01*
X1812213D01*
X1809412Y5404D01*
X1804873D01*
X1804871Y5406D01*
X1803129D01*
X1803127Y5404D01*
X1795743D01*
X1795113Y4774D01*
X1782621D01*
X1773941Y13454D01*
X1740327D01*
X1737596Y10723D01*
Y9123D01*
X1735935Y7462D01*
X1676907D01*
X1669821Y376D01*
X1661700D01*
X1655624Y-5700D01*
X1625541D01*
X1623900Y-4059D01*
Y4600D01*
G01X1632574Y106107D02*
X1633682Y104999D01*
X1662189D01*
X1671603Y95580D01*
X1676001D01*
X1682953Y88628D01*
X1698348D01*
X1699755Y87221D01*
X1703675D01*
X1707351Y83545D01*
X1751196D01*
X1754418Y86767D01*
X1766871D01*
X1774685Y94581D01*
X1793730D01*
X1809889Y110740D01*
Y112358D01*
X1808331Y113916D01*
Y115160D01*
X1811658Y118487D01*
X1817637D01*
X1827585Y128435D01*
X1844095D01*
X1854402Y118128D01*
X1860238D01*
X1862811Y115555D01*
Y108224D01*
X1875964Y95071D01*
X1890834D01*
X1905513Y109750D01*
X1910414D01*
X1918002Y102162D01*
Y98902D01*
G01X1632006Y94500D02*
X1655830D01*
X1659401Y90929D01*
X1660213D01*
X1666781Y84361D01*
X1679256D01*
X1682698Y80919D01*
X1698679D01*
X1701289Y78309D01*
X1702887D01*
X1706056Y75140D01*
X1755764D01*
X1757400Y76776D01*
X1764176D01*
X1766500Y79100D01*
X1788411D01*
X1799135Y89824D01*
X1801164D01*
X1806835Y84153D01*
X1816253D01*
X1821183Y89083D01*
Y94083D01*
X1826700Y99600D01*
X1829020D01*
X1829685Y98935D01*
X1836050D01*
X1841791Y104676D01*
X1845775D01*
X1850999Y109900D01*
X1854500D01*
X1857303Y107097D01*
Y106670D01*
X1874536Y89437D01*
X1892700D01*
X1901571Y98308D01*
X1911098D01*
X1912486Y96920D01*
Y89315D01*
X1915301Y86500D01*
X1920900D01*
X1922709Y88309D01*
Y93709D01*
X1923300Y94300D01*
G01X1601870Y270470D02*
X1598983Y267583D01*
Y265423D01*
X1602414Y261992D01*
Y246665D01*
X1595400Y239651D01*
Y232196D01*
X1599282Y228314D01*
Y210589D01*
X1608243Y201628D01*
X1643151D01*
X1647405Y197374D01*
X1647852D01*
G01X1629595Y217725D02*
X1627008Y220312D01*
X1619887D01*
X1616086Y224113D01*
Y269423D01*
X1593682Y291827D01*
Y293094D01*
X1591230Y295546D01*
Y309838D01*
X1593236Y311844D01*
Y312328D01*
X1593235Y312329D01*
Y316695D01*
X1600524Y323984D01*
Y342521D01*
X1606272Y348269D01*
Y357391D01*
X1610370Y361489D01*
Y361890D01*
G01X1627326Y182759D02*
X1628321Y183754D01*
Y190162D01*
X1630836Y192677D01*
Y194586D01*
X1630814Y194608D01*
Y196080D01*
X1630836Y196102D01*
Y197560D01*
G01X1875700Y184800D02*
X1871736D01*
X1862436Y175500D01*
X1860356D01*
X1859180Y174324D01*
X1854247D01*
X1842675Y185896D01*
X1716999D01*
X1714192Y183089D01*
X1704388D01*
X1701866Y180567D01*
X1689468D01*
X1682155Y187880D01*
X1679300D01*
X1676895Y185475D01*
Y182755D01*
X1670439Y176299D01*
Y171684D01*
X1667404Y168649D01*
X1666341D01*
X1665508Y167816D01*
X1660037D01*
X1659285Y167064D01*
Y166521D01*
X1659310Y166496D01*
Y165219D01*
X1658500Y164409D01*
X1641477D01*
X1640002Y165884D01*
X1638938D01*
G01X1597201Y238188D02*
X1597200D01*
Y232388D01*
X1600690Y228898D01*
Y210968D01*
X1608778Y202880D01*
X1649876D01*
X1654956Y197800D01*
X1670321D01*
X1672015Y199494D01*
X1675595D01*
X1681427Y205326D01*
X1688270D01*
X1688271Y205325D01*
X1694923D01*
X1694924Y205326D01*
X1701505D01*
X1701506Y205325D01*
X1711278D01*
X1711279Y205326D01*
X1718474D01*
X1729892Y193908D01*
X1851041D01*
X1852800Y192149D01*
X1858243D01*
X1862418Y187974D01*
X1876747D01*
X1881416Y183305D01*
Y181484D01*
X1883800Y179100D01*
G01X1651536Y162735D02*
X1651172D01*
X1649611Y161174D01*
X1641590D01*
X1640600Y162164D01*
Y163159D01*
X1639350Y164409D01*
X1638327D01*
X1637263Y165473D01*
Y166496D01*
X1633552Y170207D01*
X1620842D01*
X1620618Y170431D01*
X1619260D01*
X1617830Y169001D01*
X1617829D01*
X1617726Y168898D01*
X1606856D01*
X1603942Y165984D01*
X1595730D01*
X1595291Y166423D01*
G01X1644290Y196383D02*
Y195495D01*
X1648707Y191078D01*
X1670089D01*
X1672100Y193089D01*
Y197800D01*
X1672542Y198242D01*
X1676114D01*
X1681946Y204074D01*
X1687751D01*
X1687752Y204073D01*
X1695442D01*
X1695443Y204074D01*
X1700986D01*
X1700987Y204073D01*
X1711797D01*
X1711798Y204074D01*
X1717955D01*
X1729373Y192656D01*
X1849722D01*
X1851635Y190743D01*
X1857657D01*
X1861834Y186566D01*
X1876163D01*
X1879700Y183029D01*
Y178138D01*
X1883277Y174561D01*
X1886761D01*
X1893680Y181480D01*
X1940384D01*
X1943638Y178226D01*
X1945286D01*
X1946732Y176780D01*
Y156061D01*
X1943024Y152353D01*
Y150769D01*
X1944609Y149184D01*
G01X1606849Y241210D02*
X1612398Y235661D01*
Y218910D01*
X1613537Y217771D01*
Y212266D01*
X1614577Y211226D01*
X1629726D01*
X1634500Y216000D01*
X1650104D01*
X1651884Y214220D01*
X1655568D01*
X1658239Y211549D01*
X1662458D01*
X1663566Y212657D01*
Y213009D01*
G01X1834400Y216900D02*
X1830700D01*
X1827820Y214020D01*
X1718903D01*
X1714469Y209586D01*
X1683025D01*
X1680083Y212528D01*
X1671591D01*
X1664548Y205485D01*
X1655296D01*
X1653975Y206806D01*
X1637074D01*
X1635621Y208259D01*
G01X1648386Y156435D02*
Y157353D01*
X1650000Y158967D01*
Y160500D01*
X1650660Y161160D01*
X1658347D01*
X1659510Y162323D01*
Y163347D01*
X1660573Y164410D01*
X1663395D01*
X1666883Y167898D01*
X1667716D01*
X1671191Y171373D01*
Y171995D01*
X1671190Y171996D01*
Y175620D01*
X1676220Y180650D01*
X1687200D01*
X1688170Y179680D01*
X1702043D01*
X1704700Y182337D01*
X1716453D01*
X1718682Y184566D01*
X1770434D01*
X1774500Y180500D01*
Y175000D01*
X1776500Y173000D01*
X1791582D01*
X1793082Y174500D01*
X1799033D01*
X1800249Y173284D01*
X1833767D01*
X1835831Y175348D01*
X1850640D01*
X1853376Y172612D01*
X1859596D01*
X1860904Y173920D01*
X1864420D01*
X1865100Y174600D01*
G01X1854900Y175900D02*
X1853735D01*
X1842607Y187028D01*
X1729928D01*
X1729676Y186776D01*
X1711676D01*
X1710000Y185100D01*
X1706600D01*
X1704483Y187217D01*
Y193596D01*
X1701727Y196352D01*
X1690352D01*
X1689690Y195690D01*
Y190490D01*
X1687190Y187990D01*
X1683109D01*
X1682467Y188632D01*
X1677595D01*
X1675078Y186115D01*
X1675077D01*
X1673337Y184375D01*
Y181437D01*
X1669688Y177788D01*
Y171996D01*
X1667092Y169400D01*
X1660900D01*
X1659495Y170805D01*
X1647045D01*
X1645241Y172609D01*
X1643662D01*
G01X1610140Y358350D02*
Y358095D01*
X1612040Y356195D01*
Y348294D01*
X1610181Y346435D01*
X1607989D01*
X1605380Y343826D01*
Y325648D01*
X1595491Y315759D01*
Y313265D01*
X1595492Y313264D01*
Y310908D01*
X1593570Y308986D01*
Y296398D01*
X1595938Y294030D01*
Y292763D01*
X1619642Y269059D01*
Y267189D01*
X1619641Y267188D01*
Y263167D01*
X1619639Y263165D01*
Y260931D01*
X1623020Y257550D01*
Y251700D01*
X1621916Y250596D01*
Y232072D01*
X1626917Y227071D01*
X1650685D01*
X1661467Y216289D01*
X1685012D01*
X1687550Y213751D01*
G01X1626124Y225250D02*
X1622690Y221816D01*
X1620511D01*
X1617590Y224737D01*
Y270047D01*
X1595186Y292451D01*
Y293718D01*
X1592780Y296124D01*
Y309260D01*
X1594740Y311220D01*
Y312952D01*
X1594739Y312953D01*
Y316071D01*
X1604464Y325796D01*
Y343974D01*
X1608656Y348166D01*
X1609271D01*
G01X1612250Y435500D02*
X1615153Y432597D01*
Y386153D01*
X1614753Y385753D01*
Y348879D01*
X1610805Y344931D01*
X1610749D01*
Y322196D01*
X1609417Y320864D01*
X1603972D01*
X1603971Y320865D01*
X1602725D01*
X1596995Y315135D01*
Y313889D01*
X1596996Y313888D01*
Y310284D01*
X1595140Y308428D01*
Y296956D01*
X1614857Y277239D01*
X1616261D01*
X1619104Y274396D01*
Y270661D01*
X1620394Y269371D01*
Y266877D01*
X1620393Y266876D01*
Y262855D01*
X1620391Y262853D01*
Y261339D01*
X1623773Y257957D01*
Y256587D01*
X1623780Y256580D01*
Y251312D01*
X1622668Y250200D01*
Y232384D01*
X1627053Y227999D01*
X1637192D01*
X1643106Y233913D01*
G01X1868843Y207920D02*
X1868575Y207652D01*
X1860617D01*
X1858065Y210204D01*
X1847068D01*
X1844347Y212925D01*
Y216200D01*
X1839028Y221519D01*
X1828319D01*
X1824828Y218028D01*
X1718551D01*
X1713117Y212594D01*
X1691285D01*
X1686838Y217041D01*
X1661779D01*
X1644907Y233913D01*
X1643106D01*
G01X1679145Y461950D02*
X1674643D01*
X1674057Y461364D01*
X1674053D01*
X1671906Y459217D01*
X1665748D01*
X1662846Y462119D01*
X1647878D01*
X1640475Y454716D01*
X1639169D01*
X1638246Y453793D01*
Y449502D01*
X1641367Y446381D01*
Y443872D01*
X1637924Y440429D01*
Y432129D01*
X1638802Y431251D01*
Y422855D01*
X1642222Y419435D01*
Y410058D01*
X1642223Y410057D01*
Y409021D01*
X1642222Y409020D01*
Y407815D01*
X1640154Y405747D01*
Y374233D01*
X1638225Y372304D01*
Y370178D01*
X1637183Y369136D01*
Y357933D01*
X1640872Y354244D01*
Y350505D01*
X1640199Y349832D01*
Y342631D01*
X1646760Y336070D01*
Y327423D01*
X1646761Y327422D01*
Y323890D01*
X1646760Y323889D01*
Y302283D01*
X1649133Y299910D01*
Y299373D01*
X1649135Y299371D01*
Y296463D01*
X1649134Y296462D01*
Y295840D01*
X1649133Y295839D01*
Y281905D01*
X1650046Y280992D01*
Y256840D01*
X1650047Y256839D01*
Y252642D01*
X1664660Y238029D01*
X1680531D01*
X1681116Y238614D01*
G01X1627024Y253387D02*
X1625380Y255031D01*
Y258500D01*
X1621897Y261983D01*
Y266252D01*
X1621898Y266253D01*
Y269995D01*
X1620608Y271285D01*
Y274016D01*
X1620609Y274017D01*
Y275263D01*
X1617129Y278743D01*
X1615481D01*
X1596790Y297434D01*
Y307950D01*
X1598500Y309660D01*
Y314512D01*
X1603348Y319360D01*
X1610360D01*
X1612253Y321253D01*
Y321448D01*
X1612254Y321449D01*
Y322071D01*
X1612253Y322072D01*
Y344251D01*
X1616300Y348298D01*
Y385083D01*
X1616700Y385483D01*
Y404200D01*
X1619700Y407200D01*
Y411201D01*
X1616657Y414244D01*
Y436751D01*
X1615775Y437633D01*
Y439031D01*
X1612183Y442623D01*
G01X1639750Y445477D02*
Y444026D01*
X1636672Y440948D01*
Y431610D01*
X1637550Y430732D01*
Y422275D01*
X1640970Y418855D01*
Y409539D01*
X1638902Y407471D01*
Y374752D01*
X1636973Y372823D01*
Y370697D01*
X1635431Y369155D01*
Y349856D01*
X1638017Y347270D01*
Y341221D01*
X1644756Y334482D01*
Y326592D01*
X1644757Y326591D01*
Y324721D01*
X1644756Y324720D01*
Y301452D01*
X1647129Y299079D01*
Y298542D01*
X1647131Y298540D01*
Y297294D01*
X1647130Y297293D01*
Y296671D01*
X1647129Y296670D01*
Y281074D01*
X1648042Y280161D01*
Y256009D01*
X1648043Y256008D01*
Y251633D01*
X1663993Y235683D01*
X1682113D01*
X1694860Y248430D01*
X1703836D01*
X1716114Y236152D01*
X1719080D01*
G01X1602776Y331304D02*
X1602500Y331028D01*
Y324896D01*
X1593987Y316383D01*
Y312641D01*
X1593988Y312640D01*
Y311532D01*
X1592010Y309554D01*
Y295830D01*
X1594434Y293406D01*
Y292139D01*
X1616838Y269735D01*
Y224425D01*
X1620199Y221064D01*
X1655628D01*
X1661155Y215537D01*
X1682779D01*
X1686474Y211842D01*
X1713429D01*
X1718463Y216876D01*
X1825376D01*
X1829267Y220767D01*
X1838716D01*
X1843595Y215888D01*
Y212613D01*
X1847349Y208859D01*
X1858218D01*
X1861035Y206042D01*
X1870095D01*
X1872357Y203780D01*
X1877880D01*
G01X1803280Y232611D02*
Y231313D01*
X1794732Y222765D01*
X1717968D01*
X1711557Y216354D01*
X1692845D01*
X1688353Y220846D01*
X1663924D01*
X1644971Y239799D01*
X1637996D01*
X1637995Y239798D01*
X1637373D01*
X1633414Y243757D01*
Y268835D01*
X1631844Y270405D01*
Y275499D01*
X1628220Y279123D01*
Y283300D01*
X1629070Y284150D01*
Y293563D01*
X1631044Y295537D01*
Y304912D01*
X1631043Y304913D01*
Y305535D01*
X1631044Y305536D01*
Y315064D01*
X1628803Y317305D01*
Y331302D01*
X1628687Y331418D01*
Y331421D01*
X1621600Y338508D01*
Y339162D01*
X1619897Y340865D01*
Y341136D01*
G01Y338636D02*
X1620408D01*
X1627935Y331109D01*
Y331106D01*
X1628051Y330990D01*
Y316993D01*
X1630292Y314752D01*
Y311748D01*
X1630291Y311747D01*
Y311125D01*
X1630292Y311124D01*
Y305848D01*
X1630291Y305847D01*
Y304601D01*
X1630292Y304600D01*
Y297948D01*
X1630291Y297947D01*
Y297325D01*
X1630292Y297324D01*
Y295849D01*
X1628318Y293875D01*
Y284462D01*
X1627468Y283612D01*
Y281989D01*
X1627467Y281988D01*
Y281366D01*
X1627468Y281365D01*
Y278811D01*
X1631092Y275187D01*
Y270093D01*
X1632662Y268523D01*
Y243445D01*
X1637061Y239046D01*
X1638307D01*
X1638308Y239047D01*
X1644659D01*
X1663612Y220094D01*
X1688041D01*
X1692533Y215602D01*
X1711869D01*
X1718144Y221877D01*
X1796026D01*
X1806083Y231934D01*
Y232584D01*
G01X1630150Y427663D02*
X1626033Y423546D01*
Y395269D01*
X1625827Y395063D01*
Y395027D01*
X1619768Y388968D01*
Y377347D01*
X1622315Y374800D01*
Y346231D01*
X1618313Y342229D01*
Y337264D01*
X1618314Y337263D01*
Y335288D01*
X1619108Y334494D01*
X1623483D01*
X1627299Y330678D01*
Y316681D01*
X1629540Y314440D01*
Y312060D01*
X1629539Y312059D01*
Y310813D01*
X1629540Y310812D01*
Y306160D01*
X1629539Y306159D01*
Y304289D01*
X1629540Y304288D01*
Y298260D01*
X1629539Y298259D01*
Y297013D01*
X1629540Y297012D01*
Y296161D01*
X1627566Y294187D01*
Y284774D01*
X1626716Y283924D01*
Y282301D01*
X1626715Y282300D01*
Y281054D01*
X1626716Y281053D01*
Y278499D01*
X1630340Y274875D01*
Y269781D01*
X1631910Y268211D01*
Y243133D01*
X1636749Y238294D01*
X1638619D01*
X1638620Y238295D01*
X1644347D01*
X1663300Y219342D01*
X1687729D01*
X1692221Y214850D01*
X1712181D01*
X1718329Y220998D01*
X1822598D01*
X1825700Y224100D01*
X1840452D01*
X1849134Y215418D01*
X1859789D01*
X1862479Y212728D01*
X1863311D01*
X1864170Y211869D01*
G01X1629300Y385400D02*
X1625323Y381423D01*
Y339641D01*
X1634852Y330112D01*
Y326388D01*
X1632552Y324088D01*
Y317812D01*
X1634052Y316312D01*
Y294289D01*
X1632078Y292315D01*
Y283389D01*
X1634052Y281415D01*
Y278883D01*
X1634852Y278083D01*
Y273730D01*
X1635752Y272830D01*
X1638030D01*
X1638920Y271940D01*
Y262561D01*
X1637281Y260922D01*
G01X1626291Y273309D02*
Y276796D01*
X1625212Y277875D01*
Y280429D01*
X1625211Y280430D01*
Y281417D01*
X1624270Y282358D01*
Y292040D01*
X1628787Y296557D01*
Y298571D01*
X1628788Y298572D01*
Y303976D01*
X1628787Y303977D01*
Y306471D01*
X1628788Y306472D01*
Y310500D01*
X1628787Y310501D01*
Y312371D01*
X1628788Y312372D01*
Y314128D01*
X1623824Y319092D01*
Y328335D01*
X1620159Y332000D01*
Y332004D01*
G01X1630200Y457175D02*
X1631876Y455499D01*
Y444392D01*
X1630846Y443362D01*
Y429196D01*
X1631726Y428316D01*
Y426050D01*
X1626785Y421109D01*
Y412814D01*
X1633078Y406521D01*
Y386778D01*
X1626075Y379775D01*
Y339953D01*
X1635604Y330424D01*
Y326208D01*
X1636931Y324881D01*
Y323575D01*
X1634804Y321448D01*
Y293977D01*
X1632830Y292003D01*
Y283701D01*
X1634804Y281727D01*
Y279195D01*
X1636684Y277315D01*
G01X1630750Y404800D02*
X1632326Y403224D01*
Y391325D01*
X1624571Y383570D01*
Y339329D01*
X1634100Y329800D01*
Y326700D01*
X1631800Y324400D01*
Y317500D01*
X1633300Y316000D01*
Y294601D01*
X1631326Y292627D01*
Y283077D01*
X1633300Y281103D01*
Y279466D01*
X1633299Y279465D01*
Y278843D01*
X1633300Y278842D01*
Y278571D01*
X1634100Y277771D01*
Y271341D01*
X1635670Y269771D01*
Y255933D01*
X1637281Y254322D01*
G01X1620250Y254741D02*
Y254137D01*
X1620000Y253887D01*
Y229499D01*
X1622740Y226759D01*
Y224968D01*
X1621164Y223392D01*
G01X1620240Y257660D02*
X1620058D01*
X1618674Y256276D01*
Y228400D01*
X1621164Y225910D01*
G01X1613452Y387098D02*
X1613908Y386642D01*
Y349098D01*
X1610493Y345683D01*
X1608301D01*
X1606254Y343636D01*
Y325458D01*
X1596243Y315447D01*
Y313577D01*
X1596244Y313576D01*
Y310596D01*
X1594360Y308712D01*
Y296672D01*
X1596690Y294342D01*
Y294241D01*
X1617498Y273433D01*
G01X1638991Y352037D02*
X1638871Y351917D01*
Y342188D01*
X1645508Y335551D01*
Y326904D01*
X1645509Y326903D01*
Y324409D01*
X1645508Y324408D01*
Y301764D01*
X1647881Y299391D01*
Y298854D01*
X1647883Y298852D01*
Y296982D01*
X1647882Y296981D01*
Y296359D01*
X1647881Y296358D01*
Y281386D01*
X1648794Y280473D01*
Y256321D01*
X1648795Y256320D01*
Y252123D01*
X1664418Y236500D01*
X1681866D01*
X1694548Y249182D01*
X1704148D01*
X1711472Y241858D01*
X1824875D01*
X1831096Y235637D01*
Y231976D01*
X1834767Y228305D01*
X1845505D01*
X1847906Y225904D01*
Y219838D01*
X1850070Y217674D01*
X1859852D01*
X1860581Y218403D01*
X1874060D01*
X1876413Y216050D01*
X1884027D01*
X1886952Y213125D01*
G01X1630408Y357603D02*
X1632110Y355901D01*
Y345460D01*
X1630927Y344277D01*
Y342015D01*
X1632115Y340827D01*
Y336041D01*
X1642500Y325656D01*
Y300516D01*
X1644873Y298143D01*
Y280138D01*
X1645786Y279225D01*
Y255073D01*
X1645787Y255072D01*
Y250697D01*
X1666276Y230208D01*
X1686805D01*
X1688123Y231526D01*
Y239937D01*
X1688122Y239938D01*
Y240560D01*
X1695240Y247678D01*
X1703524D01*
X1716774Y234428D01*
X1719722D01*
X1720829Y235535D01*
Y237941D01*
X1722524Y239636D01*
X1824968D01*
X1829590Y235014D01*
Y231978D01*
X1829589Y231977D01*
Y231355D01*
X1834143Y226801D01*
X1837804D01*
X1837806Y226799D01*
X1838428D01*
X1838429Y226800D01*
X1839051D01*
X1839052Y226801D01*
X1844880D01*
X1846402Y225279D01*
Y219214D01*
X1849446Y216170D01*
X1860834D01*
X1861563Y216899D01*
X1867097D01*
X1869609Y214387D01*
X1870107D01*
X1871890Y216170D01*
X1874095D01*
X1876602Y213663D01*
X1878789D01*
G01X1930500Y209464D02*
X1929510Y210454D01*
X1924908D01*
X1920440Y214922D01*
X1903116D01*
X1894218Y206024D01*
X1871747D01*
X1870419Y207352D01*
Y208573D01*
X1869496Y209496D01*
X1867956D01*
X1867232Y208772D01*
X1860630D01*
X1858355Y211047D01*
X1847289D01*
X1845100Y213236D01*
Y216511D01*
X1839340Y222271D01*
X1827441D01*
X1824350Y219180D01*
X1718639D01*
X1712805Y213346D01*
X1691597D01*
X1687150Y217793D01*
X1662721D01*
X1643728Y236786D01*
X1636129D01*
X1629596Y243319D01*
Y248205D01*
X1624590Y253211D01*
Y258210D01*
X1621143Y261657D01*
Y262541D01*
X1621145Y262543D01*
Y266564D01*
X1621146Y266565D01*
Y269683D01*
X1619856Y270973D01*
Y274328D01*
X1619857Y274329D01*
Y274951D01*
X1616817Y277991D01*
X1615169D01*
X1595990Y297170D01*
Y308214D01*
X1597748Y309972D01*
Y314200D01*
X1597747Y314201D01*
Y314823D01*
X1603037Y320113D01*
X1603659D01*
X1603660Y320112D01*
X1609853D01*
X1611501Y321760D01*
Y344563D01*
X1615505Y348567D01*
Y385404D01*
X1615905Y385804D01*
Y436439D01*
X1612256Y440088D01*
G01X1625846Y286154D02*
X1625964Y286036D01*
Y282613D01*
X1625963Y282612D01*
Y280742D01*
X1625964Y280741D01*
Y278187D01*
X1628500Y275651D01*
Y270000D01*
X1631120Y267380D01*
Y242859D01*
X1636437Y237542D01*
X1638931D01*
X1638932Y237543D01*
X1644035D01*
X1662988Y218590D01*
X1687417D01*
X1691909Y214098D01*
X1712493D01*
X1718549Y220154D01*
X1823858D01*
X1826727Y223023D01*
X1840465D01*
X1848822Y214666D01*
X1855805D01*
X1860947Y209524D01*
X1866739D01*
X1867463Y210248D01*
X1877316D01*
X1880416Y207148D01*
X1889246D01*
X1893242Y211144D01*
X1898045D01*
X1902575Y215674D01*
X1913969D01*
X1918143Y219848D01*
G01X1622000Y279495D02*
X1615793D01*
X1597560Y297728D01*
Y307656D01*
X1599526Y309622D01*
Y314474D01*
X1603552Y318500D01*
X1611000D01*
X1613500Y321000D01*
Y344400D01*
X1617161Y348061D01*
Y384645D01*
X1617500Y384984D01*
Y403936D01*
X1620452Y406888D01*
Y407052D01*
X1620500Y407100D01*
Y411499D01*
X1617561Y414438D01*
Y441361D01*
X1621200Y445000D01*
Y445026D01*
X1621226D01*
G01X1768700Y233644D02*
X1768338Y233282D01*
Y229680D01*
X1763879Y225221D01*
X1717232D01*
X1710621Y218610D01*
X1693918D01*
X1689329Y223199D01*
X1664763D01*
X1645907Y242055D01*
X1638309D01*
X1635670Y244694D01*
Y248477D01*
X1639770Y252577D01*
Y276729D01*
X1636684Y279815D01*
G01X1749462Y232955D02*
Y231296D01*
X1745801Y227635D01*
X1716454D01*
X1709685Y220866D01*
X1694854D01*
X1689852Y225868D01*
X1665286D01*
X1646593Y244561D01*
X1641956D01*
X1641113Y245404D01*
Y250728D01*
X1642027Y251642D01*
Y253512D01*
X1642026Y253513D01*
Y277665D01*
X1641113Y278578D01*
Y283643D01*
X1636800Y287956D01*
G01X1733900Y237300D02*
X1732760D01*
X1726647Y231187D01*
X1718513D01*
X1717500Y232200D01*
Y232638D01*
X1703212Y246926D01*
X1695552D01*
X1688875Y240249D01*
Y231214D01*
X1687117Y229456D01*
X1665964D01*
X1645035Y250385D01*
Y254760D01*
X1645034Y254761D01*
Y278913D01*
X1644121Y279826D01*
Y297831D01*
X1636861Y305091D01*
G01X1636922Y302588D02*
X1643369Y296141D01*
Y279514D01*
X1644282Y278601D01*
Y254449D01*
X1644283Y254448D01*
Y250706D01*
X1644282Y250705D01*
Y250074D01*
X1665998Y228358D01*
X1691618D01*
X1696102Y223874D01*
X1708859D01*
X1715420Y230435D01*
X1726995D01*
X1731885Y235325D01*
X1734425D01*
X1736400Y237300D01*
G01X1793700Y232500D02*
X1791324Y234876D01*
X1789698D01*
X1784952Y230130D01*
Y225620D01*
X1782880Y223548D01*
X1717687D01*
X1711245Y217106D01*
X1693157D01*
X1688622Y221641D01*
X1664193D01*
X1645283Y240551D01*
X1637684D01*
X1634166Y244069D01*
Y269147D01*
X1632596Y270717D01*
Y275811D01*
X1628972Y279435D01*
Y282988D01*
X1629822Y283838D01*
Y293251D01*
X1631796Y295225D01*
Y315376D01*
X1630296Y316876D01*
Y325296D01*
X1632591Y327591D01*
Y329003D01*
X1623067Y338527D01*
Y380233D01*
X1621800Y381500D01*
G01X1793600Y235100D02*
X1793072Y235628D01*
X1789386D01*
X1784200Y230442D01*
Y225932D01*
X1782590Y224322D01*
X1717397D01*
X1710933Y217858D01*
X1693469D01*
X1688880Y222447D01*
X1664451D01*
X1645595Y241303D01*
X1637996D01*
X1634918Y244381D01*
Y269459D01*
X1633348Y271029D01*
Y276123D01*
X1629724Y279747D01*
Y282676D01*
X1630574Y283526D01*
Y292939D01*
X1632548Y294913D01*
Y315688D01*
X1631048Y317188D01*
Y324712D01*
X1633348Y327012D01*
Y329488D01*
X1623819Y339017D01*
Y384281D01*
X1621800Y386300D01*
G01X1822877Y235852D02*
X1822053Y236676D01*
X1788710D01*
X1787160Y235126D01*
X1770538D01*
X1769621Y236043D01*
X1765568D01*
X1764662Y235137D01*
X1748485D01*
X1747300Y233952D01*
Y231316D01*
X1744378Y228394D01*
X1716149D01*
X1709373Y221618D01*
X1695166D01*
X1690091Y226693D01*
X1665525D01*
X1649170Y243048D01*
Y243058D01*
X1642778Y249450D01*
Y251329D01*
X1642779Y251330D01*
Y253824D01*
X1642778Y253825D01*
Y277977D01*
X1641865Y278890D01*
Y289903D01*
X1636822Y294946D01*
G01X1636925Y297444D02*
X1642617Y291752D01*
Y279202D01*
X1643530Y278289D01*
Y254137D01*
X1643531Y254136D01*
Y251018D01*
X1643530Y251017D01*
Y249762D01*
X1649922Y243370D01*
Y243360D01*
X1665676Y227606D01*
X1690242D01*
X1695478Y222370D01*
X1709061D01*
X1716039Y229348D01*
X1744268D01*
X1746400Y231480D01*
Y234116D01*
X1748173Y235889D01*
X1764350D01*
X1765256Y236795D01*
X1769933D01*
X1770850Y235878D01*
X1786848D01*
X1788398Y237428D01*
X1824691D01*
X1826085Y236034D01*
G01X1627043Y256900D02*
Y257927D01*
X1622918Y262052D01*
Y270202D01*
X1621500Y271620D01*
Y273895D01*
X1624460Y276855D01*
Y280117D01*
X1624459Y280118D01*
Y281105D01*
X1623517Y282047D01*
Y282669D01*
X1623518Y282670D01*
Y286800D01*
X1623517Y286801D01*
Y287423D01*
X1623518Y287424D01*
Y292352D01*
X1628035Y296869D01*
Y298883D01*
X1628036Y298884D01*
Y303664D01*
X1628035Y303665D01*
Y306783D01*
X1628036Y306784D01*
Y310188D01*
X1628035Y310189D01*
Y312683D01*
X1628036Y312684D01*
Y313816D01*
X1616794Y325058D01*
Y339447D01*
X1616809Y339462D01*
Y341605D01*
X1616808Y341606D01*
Y342228D01*
X1616807Y342229D01*
Y342851D01*
X1618000Y344044D01*
Y384400D01*
X1618264Y384664D01*
Y389664D01*
X1624529Y395929D01*
Y426694D01*
X1627400Y429565D01*
Y451875D01*
X1630200Y454675D01*
G01X1766077Y232681D02*
Y228483D01*
X1763567Y225973D01*
X1716920D01*
X1710309Y219362D01*
X1694230D01*
X1689634Y223958D01*
X1665068D01*
X1646219Y242807D01*
X1638654D01*
X1636422Y245039D01*
Y248165D01*
X1640523Y252266D01*
Y252888D01*
X1640522Y252889D01*
Y277041D01*
X1639609Y277954D01*
Y280216D01*
X1636684Y283141D01*
G01X1784440Y232938D02*
X1783004Y234374D01*
X1770226D01*
X1769309Y235291D01*
X1765880D01*
X1764974Y234385D01*
X1752685D01*
X1751038Y232738D01*
Y231808D01*
X1746113Y226883D01*
X1716766D01*
X1709997Y220114D01*
X1694542D01*
X1689751Y224905D01*
X1665185D01*
X1646530Y243560D01*
X1641800D01*
X1640361Y244999D01*
Y251040D01*
X1641275Y251954D01*
Y253200D01*
X1641274Y253201D01*
Y277353D01*
X1640361Y278266D01*
Y282581D01*
X1637949Y284993D01*
X1636578D01*
X1635224Y286347D01*
Y290848D01*
X1636822Y292446D01*
G01X1640000Y456900D02*
X1639582D01*
X1636994Y454312D01*
Y442336D01*
X1636995Y442335D01*
X1635920Y441260D01*
Y431298D01*
X1636798Y430420D01*
Y421963D01*
X1639940Y418821D01*
Y411617D01*
X1639941Y411616D01*
Y410370D01*
X1639940Y410369D01*
Y409870D01*
X1638150Y408080D01*
Y375064D01*
X1636221Y373135D01*
Y371009D01*
X1634679Y369467D01*
Y349544D01*
X1637257Y346966D01*
Y340135D01*
X1644004Y333388D01*
Y326280D01*
X1644005Y326279D01*
Y325033D01*
X1644004Y325032D01*
Y301140D01*
X1646377Y298767D01*
Y298230D01*
X1646379Y298228D01*
Y297606D01*
X1646378Y297605D01*
Y296983D01*
X1646377Y296982D01*
Y280762D01*
X1647290Y279849D01*
Y255697D01*
X1647291Y255696D01*
Y251321D01*
X1664947Y233665D01*
X1681632D01*
G01X1684300Y233579D02*
Y232414D01*
X1683948Y232062D01*
X1665486D01*
X1646539Y251009D01*
Y255384D01*
X1646538Y255385D01*
Y279537D01*
X1645625Y280450D01*
Y297294D01*
X1645626Y297295D01*
Y297917D01*
X1645625Y297918D01*
Y298455D01*
X1643252Y300828D01*
Y325344D01*
X1643253Y325345D01*
Y325967D01*
X1633927Y335293D01*
Y341877D01*
X1634079Y342029D01*
Y344859D01*
X1633927Y345011D01*
Y351788D01*
X1633926Y351789D01*
Y353035D01*
X1633927Y353036D01*
Y369779D01*
X1635469Y371321D01*
Y373447D01*
X1637398Y375376D01*
Y408672D01*
X1639188Y410462D01*
Y410681D01*
X1639189Y410682D01*
Y411304D01*
X1639188Y411305D01*
Y418509D01*
X1636046Y421651D01*
Y430108D01*
X1635168Y430986D01*
Y441572D01*
X1636242Y442646D01*
Y455842D01*
X1640100Y459700D01*
G01X1608850Y343835D02*
X1607596Y342581D01*
Y323929D01*
X1608764Y322761D01*
Y322440D01*
G01X1630276Y449517D02*
X1628300Y447541D01*
Y429401D01*
X1625281Y426382D01*
Y395581D01*
X1619016Y389316D01*
Y384352D01*
X1618800Y384136D01*
Y356863D01*
X1621563Y354100D01*
Y346543D01*
X1617560Y342540D01*
Y341918D01*
X1617561Y341917D01*
Y334977D01*
X1618796Y333742D01*
X1622070D01*
X1625400Y330412D01*
Y327667D01*
G01X1639500Y433200D02*
X1641060D01*
X1642216Y432044D01*
Y421212D01*
X1643592Y419836D01*
Y407414D01*
X1641406Y405228D01*
Y373772D01*
X1642028Y373150D01*
Y370285D01*
X1641310Y369567D01*
X1641290D01*
X1638435Y366712D01*
Y359069D01*
X1642124Y355380D01*
Y349986D01*
X1641451Y349313D01*
Y348007D01*
X1642374Y347084D01*
X1642467D01*
X1648012Y341539D01*
Y327942D01*
X1648013Y327941D01*
Y323371D01*
X1648012Y323370D01*
Y302802D01*
X1650385Y300429D01*
Y299892D01*
X1650387Y299890D01*
Y295944D01*
X1650386Y295943D01*
Y295321D01*
X1650385Y295320D01*
Y282424D01*
X1651298Y281511D01*
Y257359D01*
X1651299Y257358D01*
Y253161D01*
X1659108Y245352D01*
X1661186D01*
G01X1900890Y477200D02*
X1896471D01*
X1891388Y472117D01*
Y466259D01*
X1876524Y451395D01*
Y448063D01*
X1872425Y443964D01*
X1733436D01*
X1731274Y446126D01*
X1712075D01*
X1708720Y442771D01*
X1684376D01*
X1678632Y448515D01*
Y451083D01*
X1674954Y454761D01*
X1665241D01*
X1661754Y458248D01*
X1659159D01*
X1659158Y458249D01*
X1649881D01*
X1644875Y453243D01*
Y421995D01*
X1645848Y421022D01*
Y408350D01*
X1645849Y408349D01*
Y407727D01*
X1645850Y407726D01*
Y406480D01*
X1645848Y406478D01*
Y375400D01*
X1654400Y366848D01*
Y350400D01*
X1648765Y344765D01*
Y341911D01*
X1648764Y341910D01*
Y328254D01*
X1648765Y328253D01*
Y323059D01*
X1648764Y323058D01*
Y303114D01*
X1651137Y300741D01*
Y300204D01*
X1651139Y300202D01*
Y295632D01*
X1651138Y295631D01*
Y295009D01*
X1651137Y295008D01*
Y282736D01*
X1652050Y281823D01*
Y257671D01*
X1652051Y257670D01*
Y253820D01*
X1658943Y246928D01*
X1661839D01*
X1662956Y245811D01*
Y243582D01*
G01X1638063Y326504D02*
Y329029D01*
X1627927Y339165D01*
Y357554D01*
X1630476Y360103D01*
G01X1662000Y250008D02*
X1658498D01*
X1653555Y254951D01*
Y258294D01*
X1653554Y258295D01*
Y282447D01*
X1652641Y283360D01*
Y294384D01*
X1652642Y294385D01*
Y295007D01*
X1652643Y295008D01*
Y300826D01*
X1652641Y300828D01*
Y301365D01*
X1650268Y303738D01*
Y322434D01*
X1650269Y322435D01*
Y328877D01*
X1650268Y328878D01*
Y341286D01*
X1656543Y347561D01*
Y349132D01*
X1656544Y349133D01*
Y349755D01*
X1656543Y349756D01*
Y367272D01*
X1648776Y375039D01*
Y445339D01*
X1646525Y447590D01*
G01X1647200Y430450D02*
Y422647D01*
X1647766Y422081D01*
Y374985D01*
X1655791Y366960D01*
Y349444D01*
X1649517Y343170D01*
Y341599D01*
X1649516Y341598D01*
Y328566D01*
X1649517Y328565D01*
Y322747D01*
X1649516Y322746D01*
Y303426D01*
X1651889Y301053D01*
Y300516D01*
X1651891Y300514D01*
Y295320D01*
X1651890Y295319D01*
Y294697D01*
X1651889Y294696D01*
Y283048D01*
X1652802Y282135D01*
Y257983D01*
X1652803Y257982D01*
Y254132D01*
X1659255Y247680D01*
X1662151D01*
X1662648Y247183D01*
X1662654D01*
X1664698Y245139D01*
X1666329D01*
G01X1611935Y429515D02*
X1614401Y427049D01*
Y395401D01*
X1611876Y392876D01*
Y385180D01*
X1613156Y383900D01*
Y369793D01*
X1598620Y355257D01*
Y324774D01*
X1590212Y316366D01*
Y315425D01*
G01X1951900Y534900D02*
Y530160D01*
X1945600Y523860D01*
Y509328D01*
X1935050Y498778D01*
X1912728D01*
X1910250Y496300D01*
Y492043D01*
X1890236Y472029D01*
Y467387D01*
X1878793Y455944D01*
X1838049D01*
X1836629Y454524D01*
X1718361D01*
X1705625Y467260D01*
X1694879D01*
X1691163Y463544D01*
X1674466D01*
X1673538Y462616D01*
X1673534D01*
X1671477Y460559D01*
X1666177D01*
X1663365Y463371D01*
X1641542D01*
X1635490Y457319D01*
Y442958D01*
X1634415Y441883D01*
Y441261D01*
X1634416Y441260D01*
Y430674D01*
X1635294Y429796D01*
Y421339D01*
X1638436Y418197D01*
Y410993D01*
X1636646Y409203D01*
Y375688D01*
X1634717Y373759D01*
Y371633D01*
X1633175Y370091D01*
Y365438D01*
X1630337Y362600D01*
G01X1665047Y467257D02*
X1664872Y467432D01*
X1639229D01*
X1635682Y463885D01*
X1633789D01*
X1626600Y456696D01*
Y429829D01*
X1623777Y427006D01*
Y397424D01*
X1621727Y395374D01*
G01X1948100Y538700D02*
X1947500Y538100D01*
Y530588D01*
X1935600Y518688D01*
Y505611D01*
X1932037Y502048D01*
X1905420D01*
X1899020Y495648D01*
Y494170D01*
X1899000Y494150D01*
Y486786D01*
X1887039Y474825D01*
Y468446D01*
X1879326Y460733D01*
X1850081D01*
X1848300Y458952D01*
X1836801D01*
X1835381Y457532D01*
X1719609D01*
X1706873Y470268D01*
X1685366D01*
X1683714Y468616D01*
X1670687D01*
X1668334Y470969D01*
X1660467D01*
X1659186Y469688D01*
X1638293D01*
X1634746Y466141D01*
X1632853D01*
X1624200Y457488D01*
Y450300D01*
X1623100Y449200D01*
X1612007D01*
X1609088Y446281D01*
Y441596D01*
X1608761Y441269D01*
Y430291D01*
X1608338Y429868D01*
Y410134D01*
X1603982Y405778D01*
X1601360D01*
X1594340Y398758D01*
Y389122D01*
X1591867Y386649D01*
Y356475D01*
X1590154Y354762D01*
G01X1589100Y358400D02*
X1589975D01*
X1590327Y358752D01*
Y392097D01*
X1592836Y394606D01*
Y399382D01*
X1600736Y407282D01*
X1603358D01*
X1606834Y410758D01*
Y430492D01*
X1607257Y430915D01*
Y441893D01*
X1607584Y442220D01*
Y445657D01*
X1607583Y445658D01*
Y446904D01*
X1607584Y446905D01*
Y447462D01*
X1619422Y459300D01*
X1623884D01*
X1632230Y467646D01*
X1634123D01*
X1637669Y471192D01*
X1658562D01*
X1659843Y472473D01*
X1668958D01*
X1671311Y470120D01*
X1683090D01*
X1684742Y471772D01*
X1707497D01*
X1720233Y459036D01*
X1834757D01*
X1836177Y460456D01*
X1847676D01*
X1849457Y462237D01*
X1878702D01*
X1882861Y466396D01*
Y476625D01*
X1890000Y483764D01*
Y499500D01*
X1894052Y503552D01*
X1912351D01*
X1922655Y513856D01*
X1924190D01*
X1928582Y518248D01*
X1933032D01*
X1945600Y530816D01*
Y542799D01*
X1940299Y548100D01*
X1934707D01*
X1920381Y562426D01*
Y574510D01*
X1923321Y577450D01*
X1923679D01*
X1925076Y578847D01*
Y581324D01*
X1923400Y583000D01*
G01X1923600Y565100D02*
X1924900D01*
X1931380Y558620D01*
X1934544D01*
X1951180Y541984D01*
Y536552D01*
X1949904Y535276D01*
Y529800D01*
X1940493Y520389D01*
Y505285D01*
X1934848Y499640D01*
X1912390D01*
X1909350Y496600D01*
Y492773D01*
X1889484Y472907D01*
Y467699D01*
X1878481Y456696D01*
X1837737D01*
X1836317Y455276D01*
X1718673D01*
X1705937Y468012D01*
X1694567D01*
X1690851Y464296D01*
X1674154D01*
X1673813Y463955D01*
X1673809D01*
X1671730Y461876D01*
X1665924D01*
X1663677Y464123D01*
X1641230D01*
X1634738Y457631D01*
Y443270D01*
X1633663Y442195D01*
Y440949D01*
X1633664Y440948D01*
Y430362D01*
X1634542Y429484D01*
Y421027D01*
X1637684Y417885D01*
Y411305D01*
X1635894Y409515D01*
Y376000D01*
X1633965Y374071D01*
Y371945D01*
X1632378Y370358D01*
Y367237D01*
X1630240Y365099D01*
G01X1590218Y350995D02*
Y351269D01*
X1593495Y354546D01*
Y385921D01*
X1595844Y388270D01*
Y398134D01*
X1601984Y404274D01*
X1604606D01*
X1609842Y409510D01*
Y429244D01*
X1610265Y429667D01*
Y440645D01*
X1610592Y440972D01*
Y443261D01*
X1611755Y444424D01*
X1613025D01*
X1616201Y447600D01*
X1624000D01*
X1625848Y449448D01*
Y457008D01*
X1633477Y464637D01*
X1635370D01*
X1638917Y468184D01*
X1659810D01*
X1661091Y469465D01*
X1667710D01*
X1670063Y467112D01*
X1684338D01*
X1685990Y468764D01*
X1706249D01*
X1718985Y456028D01*
X1836005D01*
X1837425Y457448D01*
X1848924D01*
X1850705Y459229D01*
X1879950D01*
X1888732Y468011D01*
Y474390D01*
X1900524Y486182D01*
Y495024D01*
X1905964Y500464D01*
X1934608D01*
X1939741Y505597D01*
Y520701D01*
X1949152Y530112D01*
Y535588D01*
X1950428Y536864D01*
Y541672D01*
X1936600Y555500D01*
X1935457D01*
X1933089Y557868D01*
X1931068D01*
X1926736Y562200D01*
X1923771D01*
X1921885Y564086D01*
Y567585D01*
X1923000Y568700D01*
G01X1643150Y348692D02*
X1644073Y349615D01*
X1645743D01*
X1646955Y350827D01*
Y356619D01*
X1643679Y359895D01*
Y366112D01*
X1645169Y367602D01*
Y371513D01*
X1645170Y371514D01*
Y372136D01*
X1642910Y374396D01*
Y404604D01*
X1645098Y406792D01*
Y407414D01*
X1645097Y407415D01*
Y408037D01*
X1645096Y408038D01*
Y420710D01*
X1644123Y421683D01*
Y453977D01*
X1649147Y459001D01*
X1649569D01*
X1649570Y459002D01*
X1650192D01*
X1650193Y459001D01*
X1659470D01*
X1659471Y459000D01*
X1660093D01*
X1660094Y459001D01*
X1662065D01*
X1665389Y455677D01*
X1675221D01*
X1675744Y456200D01*
G01X1676041Y458884D02*
X1675132Y457975D01*
X1675113D01*
X1673621Y456483D01*
X1665647D01*
X1662377Y459753D01*
X1650505D01*
X1650504Y459754D01*
X1649258D01*
X1649257Y459753D01*
X1648753D01*
X1643371Y454371D01*
Y421371D01*
X1644344Y420398D01*
Y407726D01*
X1644345Y407725D01*
Y407103D01*
X1642158Y404916D01*
Y374084D01*
X1644417Y371825D01*
Y367914D01*
X1642927Y366424D01*
Y359583D01*
X1646203Y356307D01*
Y351139D01*
X1645431Y350367D01*
X1644694D01*
X1643700Y351361D01*
Y351667D01*
G01X1715837Y246178D02*
X1708379D01*
X1704623Y249934D01*
X1694236D01*
X1684537Y240235D01*
X1675629D01*
X1661652Y254212D01*
X1657684D01*
X1655059Y256837D01*
Y258918D01*
X1655058Y258919D01*
Y283071D01*
X1654969Y283160D01*
Y314316D01*
X1659200Y318547D01*
Y368373D01*
X1650280Y377293D01*
Y448761D01*
X1646451Y452590D01*
G01X1666345Y241987D02*
X1667905Y243547D01*
Y246650D01*
X1662971Y251584D01*
X1657986D01*
X1654307Y255263D01*
Y258606D01*
X1654306Y258607D01*
Y282759D01*
X1653393Y283672D01*
Y294072D01*
X1653394Y294073D01*
Y294695D01*
X1653395Y294696D01*
Y301138D01*
X1653393Y301140D01*
Y301677D01*
X1651020Y304050D01*
Y322122D01*
X1651021Y322123D01*
Y329189D01*
X1651020Y329190D01*
Y340974D01*
X1657295Y347249D01*
Y348820D01*
X1657296Y348821D01*
Y350067D01*
X1657295Y350068D01*
Y367584D01*
X1649528Y375351D01*
Y447031D01*
X1646469Y450090D01*
G01X1687741Y466988D02*
X1687416Y466663D01*
X1685881D01*
X1684922Y465704D01*
X1673570D01*
X1673230Y465364D01*
X1673226D01*
X1671146Y463284D01*
X1666508D01*
X1664261Y465531D01*
X1640646D01*
X1633329Y458214D01*
Y457048D01*
X1633330Y457047D01*
Y443854D01*
X1632255Y442779D01*
Y440365D01*
X1632256Y440364D01*
Y429778D01*
X1633134Y428900D01*
Y425360D01*
X1628201Y420427D01*
Y413398D01*
X1634486Y407113D01*
Y382186D01*
X1630800Y378500D01*
G01X1600400Y446100D02*
X1602470Y448170D01*
Y452705D01*
X1611642Y461877D01*
G01X1591350Y445300D02*
X1600429Y454379D01*
Y456637D01*
X1608345Y464553D01*
Y476015D01*
X1611781Y479451D01*
X1618098D01*
Y479450D01*
X1618611D01*
X1619137Y479976D01*
X1640952D01*
X1646728Y474200D01*
X1657314D01*
X1658606Y475492D01*
X1684107D01*
X1685042Y474557D01*
X1707904D01*
X1720600Y461861D01*
X1833654D01*
X1835104Y463311D01*
X1847339D01*
X1849229Y465201D01*
X1861930D01*
X1872929Y476200D01*
X1877500D01*
X1879600Y478300D01*
Y494051D01*
X1887000Y501451D01*
Y501460D01*
X1893940Y508400D01*
X1913099D01*
X1916452Y511753D01*
Y519605D01*
X1918395Y521548D01*
X1932006D01*
X1935988Y525530D01*
Y537113D01*
X1919708Y553393D01*
X1905169D01*
X1894838Y563724D01*
X1880626D01*
X1878875Y565475D01*
G01X1875900Y453600D02*
X1874696Y452396D01*
Y447299D01*
X1872113Y444716D01*
X1734384D01*
X1731259Y447841D01*
X1722833D01*
X1704166Y466508D01*
X1695191D01*
X1689852Y461169D01*
X1682526D01*
X1681160Y459803D01*
X1677596D01*
X1676939Y460460D01*
X1675388D01*
X1672690Y457762D01*
X1665432D01*
X1662415Y460779D01*
X1648533D01*
X1642619Y454865D01*
Y442331D01*
X1639774Y439486D01*
G01X1603000Y422971D02*
X1604500Y424471D01*
Y431400D01*
X1604850Y431750D01*
Y442678D01*
X1605328Y443156D01*
Y444721D01*
X1605327Y444722D01*
Y447840D01*
X1605328Y447841D01*
Y451969D01*
X1615061Y461702D01*
Y463157D01*
G01X1626518Y528029D02*
X1628691D01*
X1636427Y520293D01*
X1650960D01*
X1652837Y518416D01*
X1691203D01*
X1695928Y523141D01*
X1717902D01*
X1724509Y529748D01*
X1761699D01*
X1765919Y533968D01*
Y538999D01*
X1764080Y540838D01*
Y568276D01*
X1765729Y569925D01*
X1770228D01*
X1776683Y576380D01*
X1780140D01*
X1782050Y578290D01*
Y583779D01*
X1788969Y590698D01*
X1793867D01*
X1795717Y588848D01*
X1814539D01*
X1815907Y587480D01*
X1816458D01*
G01X1767529Y566200D02*
X1769300Y564429D01*
Y554955D01*
X1766384Y552039D01*
Y541794D01*
X1768223Y539955D01*
Y532310D01*
X1763357Y527444D01*
X1725465D01*
X1716054Y518033D01*
X1706643D01*
X1706642Y518032D01*
X1705162D01*
X1704462Y517332D01*
X1697451D01*
X1696231Y516112D01*
X1651740D01*
X1649963Y517889D01*
X1635111D01*
X1628072Y524928D01*
X1627622D01*
G01X1764300Y570900D02*
X1762928Y569528D01*
Y540360D01*
X1764767Y538521D01*
Y535170D01*
X1760497Y530900D01*
X1724031D01*
X1717524Y524393D01*
X1695409D01*
X1690584Y519568D01*
X1653564D01*
X1651267Y521865D01*
X1637009D01*
X1631975Y526899D01*
Y527700D01*
G01X1630159Y520608D02*
X1634143Y516624D01*
X1638584D01*
X1642087Y513121D01*
X1655444D01*
X1657283Y514960D01*
X1696709D01*
X1697929Y516180D01*
X1704940D01*
X1705640Y516880D01*
X1738380D01*
X1744300Y522800D01*
X1758400D01*
X1761890Y526290D01*
X1768880D01*
X1771670Y523500D01*
X1774940D01*
X1780752Y529312D01*
Y534082D01*
X1790676Y544006D01*
Y556244D01*
X1789066Y557854D01*
Y575095D01*
X1791329Y577358D01*
Y583059D01*
X1792170Y583900D01*
G01X1762062Y592055D02*
X1761218Y591211D01*
X1752627D01*
X1743416Y582000D01*
X1740501D01*
X1734476Y575975D01*
X1724677D01*
X1707806Y559104D01*
X1703797D01*
X1698460Y564441D01*
Y570940D01*
X1693600Y575800D01*
X1664400D01*
X1656100Y584100D01*
Y601954D01*
X1653124Y604930D01*
X1644856D01*
G01X1762062Y589555D02*
X1761814Y589803D01*
X1753211D01*
X1740316Y576908D01*
X1738316D01*
X1735975Y574567D01*
X1725261D01*
X1708390Y557696D01*
X1703213D01*
X1697052Y563857D01*
Y570356D01*
X1693016Y574392D01*
X1663816D01*
X1654692Y583516D01*
Y601370D01*
X1653285Y602777D01*
X1643478D01*
X1640921Y605334D01*
G01X1944925Y226001D02*
X1944924D01*
Y226000D01*
X1945000D01*
Y225648D01*
X1945348Y225300D01*
Y205722D01*
X1949770Y201300D01*
X1953024D01*
X1960320Y194004D01*
Y183690D01*
X1958500Y181870D01*
Y143109D01*
X1963131Y138478D01*
X1965252D01*
X1973157Y130573D01*
Y75182D01*
X1969069Y71094D01*
X1948348D01*
X1943606Y66352D01*
X1928187D01*
X1923397Y71142D01*
X1917943D01*
X1913143Y66342D01*
X1901394D01*
X1891372Y56320D01*
Y41704D01*
X1886665Y36997D01*
Y34007D01*
X1886666Y34006D01*
Y22119D01*
X1884834Y20287D01*
X1882327D01*
X1882326Y20288D01*
X1881352D01*
X1881346Y20282D01*
X1880937D01*
X1876769Y16114D01*
X1856013D01*
X1839600Y-299D01*
Y-6199D01*
X1834300Y-11499D01*
Y-15229D01*
X1829501Y-20028D01*
X1683350D01*
X1680033Y-16711D01*
G01X1688000Y3000D02*
X1691056Y-56D01*
X1796735D01*
X1797502Y711D01*
X1814566D01*
X1817500Y3645D01*
X1819268D01*
X1821592Y5969D01*
X1824232D01*
X1826004Y7741D01*
Y19139D01*
X1827446Y20581D01*
Y26719D01*
X1833884Y33157D01*
X1839257D01*
X1841060Y34960D01*
Y35540D01*
G01X1944463Y228458D02*
X1945542D01*
X1946500Y227500D01*
Y226655D01*
X1946501Y226654D01*
Y225348D01*
X1946500Y225347D01*
Y206200D01*
X1950100Y202600D01*
X1953354D01*
X1961472Y194482D01*
Y183212D01*
X1959652Y181392D01*
Y147578D01*
X1961657Y145573D01*
X1965257D01*
X1967013Y143817D01*
Y139371D01*
X1974309Y132075D01*
Y73622D01*
X1970629Y69942D01*
X1948826D01*
X1943908Y65024D01*
X1927298D01*
X1922380Y69942D01*
X1918602D01*
X1913849Y65189D01*
X1901871D01*
X1892524Y55842D01*
Y41179D01*
X1887865Y36520D01*
Y21688D01*
X1885288Y19111D01*
X1881396D01*
X1877247Y14962D01*
X1856491D01*
X1840800Y-729D01*
Y-6701D01*
X1835452Y-12049D01*
Y-15707D01*
X1829979Y-21180D01*
X1681220D01*
X1676819Y-16779D01*
G01X1667000Y88000D02*
X1669687Y85313D01*
X1679927D01*
X1682468Y82772D01*
X1683079D01*
X1683744Y82107D01*
X1702954D01*
X1705818Y79243D01*
X1706606D01*
X1706607Y79244D01*
X1744182D01*
X1746957Y76469D01*
X1754570D01*
X1755829Y77728D01*
X1763781D01*
X1766105Y80052D01*
X1787468D01*
X1798192Y90776D01*
X1801559D01*
X1807230Y85105D01*
X1815804D01*
X1820152Y89453D01*
Y94453D01*
X1826299Y100600D01*
X1829367D01*
X1830080Y99887D01*
X1835655D01*
X1841397Y105629D01*
X1842185D01*
X1842186Y105628D01*
X1844910D01*
X1847264Y107982D01*
Y108034D01*
X1851030Y111800D01*
X1857800D01*
X1858600Y111000D01*
Y106720D01*
X1874931Y90389D01*
X1892305D01*
X1901176Y99260D01*
X1911493D01*
X1913438Y97315D01*
Y89962D01*
X1915900Y87500D01*
X1920200D01*
X1921700Y89000D01*
Y92613D01*
X1918210Y96103D01*
G01X1918352Y89300D02*
X1916200D01*
X1914589Y90911D01*
Y97511D01*
X1909364Y102736D01*
X1903305D01*
X1891955Y91386D01*
X1875281D01*
X1859562Y107105D01*
Y113458D01*
X1857844Y115176D01*
X1850175D01*
X1843351Y108352D01*
X1808848D01*
X1791718Y91222D01*
X1773622D01*
X1768100Y85700D01*
X1765000D01*
X1760725Y81425D01*
X1753352D01*
X1753277Y81500D01*
X1753266D01*
X1752230Y82536D01*
X1743770D01*
X1743334Y82100D01*
X1707002D01*
X1703130Y85972D01*
X1699598D01*
X1697894Y87676D01*
X1694174D01*
X1694161Y87663D01*
X1692972D01*
X1692971Y87664D01*
X1689409D01*
X1689397Y87676D01*
X1682503D01*
X1675629Y94550D01*
X1671407D01*
X1666504Y99454D01*
X1664696Y101262D01*
X1659962D01*
X1658100Y99400D01*
G01X1807818Y124179D02*
Y122659D01*
X1792614Y107455D01*
X1790227D01*
X1784373Y101601D01*
X1773210D01*
X1768962Y97353D01*
X1758803D01*
X1758802Y97352D01*
X1758168D01*
X1748879Y88063D01*
X1722437D01*
X1718601Y91899D01*
X1714199D01*
X1711332Y94766D01*
X1703957D01*
X1702227Y93036D01*
X1686547D01*
X1682348Y97235D01*
X1682170D01*
X1682109Y97296D01*
X1679294D01*
X1677809Y98781D01*
X1672743D01*
X1669514Y102010D01*
Y103436D01*
X1662206Y110744D01*
X1657123D01*
X1656160Y111707D01*
Y112953D01*
X1656159Y112954D01*
Y117142D01*
X1654673Y118628D01*
G01X1677649Y90301D02*
X1678504Y89446D01*
X1678816D01*
X1684451Y83811D01*
X1703661D01*
X1706524Y80948D01*
X1743812D01*
X1744204Y81340D01*
X1751796D01*
X1753231Y79905D01*
X1763547D01*
X1765399Y81757D01*
X1782177D01*
X1787206Y86786D01*
X1789986D01*
X1805296Y102096D01*
X1813313D01*
X1818417Y107200D01*
X1844770D01*
X1851170Y113600D01*
X1857110D01*
G01X1815026Y121478D02*
X1811107D01*
X1805150Y115521D01*
Y110455D01*
X1791939Y97244D01*
X1772406D01*
X1767524Y92362D01*
X1756471D01*
X1750268Y86159D01*
X1721647D01*
X1717995Y89811D01*
X1712080D01*
X1710090Y91801D01*
X1703686D01*
X1703017Y91132D01*
X1685024D01*
X1680965Y95191D01*
X1678667D01*
X1676662Y97196D01*
X1672118D01*
X1662344Y106970D01*
X1660056D01*
X1657835Y109191D01*
G01X1660985D02*
X1662696D01*
X1668763Y103124D01*
Y101698D01*
X1672483Y97978D01*
X1676982D01*
X1678816Y96144D01*
X1681631D01*
X1685891Y91884D01*
X1702705D01*
X1704306Y93485D01*
X1710733D01*
X1712291Y91927D01*
X1712292D01*
X1713655Y90564D01*
X1718306D01*
X1721959Y86911D01*
X1749357D01*
X1758646Y96200D01*
X1769439D01*
X1773578Y100339D01*
X1784885D01*
X1790533Y105987D01*
X1793071D01*
X1812084Y125000D01*
X1819500D01*
X1825439Y130939D01*
X1845133D01*
X1855404Y120668D01*
X1861522D01*
X1868992Y113198D01*
Y103758D01*
X1875608Y97142D01*
X1887919D01*
X1898102Y107325D01*
G01X1675062Y91219D02*
Y90183D01*
X1676551Y88694D01*
X1678504D01*
X1684139Y83059D01*
X1703349D01*
X1706212Y80196D01*
X1744835D01*
X1747570Y77461D01*
X1751227D01*
X1752919Y79153D01*
X1763859D01*
X1765710Y81004D01*
X1786768D01*
X1806793Y101029D01*
X1813310D01*
X1815901Y103620D01*
X1824990D01*
G01X1658100Y99400D02*
X1658154D01*
G01X1813118Y127976D02*
X1810897Y125755D01*
X1806999D01*
X1805789Y124545D01*
Y122373D01*
X1792430Y109014D01*
X1789862D01*
X1783686Y102838D01*
X1768238D01*
X1764100Y98700D01*
X1757886D01*
X1748401Y89215D01*
X1722943D01*
X1719289Y92869D01*
X1714859D01*
X1711763Y95965D01*
X1702168D01*
X1701838Y96295D01*
X1695624D01*
X1694940Y96979D01*
X1691863D01*
X1690682Y95798D01*
X1685521D01*
X1681915Y99404D01*
Y99809D01*
X1680875Y100849D01*
X1680470D01*
X1680467Y100852D01*
X1674525D01*
X1672475Y102902D01*
Y103612D01*
X1665534Y110553D01*
X1663837D01*
X1662500Y111890D01*
Y112912D01*
X1661496Y113916D01*
X1659410D01*
X1657835Y115491D01*
G01X1807509Y128500D02*
X1806320D01*
X1803070Y125250D01*
Y122714D01*
X1792107Y111751D01*
X1788867D01*
X1784327Y107211D01*
X1763490D01*
X1748079Y91800D01*
X1737700D01*
X1734728Y94772D01*
X1716050D01*
X1712333Y98489D01*
X1700465D01*
X1698301Y100653D01*
X1684669D01*
X1679795Y105527D01*
X1672699D01*
X1668813Y109413D01*
Y113173D01*
X1667970Y114016D01*
X1663523D01*
X1662660Y114879D01*
X1661597D01*
X1660985Y115491D01*
G01X1667238Y112387D02*
Y109912D01*
X1672374Y104776D01*
X1679047D01*
X1683749Y100074D01*
Y99566D01*
X1686141Y97174D01*
X1690265D01*
X1691382Y98291D01*
X1695407D01*
X1696251Y97447D01*
X1711911D01*
X1715337Y94021D01*
X1719200D01*
X1722651Y90570D01*
X1748126D01*
X1763636Y106080D01*
X1785245D01*
X1789525Y110360D01*
X1792124D01*
X1804354Y122590D01*
Y124820D01*
X1806441Y126907D01*
X1809538D01*
X1812183Y129552D01*
X1820635D01*
X1822774Y131691D01*
X1844821D01*
X1844822Y131692D01*
X1845444D01*
X1855716Y121420D01*
X1862291D01*
X1869744Y113966D01*
Y104070D01*
X1875920Y97894D01*
X1886395D01*
X1897651Y109150D01*
X1903566D01*
X1905858Y111442D01*
X1912642D01*
X1914500Y113300D01*
G01X1657835Y143837D02*
G03X1659386Y144438I95J2057D01*
G01X1659886Y144938D01*
G02X1661093Y145438I1207J-1207D01*
G01X1665905D01*
G03X1667242Y145992I0J1890D01*
G01X1671710Y150460D01*
G02X1672892Y150950I1182J-1181D01*
G01X1675866D01*
G03X1676792Y151876I0J926D01*
G01Y152609D01*
G02X1678644I926J0D01*
G01Y151876D01*
G03X1680496I926J0D01*
G01Y152617D01*
G02X1682348I926J0D01*
G01Y151876D01*
G03X1684200I926J0D01*
G01Y152617D01*
G02X1686052I926J0D01*
G01Y151876D01*
G03X1686978Y150950I926J0D01*
G01X1696212D01*
G02X1697217Y150533I-1J-1422D01*
G01X1697653Y150097D01*
G03X1699335Y149400I1682J1681D01*
G01X1701432D01*
G02X1706924Y147125I0J-7767D01*
G01X1715808Y138241D01*
G03X1716753Y137850I945J945D01*
G01X1731781D01*
G03X1732713Y138236I0J1318D01*
G01X1733787Y139310D01*
G02X1734820Y139738I1033J-1033D01*
G01X1735339D01*
G02X1735914Y139500I0J-813D01*
G01X1723314Y142650D02*
X1723310D01*
X1721975Y141291D01*
G02X1721558Y141116I-417J409D01*
G01X1717336D01*
G02X1716441Y141178I0J6492D01*
G02X1715019Y141767I0J2011D01*
G01X1707560Y149226D01*
G03X1702609Y151277I-4951J-4951D01*
G01X1701582D01*
G02X1698927Y153139I0J2824D01*
G01X1735989Y133250D02*
G02X1726620Y131719I-9369J27901D01*
G01X1726249Y131715D01*
G02X1724889Y133381I340J1666D01*
G01Y133383D01*
G03X1723584Y134688I-1305J0D01*
G01X1712056D01*
G02X1710227Y135446I0J2586D01*
G01X1702498Y143175D01*
G03X1699672Y144709I-4001J-4001D01*
G01X1698510D01*
G02X1695572Y145739I0J4705D01*
G03X1692045Y147200I-3527J-3527D01*
G01X1676043D01*
G03X1670828Y145105I0J-7538D01*
G02X1666205Y143238I-4623J4790D01*
G01X1663488D01*
G03X1662291Y142742I0J-1692D01*
G01X1662290D01*
G02X1661315Y142338I-975J975D01*
G01X1661115D01*
G03X1659486Y140709I0J-1629D01*
G02X1657949Y139172I-1537J0D01*
G01X1654754D01*
G02X1653186Y140740I0J1568D01*
G02X1654685Y143837I3949J0D01*
G01X1657835Y146987D02*
G02X1658330Y148182I1690J0D01*
G01X1658878Y148730D01*
G03X1659486Y150197I-1466J1467D01*
G01Y150202D01*
G02X1660218Y151970I2501J0D01*
G01X1662354Y154106D01*
G02X1664122Y154838I1768J-1769D01*
G01X1664320D01*
G03X1665686Y156204I0J1366D01*
G02X1666218Y157486I1817J-3D01*
G01X1666220Y157488D01*
G02X1666555Y157811I8957J-8954D01*
G02X1677177Y161197I10622J-14968D01*
G01X1683883D01*
G03X1688917Y163282I0J7120D01*
G01X1692831Y167196D01*
G02X1695845Y168444I3014J-3015D01*
G01X1701266D01*
G02X1720179Y160610I0J-26747D01*
G01X1720268Y160521D01*
G02X1720475Y160014I-517J-507D01*
G03X1720706Y159456I789J0D01*
G01X1721564Y158598D01*
G03X1721763Y158412I2856J2856D01*
G03X1724170Y157415I2407J2407D01*
G01X1724420D01*
G02X1725724Y156875I0J-1844D01*
G01X1729273Y153326D01*
X1731823Y150775D01*
G03X1735989Y149050I4165J4166D01*
G01X1660985Y150137D02*
X1660840Y150282D01*
Y150287D01*
G02X1661099Y151375I2413J0D01*
G02X1661296Y151648I949J-477D01*
G01X1661641Y151993D01*
G02X1662894I626J-626D01*
G03X1663522Y151733I628J628D01*
G01X1663938D01*
G03X1665718Y152470I0J2518D01*
G03X1666130Y153465I-995J995D01*
G01Y153840D01*
G02X1666343Y154353I727J-1D01*
G01X1666344Y154354D01*
G02X1667502Y154834I1158J-1157D01*
G03X1668062Y155066I0J792D01*
G01X1669716Y156720D01*
G02X1675882Y159274I6166J-6165D01*
G01X1695014D01*
G03X1695940Y160200I0J926D01*
G01Y161844D01*
G02X1697792I926J0D01*
G01Y160200D01*
G03X1698718Y159274I926J0D01*
G01X1702258D01*
G02X1709428Y156304I0J-10140D01*
G01X1711240Y154492D01*
G03X1716500Y152313I5260J5259D01*
G01X1718683D01*
G02X1719937Y152247I-2J-11991D01*
G02X1727540Y149098I1J-10751D01*
G01X1731926Y144712D01*
X1732454Y144185D01*
G02X1732820Y143300I-885J-884D01*
G03X1733127Y142835I1286J515D01*
G01X1733414Y142548D01*
G03X1734323Y142172I909J910D01*
G01X1734326D01*
G03X1734838Y142384I0J724D01*
G03X1734989Y142750I-366J365D01*
G01X1657836Y153288D02*
G03X1661827Y154941I0J5644D01*
G01X1662122Y155236D01*
G03X1662467Y156069I-833J833D01*
G01Y156659D01*
G02X1662791Y157441I1106J0D01*
G01X1663026Y157676D01*
G02X1669115Y161591I13604J-14465D01*
G02X1676629Y163067I7513J-18381D01*
G01X1683920D01*
G03X1687153Y164406I0J4573D01*
G01X1691395Y168648D01*
G02X1695436Y170322I4041J-4040D01*
G01X1700909D01*
G02X1724962Y160359I0J-34016D01*
G02X1725246Y159672I-687J-686D01*
G03X1725406Y159286I546J0D01*
G01X1731212Y153480D01*
G03X1734832Y151416I5579J5579D01*
G02X1735489Y151220I-2229J-8672D01*
G02X1738940Y149074I-2879J-8478D01*
G01X1742214Y145800D01*
G01X1739064Y139500D02*
X1739062Y139502D01*
G03X1734838Y141250I-4224J-4230D01*
G01X1734835D01*
G02X1732133Y142369I0J3822D01*
G01X1728721Y145781D01*
G03X1717181Y150561I-11540J-11540D01*
G01X1714274D01*
G02X1710672Y152053I0J5094D01*
G01X1709028Y153697D01*
G03X1700411Y157266I-8617J-8618D01*
G01X1675223D01*
G03X1671283Y155634I0J-5572D01*
G01X1667867Y152218D01*
G02X1666982Y151852I-885J887D01*
G03X1666049Y151302I603J-2090D01*
G01X1666012Y151264D01*
G02X1664689Y150716I-1323J1323D01*
G03X1663254Y150006I333J-2479D01*
G01X1662314Y149066D01*
G02X1661040Y148538I-1274J1273D01*
G01X1661036D01*
G03X1659827Y148037I0J-1709D01*
G01X1659826Y148036D01*
G03X1659386Y146974I1062J-1062D01*
G02X1658936Y145888I-1535J0D01*
G01X1658875Y145827D01*
G02X1657936Y145438I-939J939D01*
G03X1656186Y143688I0J-1750D01*
G01Y143685D01*
G02X1655127Y141129I-3614J0D01*
G01X1654685Y140687D01*
G01X1660985Y143837D02*
G02X1662452Y144238I1467J-2483D01*
G01X1666874D01*
G03X1667922Y144672I0J1482D01*
G01X1671115Y147865D01*
G02X1674084Y149095I2969J-2969D01*
G01X1695007D01*
G02X1695944Y148706I0J-1323D01*
G01X1696400Y148250D01*
G03X1698396Y147423I1996J1996D01*
G01X1699259D01*
G02X1702112Y146241I0J-4034D01*
G01X1703257Y145096D01*
G03X1704567I655J655D01*
G01X1704783Y145312D01*
G02X1706094Y144003I655J-654D01*
G01X1705877Y143786D01*
G03X1707187Y142476I655J-655D01*
G01X1707403Y142692D01*
G02X1708714Y141383I655J-655D01*
G01X1708497Y141166D01*
G03X1709807Y139856I655J-655D01*
G01X1710023Y140072D01*
G02X1711334Y138763I655J-655D01*
G01X1710808Y138237D01*
G03Y137545I345J-346D01*
G01X1711153Y137200D01*
G03X1712963Y136450I1810J1809D01*
G01X1724996D01*
G02X1725667Y136172I0J-949D01*
G01X1726788Y135051D01*
G03X1727755Y134650I968J967D01*
G01X1729088D01*
G03X1729943Y135004I0J1210D01*
G01X1731231Y136292D01*
G02X1732737Y136916I1506J-1505D01*
G01X1733762D01*
G02X1734688Y135990I0J-926D01*
G03X1736540I926J0D01*
G01Y136338D01*
G02X1737648Y137446I1108J0D01*
G01X1738508D01*
G02X1739063Y136894I0J-555D01*
G01X1739064Y136350D01*
G01Y126900D02*
X1727082D01*
G03X1725491Y126241I0J-2250D01*
G02X1723099Y125250I-2392J2392D01*
G01X1700562D01*
G02X1699322Y125764I0J1753D01*
G01X1698959Y126128D01*
G02Y126854I364J363D01*
G01X1700731Y128625D01*
G03X1699421Y129935I-655J655D01*
G01X1697941Y128456D01*
G02X1696631Y129766I-655J655D01*
G01X1698056Y131190D01*
G03X1696746Y132501I-655J655D01*
G01X1695773Y131528D01*
G02X1692919Y131529I-1427J1426D01*
G01X1691903Y132544D01*
G02X1691791Y132814I269J270D01*
G01Y134439D01*
G03X1691333Y135544I-1562J0D01*
G01X1688503Y138374D01*
G03X1685242Y139725I-3261J-3260D01*
G01X1681274D01*
Y139730D01*
G02X1680656Y139986I0J874D01*
G03X1679250Y140544I-2479J-4197D01*
G03X1678178Y140663I-1071J-4756D01*
G01X1676725D01*
G03X1670105Y137921I0J-9362D01*
G01X1668849Y136665D01*
G02X1667335Y136038I-1514J1514D01*
G01X1665782D01*
G02X1665532Y136142I1J354D01*
G01X1664136Y137538D01*
G01X1726464Y111150D02*
X1725795Y110481D01*
G02X1723789Y109650I-2006J2006D01*
G01X1716304D01*
G03X1713547Y108508I0J-3899D01*
G02X1713442Y108410I-1307J1295D01*
G02X1712246Y107969I-1195J1399D01*
G01X1710354D01*
G02X1709428Y108895I0J926D01*
G01Y109762D01*
G03X1707576I-926J0D01*
G01Y108864D01*
G02X1705724I-926J0D01*
G01Y109659D01*
G03X1703872I-926J0D01*
G01Y108885D01*
G02X1702020I-926J0D01*
G01Y109755D01*
G03X1700168I-926J0D01*
G01Y108907D01*
G02X1698316I-926J0D01*
G01Y109753D01*
G03X1696464I-926J0D01*
G01Y108895D01*
G02X1695538Y107969I-926J0D01*
G01X1694477D01*
G02X1692877Y108632I0J2263D01*
G01X1687250Y114259D01*
G03X1683493Y115815I-3757J-3757D01*
G01X1677685D01*
G02X1677104Y116056I0J822D01*
G01X1676934Y116226D01*
X1676621Y116540D01*
G02X1676173Y117620I1080J1081D01*
G03X1675720Y118714I-1547J0D01*
G01X1675595Y118839D01*
G02X1675301Y119549I710J710D01*
G03X1674057Y121645I-4728J-1389D01*
G01X1671421Y124281D01*
G03X1670077Y124838I-1344J-1343D01*
G01X1664176D01*
G03X1662486Y124138I0J-2390D01*
G01X1662252Y123904D01*
G02X1661127Y123438I-1125J1125D01*
G01X1657035D01*
G02X1655598Y124034I0J2030D01*
G01X1654694Y124940D01*
X1654686D01*
G01X1739064Y120600D02*
X1736610D01*
G03X1732617Y118946I0J-5647D01*
G01X1730593Y116922D01*
G02X1724919Y114287I-6439J6439D01*
G01X1717815D01*
G02X1717294Y114503I0J737D01*
G03X1716980Y114633I-314J-314D01*
G01X1716599Y114634D01*
G02X1715821Y115415I2J780D01*
G01Y115417D01*
G03X1715125Y116115I-697J1D01*
G01X1714668Y116116D01*
G03X1713969Y115419I-2J-697D01*
G02X1713188Y114640I-780J1D01*
G01X1712896Y114641D01*
G02X1712117Y115422I1J780D01*
G01Y115423D01*
G03X1711406Y116137I-713J1D01*
G01X1710980Y116138D01*
G03X1710265Y115426I-2J-713D01*
G01Y115425D01*
G02X1709484Y114646I-780J1D01*
G01X1701828Y114656D01*
X1701821Y114658D01*
G02X1690509Y118229I0J19702D01*
G02X1690318Y118376I9750J12865D01*
G01X1683534Y125160D01*
G03X1680255Y126518I-3279J-3279D01*
G01X1678285D01*
G02X1675166Y127810I0J4411D01*
G03X1670796Y129620I-4370J-4370D01*
G01X1668761D01*
X1657932Y129619D01*
G02X1656199Y131352I0J1733D01*
G01Y131353D01*
G03X1655121Y133954I-3677J0D01*
G01X1654686Y134389D01*
G01X1720164Y108000D02*
X1718771Y106610D01*
G02X1718149Y106352I-623J623D01*
G01X1716708D01*
G03X1714876Y105593I0J-2591D01*
G02X1711976Y104392I-2900J2900D01*
G01X1711490D01*
G02X1711005Y104878I0J485D01*
G01Y105236D01*
G03X1710164Y106077I-841J0D01*
G01X1709996D01*
G03X1709153Y105234I0J-843D01*
G02X1708311Y104392I-842J0D01*
G01X1708143D01*
G02X1707301Y105234I0J842D01*
G03X1706459Y106076I-842J0D01*
G01X1706291D01*
G03X1705449Y105234I0J-842D01*
G02X1704607Y104392I-842J0D01*
G01X1704439D01*
G02X1703597Y105234I0J842D01*
G03X1702755Y106076I-842J0D01*
G01X1702587D01*
G03X1701745Y105234I0J-842D01*
G02X1700903Y104392I-842J0D01*
G01X1700735D01*
G02X1699893Y105234I0J842D01*
G03X1699051Y106076I-842J0D01*
G01X1698883D01*
G03X1698041Y105234I0J-842D01*
G02X1697199Y104392I-842J0D01*
G01X1697031D01*
G02X1696189Y105234I0J842D01*
G03X1695351Y106072I-838J0D01*
G01X1695175D01*
G03X1694337Y105234I0J-838D01*
G02X1693495Y104392I-842J0D01*
G01X1693327D01*
G02X1692485Y105234I0J842D01*
G01Y105334D01*
G03X1691629Y106190I-856J0D01*
G01X1691589D01*
G03X1690633Y105234I0J-956D01*
G02X1689791Y104392I-842J0D01*
G01X1687806D01*
G02X1687244Y104582I0J926D01*
G01X1686742Y104965D01*
G02X1686650Y105045I560J737D01*
G02X1686648Y106271I612J614D01*
G01X1688919Y108552D01*
G03X1687608Y109858I-655J653D01*
G01X1686056Y108301D01*
G02X1684742Y109608I-657J653D01*
G01X1685784Y110656D01*
G03X1684475Y111962I-654J653D01*
G01X1683261Y110746D01*
G02X1681949Y112055I-656J655D01*
G03X1680639Y113363I-655J654D01*
G01X1680124Y112847D01*
G02X1679250Y112499I-840J837D01*
G02X1678447Y112844I34J1185D01*
G02X1676980Y113452I2J2078D01*
G01X1674750Y115680D01*
G02X1674281Y116552I1211J1213D01*
G03X1673735Y117869I-1858J1D01*
G01X1669128Y122457D01*
G03X1666752Y123438I-2376J-2387D01*
G01X1664739D01*
G03X1662429Y122481I0J-3266D01*
G01X1662266Y122318D01*
G02X1660985Y121790I-1275J1275D01*
G01X1654685D02*
X1654578Y121683D01*
G03Y120390I646J-646D01*
G03X1654945Y120238I367J367D01*
G01X1666670D01*
G02X1669257Y119168I0J-3662D01*
G01X1672152Y116279D01*
G02X1672567Y115277I-1002J-1002D01*
G03X1672855Y114740I1035J209D01*
G01X1674962Y112633D01*
G02Y111323I-654J-655D01*
G01X1673218Y109578D01*
G03X1674528Y108268I655J-655D01*
G01X1676272Y110013D01*
G02X1677022Y110279I655J-655D01*
G02X1678997Y109461I0J-2793D01*
G01X1679487Y108971D01*
X1685241Y103235D01*
G03X1687006Y102505I1765J1770D01*
G01X1702830D01*
G02X1703756Y101579I0J-926D01*
G01Y101282D01*
G03X1705608I926J0D01*
G01Y101579D01*
G02X1707460I926J0D01*
G01Y101277D01*
G03X1709312I926J0D01*
G01Y101579D01*
G02X1711164I926J0D01*
G01Y101310D01*
G03X1713016I926J0D01*
G01Y101579D01*
G02X1713942Y102505I926J0D01*
G01X1719609D01*
G03X1721789Y104685I0J2180D01*
G01Y107202D01*
G02X1722587Y108000I798J0D01*
G01X1723314D01*
G01X1739064Y123750D02*
X1738718Y123404D01*
G02X1735932Y122250I-2786J2786D01*
G03X1732151Y120684I0J-5347D01*
G01X1728434Y116967D01*
G02X1725738Y115850I-2696J2695D01*
G01X1719985D01*
G02X1719080Y116225I0J1280D01*
G01X1718614Y116691D01*
G03X1718166Y117085I-3275J-3272D01*
G03X1715904Y118022I-2262J-2262D01*
G01X1708875D01*
G03X1708251Y117398I0J-624D01*
G02X1707625Y116772I-626J0D01*
G01X1707025D01*
G02X1706399Y117398I0J626D01*
G03X1705773Y118024I-626J0D01*
G01X1705173D01*
G03X1704547Y117398I0J-626D01*
G02X1703932Y116783I-615J0D01*
G01X1703310D01*
G02X1702695Y117398I0J615D01*
G03X1702071Y118022I-624J0D01*
G01X1697413D01*
G02X1695455Y118833I0J2769D01*
G02X1695285Y118999I5789J6099D01*
G01X1693385Y120898D01*
G03X1692075I-655J-654D01*
G02X1690765Y122208I-655J655D01*
G03X1689455Y123518I-655J655D01*
G02X1688145Y124828I-655J655D01*
G03X1686835Y126138I-655J655D01*
G02X1685525Y127448I-655J655D01*
G03X1684215Y128758I-655J655D01*
G02X1682905Y130068I-655J655D01*
G01X1683042Y130205D01*
G03Y131241I-517J518D01*
G01X1682525Y131758D01*
G03X1681341Y132249I-1185J-1184D01*
G02X1679542Y133241I814J3604D01*
G01X1679250Y133533D01*
X1677879Y134906D01*
G03X1675553Y135869I-2324J-2324D01*
G03X1675045Y135896I-505J-4700D01*
G03X1673453Y135173I166J-2479D01*
G01X1671689Y133409D01*
G02X1670310Y132838I-1379J1380D01*
G01X1667993D01*
G03X1664135Y131239I0J-5454D01*
G01X1654685D02*
G03X1655305Y130456I3682J2279D01*
G01X1657269Y128492D01*
G03X1662227Y126438I4958J4957D01*
G01X1672445D01*
G02X1675279Y125264I0J-4008D01*
G03X1676370Y124812I1091J1091D01*
G01X1677274D01*
G02X1679250Y124555I-1J-7729D01*
G02X1682739Y122548I-1976J-7472D01*
G01X1686417Y118870D01*
G03X1701139Y112772I14722J14722D01*
G01X1724430D01*
G03X1724470Y112774I0J394D01*
G03X1733305Y116966I-1464J14491D01*
G01X1734678Y118339D01*
G02X1736395Y119050I1717J-1718D01*
G01X1738472D01*
G03X1742214Y120600I0J5292D01*
G01X1735912Y123750D02*
X1736311D01*
G03X1736730Y123923I0J594D01*
G03X1736800Y124134I-283J211D01*
G01Y124680D01*
G03X1736254Y125226I-546J0D01*
G01X1734686D01*
G03X1733322Y124661I0J-1929D01*
G01X1730972Y122311D01*
X1730788Y122128D01*
X1729383Y120724D01*
X1728256Y119597D01*
G02X1727068Y119105I-1188J1188D01*
G02X1726260Y119050I-809J5918D01*
G01X1719321D01*
G02X1718278Y119482I0J1475D01*
G03X1717245Y119910I-1033J-1033D01*
G01X1714417D01*
G02X1713735Y120592I0J682D01*
G01Y120593D01*
G03X1713065Y121263I-670J0D01*
G01X1712554D01*
G03X1711883Y120592I0J-671D01*
G02X1711201Y119910I-682J0D01*
G01X1710713D01*
G02X1710031Y120592I0J682D01*
G03X1709327Y121296I-704J0D01*
G01X1708882D01*
G03X1708179Y120593I0J-703D01*
G01Y120592D01*
G02X1707254Y119667I-925J0D01*
G01X1707252D01*
G02X1706327Y120592I0J925D01*
G03X1705538Y121381I-789J0D01*
G01X1705264D01*
G03X1704475Y120592I0J-789D01*
G01Y120581D01*
G02X1702623I-926J0D01*
G01Y120592D01*
G03X1701821Y121394I-802J0D01*
G01X1701573D01*
G03X1700771Y120592I0J-802D01*
G02X1700089Y119910I-682J0D01*
G01X1698606D01*
G02X1695984Y120996I0J3708D01*
G01X1683573Y133407D01*
G03X1681958Y134076I-1615J-1615D01*
G02X1680567Y134872I769J2958D01*
G01X1680051Y135388D01*
G03X1676800Y136813I-3251J-2996D01*
G01X1673634D01*
G03X1672836Y136482I1J-1129D01*
G01X1671709Y135355D01*
G02X1668047Y133838I-3662J3662D01*
G01X1664586D01*
G03X1662879Y133131I0J-2414D01*
G01X1662877D01*
X1660985Y131239D01*
G01X1657835D02*
G02X1658150Y132000I1077J0D01*
G01X1660178Y134028D01*
G02X1662134Y134838I1956J-1957D01*
G01X1667235D01*
G03X1670561Y136216I0J4703D01*
G01X1672412Y138067D01*
G02X1673117Y138359I705J-705D01*
G01X1679130D01*
G02X1679250Y138350I-2J-830D01*
G02X1679717Y138116I-119J-821D01*
G03X1680526Y137781I809J809D01*
G01X1681108D01*
G02X1682491Y137208I0J-1956D01*
G01X1682937Y136762D01*
G03X1684247Y136764I654J656D01*
G01X1684905Y137423D01*
G02X1686217Y136114I656J-655D01*
G01X1685553Y135449D01*
G03X1686865Y134140I656J-655D01*
G01X1687685Y134962D01*
G02X1688997Y133652I656J-655D01*
G01X1688183Y132837D01*
G03X1688185Y131527I656J-654D01*
G01X1690965Y128753D01*
G03X1692152Y128856I532J759D01*
G01X1692168Y128872D01*
G02X1693477Y127563I654J-655D01*
G01X1693462Y127547D01*
G03X1694772Y126236I655J-656D01*
G02X1696082Y124926I655J-655D01*
G01X1695755Y124599D01*
G03X1695754Y123945I327J-328D01*
G01X1695990Y123709D01*
G03X1696196Y123554I654J655D01*
G01X1696410Y123436D01*
G03X1696858Y123320I449J810D01*
G01X1717246D01*
G02X1718767Y122690I0J-2151D01*
G03X1719829Y122250I1062J1062D01*
G01X1726729D01*
G03X1727736Y122667I0J1424D01*
G03X1727966Y123222I-555J555D01*
G01Y124070D01*
G03X1727460Y124576I-506J0D01*
G01X1726863D01*
G03X1726464Y124177I0J-399D01*
G01Y123750D01*
G01X1731789Y139450D02*
X1730383Y140856D01*
G03X1728953Y140855I-715J-715D01*
G02X1727643Y142165I-655J655D01*
G03Y143595I-715J715D01*
G01X1727366Y143872D01*
G03X1726455Y144250I-912J-911D01*
G01X1718065D01*
G02X1713296Y146226I1J6746D01*
G01X1707634Y151888D01*
G03X1700157Y154985I-7477J-7477D01*
G01X1695160D01*
G03X1694699Y154524I0J-461D01*
G01Y154154D01*
G02X1692847I-926J0D01*
G01Y154440D01*
G03X1690995I-926J0D01*
G01Y154093D01*
G02X1689143I-926J0D01*
G01Y154524D01*
G03X1688253Y155414I-890J0D01*
G01X1676046D01*
G03X1673854Y154506I0J-3101D01*
G01X1668472Y149124D01*
G02X1667298Y148638I-1174J1175D01*
G01X1664622D01*
G03X1662854Y147906I0J-2501D01*
G01X1662272Y147324D01*
G02X1661458Y146987I-814J814D01*
G01X1660985D01*
G01X1739064Y130050D02*
X1738527Y129513D01*
G02X1736127Y128519I-2400J2399D01*
G01X1711808D01*
G02X1707764Y130194I0J5719D01*
G01X1707171Y130786D01*
G03X1705987Y130785I-592J-592D01*
G01X1705770Y130568D01*
G02X1704460Y131878I-655J655D01*
G01X1704615Y132033D01*
G03X1703304Y133342I-655J655D01*
G01X1703142Y133180D01*
G02X1701832Y134490I-655J655D01*
G01X1701995Y134653D01*
G03X1700684Y135962I-656J655D01*
G01X1700443Y135721D01*
G02X1699133Y137031I-655J655D01*
G01X1699375Y137273D01*
G03X1699374Y138583I-655J655D01*
G01X1698439Y139518D01*
G03X1695587Y140700I-2854J-2854D01*
G01X1693499D01*
G02X1692394Y141158I0J1562D01*
G01X1692224Y141328D01*
G03X1687584Y143250I-4640J-4640D01*
G01X1674937D01*
G03X1672849Y142385I0J-2953D01*
G01X1671102Y140638D01*
G02X1667480Y139138I-3622J3623D01*
G01X1660881D01*
G03X1660036Y138788I0J-1195D01*
G01X1659458Y138210D01*
G02X1657836Y137538I-1622J1622D01*
G01X1742214Y130050D02*
X1743091D01*
G03X1743721Y131571I0J891D01*
G03X1742770Y131965I-951J-951D01*
G01X1738365D01*
G03X1735992Y130982I0J-3355D01*
G01X1735737Y130727D01*
G02X1734585Y130250I-1152J1153D01*
G01X1726579D01*
G02X1724889Y130950I0J2390D01*
G03X1723407Y131564I-1482J-1482D01*
G01X1715598D01*
G02X1708447Y134525I-1J10113D01*
G01X1707549Y135423D01*
G03X1706451I-549J-550D01*
G01X1706450Y135422D01*
G02X1705352I-549J550D01*
G01X1705140Y135634D01*
G02Y136732I550J549D01*
G03X1705141Y137906I-587J588D01*
G01X1705005Y138042D01*
G03X1703831Y138043I-588J-587D01*
G01X1703830Y138042D01*
G02X1702732I-549J550D01*
G01X1702520Y138254D01*
G02Y139352I550J549D01*
G01X1702521Y139353D01*
G03Y140451I-550J549D01*
G01X1701972Y141000D01*
G03X1697549Y142832I-4423J-4423D01*
G01X1696719D01*
G02X1695114Y143497I0J2270D01*
G03X1690708Y145322I-4406J-4406D01*
G01X1674912D01*
G03X1672406Y144284I0J-3544D01*
G01X1671795Y143673D01*
G02X1668331Y142238I-3464J3463D01*
G01X1663986D01*
G03X1662961Y141814I0J-1451D01*
G01X1662286Y141138D01*
G02X1660985Y140688I-1113J1113D01*
G01X1681352Y196092D02*
Y195253D01*
X1671350Y185251D01*
X1659167D01*
X1657483Y183567D01*
Y181237D01*
X1655682Y179436D01*
X1651808D01*
X1651000Y178628D01*
G01X1686183Y191250D02*
X1685400Y192033D01*
Y196895D01*
X1688170Y199665D01*
X1697270D01*
X1697271Y199666D01*
X1699158D01*
X1699159Y199665D01*
X1706285D01*
X1707242Y198708D01*
Y191321D01*
X1709314Y189249D01*
X1712531D01*
X1714000Y187780D01*
X1843073D01*
X1853273Y177580D01*
X1855720D01*
X1857400Y175900D01*
G01X1683484Y190908D02*
X1684607Y192031D01*
Y197166D01*
X1687858Y200417D01*
X1696958D01*
X1696959Y200418D01*
X1699470D01*
X1699471Y200417D01*
X1716083D01*
X1727968Y188532D01*
X1843698D01*
X1853898Y178332D01*
X1861168D01*
X1862000Y177500D01*
G01X1944600Y151700D02*
X1947484Y154584D01*
Y177092D01*
X1945598Y178978D01*
X1943950D01*
X1940696Y182232D01*
X1893368D01*
X1893260Y182124D01*
X1883747D01*
X1882824Y183047D01*
Y183889D01*
X1875305Y191408D01*
X1866771D01*
X1862072Y196107D01*
Y198757D01*
X1859153Y201676D01*
X1852693D01*
X1851471Y200454D01*
X1851417D01*
X1847728Y196765D01*
X1843835D01*
X1837403Y203197D01*
X1722374D01*
X1718993Y206578D01*
X1680908D01*
X1677304Y202974D01*
X1673348D01*
X1669522Y199148D01*
X1661680D01*
X1660583Y200245D01*
Y200646D01*
X1660440Y200789D01*
G01X1691439Y174354D02*
X1690185D01*
X1688168Y172337D01*
X1686121D01*
X1680188Y166404D01*
X1669948D01*
X1661722Y158178D01*
Y157172D01*
X1660985Y156435D01*
G01X1739064Y145800D02*
Y146745D01*
G03X1737861Y147948I-1203J0D01*
G03X1737121Y147208I0J-740D01*
G01Y146866D01*
G02X1735269I-926J0D01*
G01Y147057D01*
G03X1734531Y147795I-738J0D01*
G01X1732578D01*
G02X1732196Y147953I0J540D01*
G01X1726130Y154020D01*
G03X1723305Y155190I-2825J-2826D01*
G01X1720973D01*
G02X1720148Y155532I0J1166D01*
G01X1717280Y158400D01*
G02X1716750Y159679I1278J1279D01*
G01Y159954D01*
G03X1716288Y161071I-1582J0D01*
G01X1714992Y162367D01*
G03X1713063Y163166I-1929J-1929D01*
G01X1712335D01*
G03X1711732Y162563I0J-603D01*
G02X1711083Y161914I-649J0D01*
G01X1710529D01*
G02X1709880Y162563I0J649D01*
G03X1709277Y163166I-603J0D01*
G01X1707705D01*
G02X1707184Y163382I0J737D01*
G01X1706381Y164187D01*
G03X1700631Y166571I-5750J-5741D01*
G01X1695823D01*
G03X1694136Y165872I0J-2386D01*
G01X1692812Y164548D01*
G03Y163238I655J-655D01*
G01X1692888Y163162D01*
G02X1691578Y161852I-655J-655D01*
G01X1691502Y161928D01*
G03X1690353I-575J-574D01*
G01X1689912Y161488D01*
G03X1689785Y161180I308J-307D01*
G01X1739064Y142650D02*
X1738097Y143617D01*
G03X1736487Y144284I-1610J-1610D01*
G01X1736281D01*
G02X1732243Y145957I0J5710D01*
G01X1726730Y151470D01*
G03X1721106Y153800I-5625J-5624D01*
G02X1712109Y157526I-1J12723D01*
G01X1709858Y159777D01*
G03X1708202Y160463I-1656J-1656D01*
G02X1706453Y161382I824J3692D01*
G03X1698501Y164676I-7952J-7952D01*
G01X1695734D01*
G01X1688207Y168972D02*
X1690987Y171752D01*
G02X1693005Y172588I2018J-2018D01*
G01X1713538D01*
G02X1716186Y171491I0J-3744D01*
G01X1718612Y169065D01*
G03X1721489Y167874I2876J2877D01*
G01X1722417D01*
G02X1724238Y167120I0J-2576D01*
G01X1729500Y161858D01*
G02X1730050Y160531I-1328J-1328D01*
G01Y159650D01*
G03X1730757Y157943I2414J0D01*
G01X1732288Y156412D01*
X1732289D01*
G03X1733376Y155965I1088J1100D01*
G01X1734520D01*
G02X1736275Y155238I0J-2482D01*
G01X1743066Y148447D01*
G02X1743867Y146514I-1932J-1933D01*
G01Y144820D01*
G02X1743501Y143937I-1248J0D01*
G01X1742214Y142650D01*
G01X1673074Y453185D02*
X1666528D01*
X1656048Y442705D01*
Y409672D01*
X1657954Y407766D01*
Y394454D01*
X1655062Y391562D01*
Y376590D01*
X1664100Y367552D01*
Y316169D01*
X1660574Y312643D01*
Y258482D01*
X1673556Y245500D01*
X1681760D01*
G01X1942000Y440500D02*
X1941696Y440804D01*
X1908845D01*
X1904428Y436387D01*
X1683957D01*
X1679175Y431605D01*
Y317961D01*
X1679176Y317960D01*
Y317338D01*
X1679177Y317337D01*
Y311351D01*
X1679175Y311349D01*
Y308366D01*
X1676733Y305924D01*
Y298963D01*
X1674011Y296241D01*
Y269309D01*
X1681545Y261775D01*
X1682167D01*
X1682168Y261776D01*
X1825619D01*
X1825620Y261777D01*
X1831606D01*
X1831607Y261776D01*
X1866432D01*
X1887548Y240660D01*
X1907007D01*
X1934562Y213105D01*
Y206562D01*
X1930300Y202300D01*
X1918653D01*
X1917568Y201215D01*
G01X1882345Y231837D02*
X1878992Y235190D01*
Y238375D01*
X1870037Y247330D01*
X1862630D01*
X1859500Y244200D01*
X1848700D01*
X1844200Y248700D01*
X1838519D01*
X1832659Y254560D01*
X1685162D01*
X1685161Y254559D01*
X1678551D01*
X1666795Y266315D01*
Y299235D01*
X1669516Y301956D01*
Y309489D01*
X1671959Y311932D01*
Y314343D01*
X1671960Y314344D01*
Y314966D01*
X1671959Y314967D01*
Y417941D01*
X1665900Y424000D01*
Y425900D01*
X1667809Y427809D01*
G01X1882200Y234400D02*
X1881860Y234060D01*
X1881362D01*
X1879829Y235593D01*
Y238602D01*
X1870349Y248082D01*
X1862318D01*
X1859188Y244952D01*
X1849012D01*
X1844364Y249600D01*
X1838683D01*
X1832971Y255312D01*
X1684850D01*
X1684849Y255311D01*
X1678863D01*
X1667547Y266627D01*
Y298923D01*
X1670268Y301644D01*
Y309177D01*
X1672711Y311620D01*
Y314031D01*
X1672712Y314032D01*
Y315278D01*
X1672711Y315279D01*
Y418253D01*
X1667729Y423235D01*
Y424621D01*
G01X1669962Y440735D02*
X1669816D01*
X1670812Y439739D01*
Y437735D01*
X1673863Y434684D01*
Y315757D01*
X1673864Y315756D01*
Y313554D01*
X1673863Y313553D01*
Y311142D01*
X1671420Y308699D01*
Y301166D01*
X1668699Y298445D01*
Y267105D01*
X1679341Y256463D01*
X1684371D01*
X1684372Y256464D01*
X1834136D01*
X1839800Y250800D01*
X1845100D01*
X1849700Y246200D01*
X1857600D01*
X1861100Y249700D01*
X1870405D01*
X1884651Y235454D01*
Y234975D01*
G01X1899816Y235035D02*
X1897084Y237767D01*
X1886500D01*
X1865147Y259120D01*
X1683270D01*
X1683269Y259119D01*
X1680443D01*
X1671355Y268207D01*
Y297343D01*
X1674077Y300065D01*
Y303505D01*
X1674076Y303506D01*
Y307597D01*
X1676519Y310040D01*
Y312451D01*
X1676520Y312452D01*
Y316858D01*
X1676519Y316859D01*
Y436103D01*
X1673544Y439078D01*
Y440384D01*
X1675186Y442026D01*
Y443900D01*
X1673064Y446022D01*
G01X1667946Y412987D02*
X1671207Y409726D01*
Y312244D01*
X1668764Y309801D01*
Y302268D01*
X1666043Y299547D01*
Y267824D01*
X1666042Y267823D01*
Y267285D01*
X1666043Y267284D01*
Y266003D01*
X1678239Y253807D01*
X1685473D01*
X1685474Y253808D01*
X1827935D01*
X1834143Y247600D01*
X1843700D01*
X1848600Y242700D01*
Y233100D01*
X1860937Y220763D01*
X1890381D01*
X1890537Y220919D01*
X1910162D01*
X1910340Y220741D01*
G01X1926100Y231200D02*
X1925205Y232095D01*
X1920605D01*
X1909183Y243517D01*
X1888639D01*
X1867724Y264432D01*
X1832709D01*
X1832708Y264433D01*
X1824518D01*
X1824517Y264432D01*
X1682646D01*
X1676700Y270378D01*
Y286659D01*
X1679100Y289059D01*
Y289500D01*
G01Y286593D02*
X1677981D01*
X1677452Y286064D01*
Y270690D01*
X1682958Y265184D01*
X1824205D01*
X1824206Y265185D01*
X1833020D01*
X1833021Y265184D01*
X1868319D01*
X1889034Y244469D01*
X1909295D01*
X1920917Y232847D01*
X1924947D01*
X1925835Y233735D01*
G01X1884000Y188100D02*
X1885800Y186300D01*
X1898218D01*
X1914166Y202248D01*
Y202770D01*
X1916013Y204617D01*
X1929370D01*
X1932794Y208041D01*
Y212745D01*
X1906620Y238919D01*
X1886978D01*
X1865625Y260272D01*
X1830983D01*
X1830982Y260273D01*
X1826244D01*
X1826243Y260272D01*
X1682792D01*
X1682791Y260271D01*
X1680921D01*
X1672507Y268685D01*
Y296865D01*
X1675229Y299587D01*
Y303983D01*
X1675228Y303984D01*
Y307119D01*
X1677671Y309562D01*
Y311973D01*
X1677673Y311975D01*
Y316713D01*
X1677672Y316714D01*
Y317336D01*
X1677671Y317337D01*
Y434830D01*
X1680737Y437896D01*
X1902960D01*
X1907572Y442508D01*
X1931208D01*
X1938510Y449810D01*
Y460935D01*
X1946000Y468425D01*
Y473000D01*
X1945000Y474000D01*
G01X1884400Y183700D02*
X1886048Y185348D01*
X1898330D01*
X1914918Y201936D01*
Y202018D01*
X1916165Y203265D01*
X1929312D01*
X1933746Y207699D01*
Y212857D01*
X1906904Y239699D01*
X1887345D01*
X1866020Y261024D01*
X1831295D01*
X1831294Y261025D01*
X1825932D01*
X1825931Y261024D01*
X1682480D01*
X1682479Y261023D01*
X1681233D01*
X1673259Y268997D01*
Y296553D01*
X1675981Y299275D01*
Y304295D01*
X1675980Y304296D01*
Y306807D01*
X1678423Y309250D01*
Y311661D01*
X1678425Y311663D01*
Y317025D01*
X1678424Y317026D01*
Y317648D01*
X1678423Y317649D01*
Y434518D01*
X1681049Y437144D01*
X1903555D01*
X1907967Y441556D01*
X1931603D01*
X1939510Y449463D01*
Y460520D01*
X1947000Y468010D01*
Y473100D01*
X1948200Y474300D01*
G01X1972700Y549950D02*
X1971150Y548400D01*
Y519973D01*
X1972780Y518343D01*
Y452220D01*
X1958336Y437776D01*
X1907447D01*
X1904906Y435235D01*
X1684077D01*
X1679927Y431085D01*
Y318273D01*
X1679928Y318272D01*
Y317650D01*
X1679929Y317649D01*
Y311039D01*
X1679927Y311037D01*
Y308054D01*
X1677485Y305612D01*
Y298651D01*
X1674763Y295929D01*
Y269621D01*
X1681856Y262528D01*
X1825307D01*
X1825308Y262529D01*
X1831918D01*
X1831919Y262528D01*
X1866744D01*
X1887860Y241412D01*
X1907888D01*
X1927900Y221400D01*
X1931434D01*
X1935474Y217360D01*
Y206410D01*
X1929907Y200843D01*
Y198200D01*
X1932000Y196107D01*
Y192271D01*
X1944541Y179730D01*
X1945910D01*
X1948236Y177404D01*
Y153882D01*
X1947613Y153259D01*
Y152188D01*
X1944609Y149184D01*
G01X1679100Y294500D02*
X1678437Y293837D01*
Y293817D01*
X1675715Y291095D01*
Y270016D01*
X1682251Y263480D01*
X1824912D01*
X1824913Y263481D01*
X1832313D01*
X1832314Y263480D01*
X1867320D01*
X1888314Y242486D01*
X1908313D01*
X1928447Y222352D01*
X1932663D01*
X1943500Y211515D01*
Y209500D01*
G01X1719317Y441947D02*
X1684136D01*
X1677880Y448203D01*
Y450447D01*
X1676718Y451609D01*
X1672421D01*
X1671997Y452033D01*
X1667060D01*
X1657200Y442173D01*
Y410150D01*
X1659106Y408244D01*
Y393900D01*
X1656214Y391008D01*
Y377162D01*
X1665252Y368124D01*
Y315371D01*
X1661726Y311845D01*
Y258960D01*
X1673511Y247175D01*
X1682965D01*
X1684509Y245631D01*
G01X1683729Y242346D02*
X1682412Y241029D01*
X1675899D01*
X1661964Y254964D01*
X1657996D01*
X1655922Y257038D01*
Y292159D01*
X1655918Y292163D01*
Y314201D01*
X1659952Y318235D01*
Y368685D01*
X1651829Y376808D01*
Y445955D01*
X1651899Y446025D01*
Y447513D01*
X1660637Y456251D01*
X1661470D01*
G01X1680769Y242605D02*
X1675387D01*
X1659822Y258170D01*
Y317041D01*
X1660704Y317923D01*
Y368997D01*
X1652582Y377119D01*
Y417147D01*
X1652581Y417148D01*
Y445643D01*
X1660689Y453751D01*
X1661522D01*
G01X1896529Y235080D02*
X1894794Y236815D01*
X1886105D01*
X1864752Y258168D01*
X1683665D01*
X1683664Y258167D01*
X1680048D01*
X1670403Y267812D01*
Y297738D01*
X1673124Y300459D01*
Y307992D01*
X1675567Y310435D01*
Y312846D01*
X1675568Y312847D01*
Y316463D01*
X1675567Y316464D01*
Y435391D01*
X1672516Y438442D01*
Y440704D01*
X1672517Y440705D01*
Y441327D01*
X1672290Y441554D01*
Y441700D01*
X1671488Y442502D01*
Y446942D01*
X1673068Y448522D01*
G01X1667462Y440735D02*
X1667316D01*
Y438248D01*
X1662112Y433044D01*
Y413227D01*
X1667023Y408316D01*
Y383949D01*
X1662555Y379481D01*
Y376686D01*
X1670075Y369166D01*
Y313095D01*
X1667642Y310662D01*
Y302321D01*
X1664734Y299413D01*
Y266248D01*
X1678295Y252687D01*
X1717653D01*
X1724181Y246159D01*
G01X1669816Y443953D02*
Y442964D01*
X1670469Y442311D01*
X1670615D01*
X1671538Y441388D01*
Y441242D01*
X1671764Y441016D01*
Y438130D01*
X1674815Y435079D01*
Y316152D01*
X1674816Y316151D01*
Y313159D01*
X1674815Y313158D01*
Y310747D01*
X1672372Y308304D01*
Y300771D01*
X1669651Y298050D01*
Y267500D01*
X1679736Y257415D01*
X1683976D01*
X1683977Y257416D01*
X1834531D01*
X1840195Y251752D01*
X1845495D01*
X1850095Y247152D01*
X1857205D01*
X1860705Y250652D01*
X1871204D01*
X1885794Y236062D01*
X1891292D01*
X1892274Y235080D01*
G01X1850723Y219250D02*
X1849182Y220791D01*
Y226046D01*
X1845828Y229400D01*
X1834736D01*
X1831848Y232288D01*
Y236085D01*
X1824945Y242988D01*
X1719733D01*
X1718049Y244672D01*
Y245561D01*
X1718048Y245562D01*
Y246184D01*
X1718049Y246185D01*
Y246205D01*
X1716453Y247801D01*
X1708173D01*
X1705288Y250686D01*
X1693809D01*
X1689759Y246636D01*
X1686695D01*
X1685404Y247927D01*
X1674151D01*
X1662478Y259600D01*
Y310296D01*
X1667165Y314983D01*
Y368421D01*
X1660208Y375378D01*
Y381139D01*
X1664590Y385521D01*
Y406626D01*
X1659856Y411360D01*
Y441058D01*
X1665251Y446453D01*
X1669816D01*
G01X1664762Y443735D02*
X1660608Y439581D01*
Y411819D01*
X1665342Y407085D01*
Y385209D01*
X1660960Y380827D01*
Y375690D01*
X1667917Y368733D01*
Y313479D01*
X1666029Y311591D01*
Y303008D01*
X1663230Y300209D01*
Y260052D01*
X1674603Y248679D01*
X1687259D01*
X1687798Y248140D01*
X1690190D01*
X1693488Y251438D01*
X1705600D01*
X1708485Y248553D01*
X1717070D01*
X1718801Y246822D01*
Y244984D01*
X1719428Y244357D01*
X1824640D01*
X1832600Y236397D01*
Y232600D01*
X1834800Y230400D01*
X1848470D01*
X1859715Y219155D01*
X1876350D01*
X1877517Y217988D01*
G01X1664762Y440735D02*
X1663477D01*
X1661360Y438618D01*
Y412915D01*
X1666271Y408004D01*
Y384261D01*
X1661803Y379793D01*
Y376374D01*
X1669323Y368854D01*
Y313407D01*
X1666890Y310974D01*
Y302633D01*
X1663982Y299725D01*
Y265936D01*
X1677983Y251935D01*
X1682173D01*
X1683615Y250493D01*
G01X1676287Y447244D02*
Y447534D01*
X1673716Y450105D01*
X1671797D01*
X1671373Y450529D01*
X1667684D01*
X1658704Y441549D01*
Y410775D01*
X1663415Y406064D01*
Y392536D01*
X1661243Y390364D01*
G01X1676304Y449794D02*
X1675241Y450857D01*
X1672109D01*
X1671685Y451281D01*
X1667372D01*
X1657952Y441861D01*
Y410462D01*
X1662663Y405751D01*
Y394363D01*
X1661243Y392943D01*
G01X1664905Y376695D02*
X1665678Y377468D01*
X1666818D01*
X1670455Y381105D01*
Y408030D01*
X1664096Y414389D01*
Y430649D01*
X1665470Y432023D01*
X1666414D01*
X1667588Y430849D01*
X1667649D01*
G01X1664829Y379194D02*
X1665603Y378420D01*
X1666423D01*
X1669703Y381700D01*
Y407718D01*
X1663344Y414077D01*
Y430961D01*
X1665358Y432975D01*
X1666414D01*
X1667588Y434149D01*
G01X1841900Y498800D02*
X1838824Y495724D01*
X1829576D01*
X1827800Y497500D01*
X1813006D01*
X1810954Y495448D01*
X1794984D01*
X1792986Y493450D01*
X1781552D01*
X1770086Y481984D01*
X1733093D01*
X1730610Y484467D01*
X1728697D01*
X1728696Y484468D01*
X1728074D01*
X1728073Y484467D01*
X1714736D01*
X1709152Y490051D01*
X1693855D01*
X1692443Y488639D01*
Y487259D01*
G01X1689943Y487203D02*
X1691463Y485683D01*
X1693096D01*
X1694019Y486606D01*
Y487535D01*
X1695005Y488521D01*
X1705579D01*
X1711175Y482925D01*
X1731088D01*
X1732781Y481232D01*
X1779172D01*
X1783450Y485510D01*
X1790210D01*
X1792610Y487910D01*
Y492010D01*
X1795296Y494696D01*
X1827614D01*
X1839236Y483074D01*
X1851720D01*
X1856220Y487574D01*
Y525740D01*
X1845000Y536960D01*
Y537900D01*
X1854000Y546900D01*
Y549300D01*
X1852400Y550900D01*
Y554900D01*
G01X1873632Y500904D02*
X1873610D01*
Y500900D01*
X1871550D01*
X1851942Y481292D01*
X1839376D01*
X1826924Y493744D01*
X1795715D01*
X1793680Y491709D01*
Y487633D01*
X1790447Y484400D01*
X1785643D01*
X1785642Y484401D01*
X1784854D01*
X1784853Y484400D01*
X1783687D01*
X1779567Y480280D01*
X1732386D01*
X1730693Y481973D01*
X1710347D01*
X1706011Y486309D01*
X1700034D01*
X1697119Y483394D01*
X1688106D01*
X1687500Y484000D01*
G01X1914750Y544863D02*
Y544150D01*
X1918100Y540800D01*
X1930599D01*
X1935000Y536399D01*
Y526401D01*
X1931099Y522500D01*
X1918000D01*
X1915500Y520000D01*
Y516000D01*
X1912300Y512800D01*
X1896993D01*
X1878500Y494307D01*
Y483300D01*
X1864411Y469211D01*
X1851247D01*
X1846671Y464635D01*
X1832542D01*
X1831176Y463269D01*
X1721184D01*
X1708944Y475509D01*
X1685437D01*
X1684502Y476444D01*
X1655939D01*
X1655790Y476593D01*
G01X1687443Y487203D02*
X1691443Y491203D01*
X1710260D01*
X1715844Y485619D01*
X1727595D01*
X1727596Y485620D01*
X1729174D01*
X1729175Y485619D01*
X1731088D01*
X1733571Y483136D01*
X1755535D01*
X1773823Y501424D01*
X1795475D01*
X1800299Y496600D01*
X1810292D01*
X1812344Y498652D01*
X1832348D01*
X1833700Y497300D01*
G01X1823300Y21700D02*
Y21098D01*
X1825252Y19146D01*
Y8053D01*
X1823920Y6721D01*
X1821280D01*
X1818956Y4397D01*
X1813793D01*
X1810992Y1596D01*
X1797323D01*
X1796423Y696D01*
X1778443D01*
X1775271Y3868D01*
X1754394D01*
X1749085Y9177D01*
G01X1755500Y9076D02*
X1759956Y4620D01*
X1774959D01*
X1774960Y4621D01*
X1775582D01*
X1778755Y1448D01*
X1796111D01*
X1797011Y2348D01*
X1810680D01*
X1813481Y5149D01*
X1818644D01*
X1822024Y8529D01*
Y9633D01*
X1823075Y10684D01*
Y16125D01*
X1818200Y21000D01*
Y23539D01*
X1821759Y27098D01*
X1825545D01*
X1832541Y34094D01*
X1838694D01*
X1839400Y34800D01*
Y36241D01*
X1840275Y37116D01*
X1850427D01*
X1851659Y35884D01*
Y33577D01*
X1853453Y31783D01*
X1865816D01*
X1868818Y34785D01*
X1876236D01*
X1878997Y37546D01*
G01X1853317Y108197D02*
X1850926D01*
X1846253Y103524D01*
X1844440D01*
X1833061Y92145D01*
G01X1746491Y95650D02*
X1750299D01*
X1764600Y109951D01*
Y118685D01*
X1765015Y119100D01*
G01X1719080Y236152D02*
Y237256D01*
X1722930Y241106D01*
X1824562D01*
X1830342Y235326D01*
Y231666D01*
X1834455Y227553D01*
X1845193D01*
X1847005Y225741D01*
Y225740D01*
X1847154Y225591D01*
Y219526D01*
X1849758Y216922D01*
X1860522D01*
X1861251Y217651D01*
X1873748D01*
X1876160Y215239D01*
X1880436D01*
X1881387Y214288D01*
Y212988D01*
X1883800Y210575D01*
G01X1868015Y452987D02*
X1866423Y454579D01*
X1853484D01*
X1848797Y449892D01*
X1845870D01*
X1842102Y446124D01*
X1737259D01*
X1736019Y447364D01*
Y449719D01*
X1737150Y450850D01*
G01X1762715Y521085D02*
Y520685D01*
X1765756Y517644D01*
X1773691D01*
X1798971Y542924D01*
X1840324D01*
X1848800Y551400D01*
G01X1767529Y566200D02*
X1770414D01*
X1777746Y573532D01*
X1784862D01*
X1790125Y578795D01*
Y587898D01*
X1791349Y589122D01*
G01X1764300Y570900D02*
X1763500Y571700D01*
X1761400D01*
X1760400Y572700D01*
Y579900D01*
X1776000Y595500D01*
X1789853D01*
X1791323Y594030D01*
G01X1718037Y597184D02*
X1720544Y594677D01*
Y586628D01*
X1724000Y583172D01*
X1730064D01*
X1733368Y579868D01*
G01X1754000Y553500D02*
X1747480Y560020D01*
X1738438D01*
X1737958Y560500D01*
G01X1766400Y599400D02*
Y591100D01*
X1760467Y585167D01*
X1750567D01*
X1740900Y575500D01*
X1738900D01*
X1736000Y572600D01*
X1726480D01*
X1725694Y571814D01*
G01X1743500Y564500D02*
X1749500D01*
X1759500Y554500D01*
G01X1770600Y600800D02*
Y605450D01*
X1778800Y613650D01*
X1790060D01*
X1793700Y610010D01*
X1824180D01*
X1840220Y593970D01*
Y586680D01*
X1846260Y580640D01*
X1873350D01*
X1880870Y588160D01*
X1895690D01*
X1914650Y607120D01*
X1928690D01*
X1934410Y612840D01*
X1954680D01*
X1961580Y605940D01*
Y598660D01*
X1958420Y595500D01*
Y573840D01*
X1964890Y567370D01*
Y534940D01*
G01X1934544Y127957D02*
Y122942D01*
X1936544Y120942D01*
Y108413D01*
X1930039Y101908D01*
Y90461D01*
X1910978Y71400D01*
X1888670D01*
X1879120Y61850D01*
Y58231D01*
X1877240Y56351D01*
Y47450D01*
X1874020Y44230D01*
Y42844D01*
X1868224Y37048D01*
X1856402D01*
X1854430Y39020D01*
X1839309D01*
X1838929Y38640D01*
X1834393D01*
X1825003Y29250D01*
X1817750D01*
X1815150Y26650D01*
G01X1804800Y-1500D02*
X1806058Y-242D01*
X1819687D01*
X1822800Y2871D01*
Y3906D01*
X1823911Y5017D01*
X1824627D01*
X1826956Y7346D01*
Y16050D01*
X1830304Y19398D01*
Y22136D01*
X1831388Y23220D01*
X1837653D01*
X1841352Y26919D01*
Y31489D01*
X1845874Y36011D01*
X1849671D01*
X1850659Y35023D01*
Y33230D01*
X1853058Y30831D01*
X1866211D01*
X1869213Y33833D01*
X1877513D01*
X1884648Y40968D01*
Y63578D01*
X1890268Y69198D01*
X1911470D01*
X1937728Y95456D01*
Y99441D01*
G01X1798454Y82256D02*
X1801244D01*
X1804500Y79000D01*
X1816800D01*
X1823100Y85300D01*
X1825200D01*
X1827100Y83400D01*
Y81600D01*
G01X1863650Y189750D02*
Y192611D01*
X1856559Y199702D01*
X1851729D01*
X1847187Y195160D01*
X1841840D01*
X1840433Y196567D01*
X1830415D01*
G01X1834103Y176021D02*
X1834182Y176100D01*
X1850952D01*
X1851031Y176021D01*
X1851223D01*
X1853844Y173400D01*
X1859320D01*
X1860592Y174672D01*
X1862672D01*
X1866500Y178500D01*
X1875400D01*
X1885476Y168424D01*
X1887424D01*
X1889760Y170760D01*
X1912632D01*
X1922600Y180728D01*
X1940072D01*
X1942300Y178500D01*
Y175100D01*
X1943400Y174000D01*
Y153793D01*
X1942272Y152665D01*
Y149292D01*
X1945132Y146432D01*
X1945837D01*
X1945838Y146433D01*
X1946460D01*
X1946461Y146432D01*
X1946644D01*
X1949358Y143718D01*
Y140313D01*
X1950245Y139426D01*
Y136282D01*
X1939952Y125989D01*
Y113848D01*
X1946091Y107709D01*
X1949413D01*
X1952726Y104396D01*
Y102950D01*
G01X1833629Y170807D02*
Y171679D01*
X1836395Y174445D01*
X1850351D01*
X1852970Y171826D01*
X1860440D01*
X1860942Y172328D01*
X1865128D01*
X1868200Y175400D01*
X1872688D01*
X1883454Y164634D01*
X1887135D01*
X1892101Y169600D01*
X1912536D01*
X1922908Y179972D01*
X1938857D01*
X1941000Y177829D01*
Y174636D01*
X1942223Y173413D01*
Y153680D01*
X1941520Y152977D01*
Y148980D01*
X1944820Y145680D01*
X1946149D01*
X1948606Y143223D01*
Y139973D01*
X1949338Y139241D01*
Y136869D01*
X1939200Y126731D01*
Y112899D01*
X1940279Y111820D01*
Y111554D01*
X1940280Y111553D01*
Y110931D01*
X1940279Y110930D01*
Y95424D01*
X1912349Y67494D01*
X1892879D01*
X1886555Y61170D01*
Y38566D01*
X1880331Y32342D01*
Y30959D01*
X1866994Y17622D01*
X1849732D01*
X1845420Y13310D01*
G01X1848900Y548200D02*
X1846947D01*
X1840719Y541972D01*
X1802409D01*
X1786000Y525563D01*
Y522600D01*
G01X1837200Y525700D02*
X1831900Y531000D01*
X1821500D01*
X1820002Y532498D01*
X1813654D01*
X1813299Y532143D01*
Y526701D01*
X1813500Y526500D01*
G01X1793660Y560570D02*
X1795900Y558330D01*
Y552100D01*
X1793900Y550100D01*
G01X1809309Y555713D02*
X1810372Y556776D01*
X1819260D01*
X1821174Y554862D01*
X1842400D01*
X1844438Y556900D01*
X1853972D01*
X1856588Y554284D01*
X1857761D01*
X1857773Y554272D01*
X1858524D01*
X1861152Y556900D01*
X1869600D01*
X1869800Y557100D01*
G01X1861015Y130815D02*
X1865522D01*
X1866047Y131340D01*
X1898308D01*
X1900534Y133566D01*
Y135259D01*
X1901601Y136326D01*
X1906271D01*
X1908618Y138673D01*
X1913096D01*
X1914876Y136893D01*
Y127542D01*
X1918226Y124192D01*
X1920625D01*
X1921669Y125236D01*
Y131180D01*
X1921674Y131185D01*
Y131349D01*
X1924711Y134386D01*
X1930700D01*
X1932968Y132118D01*
Y123171D01*
X1935592Y120547D01*
Y108808D01*
X1928612Y101828D01*
Y90381D01*
X1910797Y72566D01*
X1901883D01*
X1900989Y73460D01*
X1896970D01*
G01X1895354Y75650D02*
X1899863D01*
X1902195Y73318D01*
X1910485D01*
X1927860Y90693D01*
Y101516D01*
X1927859Y101517D01*
Y102139D01*
X1927860Y102140D01*
Y102176D01*
X1934840Y109156D01*
Y120235D01*
X1932216Y122859D01*
Y131806D01*
X1930464Y133558D01*
X1924947D01*
X1922426Y131037D01*
Y124089D01*
X1919738Y121401D01*
X1902977D01*
X1901572Y122806D01*
Y126364D01*
X1897510Y130426D01*
X1869675D01*
X1869593Y130344D01*
X1868244D01*
X1862400Y124500D01*
G01X1883200Y76600D02*
X1894075D01*
X1894701Y77226D01*
X1899634D01*
X1902590Y74270D01*
X1910090D01*
X1925636Y89816D01*
Y117001D01*
X1923837Y118800D01*
G01X1940700Y136300D02*
Y144377D01*
X1939816Y145261D01*
Y153913D01*
X1933229Y160500D01*
X1927522D01*
X1924406Y163616D01*
X1891621D01*
X1886571Y158566D01*
X1884566D01*
X1883800Y157800D01*
Y155726D01*
X1881324Y153250D01*
G01X1927810Y123544D02*
X1926096D01*
X1921179Y118627D01*
X1913560D01*
X1908391Y113458D01*
X1905821D01*
X1902763Y110400D01*
X1895774D01*
X1890974Y105600D01*
G01X1919514Y131701D02*
X1917899D01*
X1916780Y132820D01*
Y137683D01*
X1913885Y140578D01*
X1913097D01*
X1913096Y140577D01*
X1907828D01*
X1905481Y138230D01*
X1900977D01*
X1896022Y133275D01*
X1873856D01*
X1867374Y139757D01*
X1867372D01*
X1863959Y143170D01*
X1858773D01*
X1852416Y149527D01*
X1837393D01*
X1837090Y149830D01*
G01X1857849Y148079D02*
X1859342Y149572D01*
X1864325D01*
X1871798Y142099D01*
X1874552D01*
X1875406Y142953D01*
X1876194D01*
X1876195Y142952D01*
X1880795D01*
X1884395Y139352D01*
X1888834D01*
X1893456Y143974D01*
X1896205D01*
X1899375Y147144D01*
X1900681D01*
X1901829Y145996D01*
X1912505D01*
X1915220Y143281D01*
Y142777D01*
X1920343Y137654D01*
X1932377D01*
X1934544Y135487D01*
Y127957D01*
G01X1919195Y134396D02*
Y137455D01*
X1914267Y142383D01*
Y142887D01*
X1912520Y144634D01*
X1903155D01*
X1901511Y142990D01*
Y140726D01*
X1900935Y140150D01*
X1899935D01*
X1897488Y137703D01*
X1883811D01*
X1879539Y141975D01*
X1876909D01*
X1873552Y138618D01*
X1872254D01*
G01X1839667Y151994D02*
X1845237D01*
X1846145Y151086D01*
X1852387D01*
X1859203Y144270D01*
X1866602D01*
X1872254Y138618D01*
G01X1878096Y152843D02*
X1878009Y152756D01*
Y150554D01*
X1878827Y149736D01*
X1887536D01*
X1888202Y150402D01*
Y157978D01*
X1892432Y162208D01*
X1923341D01*
X1923712Y161837D01*
Y160708D01*
X1923360Y160356D01*
X1893624D01*
X1893272Y160004D01*
Y158856D01*
X1893624Y158504D01*
X1924005D01*
X1924396Y158113D01*
Y157004D01*
X1924044Y156652D01*
X1890628D01*
X1890228Y156252D01*
Y155152D01*
X1890580Y154800D01*
X1925703D01*
X1926952Y156049D01*
G01X1836932Y170486D02*
X1839387Y172941D01*
X1849256D01*
X1851972Y170225D01*
X1856619D01*
X1860500Y166344D01*
Y157378D01*
X1861978Y155900D01*
X1871700D01*
X1872956Y154644D01*
X1878524D01*
X1879748Y153420D01*
Y152597D01*
X1880914Y151431D01*
X1886050D01*
G01X1927918Y126156D02*
X1927257D01*
X1920681Y119580D01*
X1902670D01*
X1900067Y122183D01*
Y122989D01*
X1900068Y122990D01*
Y125587D01*
X1896779Y128876D01*
X1870404D01*
X1868162Y126634D01*
Y123527D01*
X1866365Y121730D01*
X1863449D01*
X1863007Y122172D01*
X1857767D01*
X1853092Y126847D01*
Y130098D01*
X1854115Y131121D01*
G01X1854962Y133613D02*
X1855040D01*
Y133660D01*
X1855317Y133383D01*
X1855996D01*
X1859022Y130357D01*
Y124070D01*
X1860168Y122924D01*
X1863666D01*
X1864040Y122550D01*
X1865906D01*
X1867153Y123797D01*
Y126840D01*
X1869987Y129674D01*
X1897110D01*
X1900820Y125964D01*
Y122494D01*
X1902778Y120536D01*
X1919937D01*
X1927756Y128355D01*
X1929737D01*
Y128337D01*
X1929736D01*
G01X1884340Y217866D02*
X1881963D01*
X1879818Y220011D01*
X1860489D01*
X1847387Y233113D01*
Y240487D01*
X1843449Y244425D01*
G01X1918489Y212513D02*
X1917484Y213518D01*
X1904029D01*
X1898987Y208476D01*
Y201631D01*
X1896023Y198667D01*
X1893674D01*
X1892618Y197611D01*
X1873375D01*
X1869125Y201861D01*
X1864637D01*
G01X1869800Y557100D02*
X1867450Y559450D01*
Y561901D01*
X1874569Y569020D01*
X1888957D01*
X1908071Y588134D01*
Y591971D01*
X1910700Y594600D01*
X1914700D01*
G01X1897300Y548800D02*
X1894300D01*
X1891700Y551400D01*
X1867671D01*
X1853881Y537610D01*
X1847070D01*
G01X1918880Y586460D02*
X1908525D01*
X1888832Y566767D01*
X1883517D01*
X1882300Y565550D01*
G01X1958500Y535000D02*
X1957300Y536200D01*
Y542599D01*
X1946971Y552928D01*
X1943072D01*
X1935676Y560324D01*
X1932676D01*
X1928721Y564279D01*
Y587251D01*
X1928623Y587349D01*
Y591755D01*
X1922851Y597527D01*
X1911041D01*
X1906170Y592656D01*
Y588644D01*
X1888276Y570750D01*
X1867022D01*
X1862325Y566053D01*
X1852568D01*
X1852463Y565948D01*
X1850037D01*
X1849932Y566053D01*
X1842953D01*
X1840700Y563800D01*
G01X1946770Y98150D02*
X1948748Y100128D01*
X1954791D01*
X1955817Y101154D01*
Y103947D01*
X1963912Y112042D01*
X1967809D01*
X1972005Y116238D01*
Y130095D01*
X1965018Y137082D01*
X1962529D01*
X1956350Y143261D01*
Y176250D01*
X1944800Y187800D01*
G01X1943660Y98180D02*
X1946760Y101280D01*
X1954313D01*
X1954665Y101632D01*
Y104425D01*
X1963434Y113194D01*
X1967331D01*
X1970853Y116716D01*
Y129500D01*
X1964883Y135470D01*
X1962167D01*
X1955198Y142439D01*
Y175202D01*
X1948800Y181600D01*
G01X1944800Y187800D02*
X1941500D01*
X1937424Y191876D01*
Y196424D01*
X1939400Y198400D01*
G01X1934100Y193400D02*
Y191853D01*
X1944353Y181600D01*
X1948800D01*
G01X1959300Y518000D02*
X1959395Y518095D01*
Y522755D01*
X1962609Y525969D01*
Y546806D01*
X1957156Y552259D01*
Y599534D01*
X1955051Y601639D01*
X1938289D01*
X1938130Y601480D01*
G54D24*
G01X61800Y191600D02*
X66675Y186725D01*
Y160325D01*
X72950Y154050D01*
Y150850D01*
X74600Y149200D01*
Y120000D01*
X70600Y116000D01*
Y108684D01*
X69669Y107753D01*
Y102531D01*
X71982Y100218D01*
X78543D01*
X84294Y94467D01*
Y92936D01*
X85988Y91242D01*
X87064D01*
X91700Y95878D01*
X98141D01*
X102532Y91487D01*
Y83376D01*
X105500Y80408D01*
Y70300D01*
X103300Y68100D01*
Y29800D01*
X94671Y21171D01*
X89351D01*
X85569Y17389D01*
X64200D01*
G01X1963000Y573000D02*
X1967550Y568450D01*
Y528091D01*
X1961350Y521891D01*
Y519274D01*
X1961650Y518974D01*
Y512620D01*
X1957700Y508670D01*
G54D15*
X3937Y204370D03*
X-3937D03*
X-11811D03*
X35433D03*
X27559D03*
X19685D03*
X3937Y227992D03*
X-3937D03*
X-11811D03*
X35433D03*
X27559D03*
X19685D03*
X3937Y313504D03*
X-3937D03*
X-11811D03*
X3937Y337126D03*
X-3937D03*
X-11811D03*
X35433D03*
X27559D03*
X19685D03*
X35433Y313504D03*
X27559D03*
X19685D03*
G54D34*
G01X146299Y-42355D02*
X443146D01*
G02Y-45915I0J-1780D01*
G01X145585D01*
X144200Y-47300D01*
X65550D01*
X60500Y-42250D01*
G01X130313Y92757D02*
X129192Y91636D01*
Y88700D01*
X132092Y85800D01*
Y83832D01*
X130559Y82299D01*
Y81100D01*
X131809Y79850D01*
Y78950D01*
X130459Y77600D01*
Y76301D01*
X132092Y74668D01*
Y72367D01*
X132959Y71500D01*
G01X130313Y92757D02*
X127920Y95150D01*
Y108285D01*
X128835Y109200D01*
X131412D01*
X131884Y109672D01*
Y112704D01*
X131324Y113264D01*
X129952D01*
X129392Y113824D01*
Y115264D01*
X129952Y115824D01*
X131324D01*
X131884Y116384D01*
Y117824D01*
X131324Y118384D01*
X129952D01*
X129392Y118944D01*
Y120384D01*
X129952Y120944D01*
X131324D01*
X131884Y121504D01*
Y122944D01*
X131324Y123504D01*
X129952D01*
X129392Y124064D01*
Y125504D01*
X129952Y126064D01*
X131324D01*
X131884Y126624D01*
Y144060D01*
X248187Y260363D01*
X258392D01*
G01X160431Y92757D02*
X159503Y91829D01*
Y88701D01*
X162303Y85901D01*
Y84032D01*
X160920Y82649D01*
Y81250D01*
X162370Y79800D01*
Y78600D01*
X160870Y77100D01*
Y75901D01*
X162303Y74468D01*
Y72588D01*
X163391Y71500D01*
G01X163477Y87714D02*
X164703Y86488D01*
Y73475D01*
X165478Y72700D01*
Y71076D01*
X163902Y69500D01*
X162678D01*
X160431Y67253D01*
Y65699D01*
G01X132959Y87714D02*
X131084Y89589D01*
Y91092D01*
X132380Y92388D01*
Y99752D01*
X133984Y101356D01*
Y102573D01*
X133184Y103373D01*
X130884D01*
X130084Y104173D01*
Y105373D01*
X130884Y106173D01*
X133184D01*
X134384Y107373D01*
Y143024D01*
X249223Y257863D01*
X258392D01*
G01X130313Y65699D02*
Y67821D01*
X132192Y69700D01*
X133592D01*
X135048Y71156D01*
Y72500D01*
X134432Y73116D01*
Y86241D01*
X132959Y87714D01*
G01X153738Y92757D02*
X152617Y91636D01*
Y88700D01*
X155959Y85358D01*
Y84300D01*
X154159Y82500D01*
Y80925D01*
X155359Y79725D01*
Y78599D01*
X154159Y77399D01*
Y76026D01*
X155517Y74668D01*
Y73467D01*
X157084Y71900D01*
G01X153738Y92757D02*
X155438Y94457D01*
Y96347D01*
X157984Y98893D01*
Y124500D01*
X158784Y125300D01*
X159984D01*
X160784Y124500D01*
Y103200D01*
X161584Y102400D01*
X162784D01*
X163584Y103200D01*
Y150717D01*
X255526Y242659D01*
X258392D01*
G01X157084Y87714D02*
X155192Y89606D01*
Y91300D01*
X159792Y95900D01*
X163792D01*
X166684Y98792D01*
Y148856D01*
X167484Y149656D01*
X168684D01*
X169484Y148856D01*
Y133656D01*
X170284Y132856D01*
X171484D01*
X172284Y133656D01*
Y155881D01*
X256562Y240159D01*
X257892D01*
G01X153738Y65699D02*
X154985Y66946D01*
Y68200D01*
X156285Y69500D01*
X157285D01*
X159085Y71300D01*
Y72700D01*
X158473Y73312D01*
Y86325D01*
X157084Y87714D01*
G01X123620Y92757D02*
X122856Y93521D01*
Y131284D01*
X123416Y131844D01*
X125132D01*
X125692Y132404D01*
Y133844D01*
X125132Y134404D01*
X123416D01*
X122856Y134964D01*
Y142104D01*
X246115Y265363D01*
X257892D01*
G01X126580Y71500D02*
X125492Y72588D01*
Y74468D01*
X124059Y75901D01*
Y77100D01*
X125559Y78600D01*
Y79800D01*
X124109Y81250D01*
Y82649D01*
X125492Y84032D01*
Y85901D01*
X122692Y88701D01*
Y91829D01*
X123620Y92757D01*
G01X126666Y87714D02*
X124784Y89596D01*
Y91056D01*
X125420Y91692D01*
Y125729D01*
X129384Y129693D01*
Y145096D01*
X247151Y262863D01*
X257892D01*
G01X123620Y65699D02*
Y67253D01*
X125867Y69500D01*
X127091D01*
X128667Y71076D01*
Y72700D01*
X127892Y73475D01*
Y86488D01*
X126666Y87714D01*
G01X150391Y71900D02*
X148917Y73374D01*
Y74468D01*
X147484Y75901D01*
Y77124D01*
X148984Y78624D01*
Y79976D01*
X147484Y81476D01*
Y82599D01*
X149159Y84274D01*
Y85659D01*
X146117Y88701D01*
Y91829D01*
X147045Y92757D01*
G01D02*
Y131400D01*
X147845Y132200D01*
X149045D01*
X149845Y131400D01*
Y116400D01*
X150645Y115600D01*
X151845D01*
X152645Y116400D01*
Y126953D01*
X157184Y131492D01*
Y141608D01*
X154792Y144000D01*
Y145700D01*
X157184Y148092D01*
Y151389D01*
X253454Y247659D01*
X258392D01*
G01X150391Y87714D02*
X148584Y89521D01*
Y91156D01*
X149545Y92117D01*
Y112100D01*
X150345Y112900D01*
X151545D01*
X152345Y112100D01*
Y100900D01*
X153145Y100100D01*
X154345D01*
X155484Y101239D01*
Y126092D01*
X159984Y130592D01*
Y150653D01*
X254490Y245159D01*
X258392D01*
G01X147045Y65699D02*
X148292Y66946D01*
Y68200D01*
X149592Y69500D01*
X150592D01*
X152392Y71300D01*
Y72700D01*
X151780Y73312D01*
Y86325D01*
X150391Y87714D01*
G01X167124Y92757D02*
X166003Y91636D01*
Y88700D01*
X168903Y85800D01*
Y83832D01*
X167370Y82299D01*
Y81100D01*
X168620Y79850D01*
Y78950D01*
X167270Y77600D01*
Y76301D01*
X168903Y74668D01*
Y72367D01*
X169770Y71500D01*
G01Y87714D02*
X171243Y86241D01*
Y73116D01*
X171859Y72500D01*
Y71156D01*
X170403Y69700D01*
X169003D01*
X167124Y67821D01*
Y65699D01*
G01X141880Y87514D02*
Y87515D01*
X142978D01*
X144012Y86481D01*
Y83706D01*
X143306Y83000D01*
X142792D01*
X142092Y82300D01*
Y81300D01*
X142792Y80600D01*
X143292D01*
X144012Y79880D01*
Y78507D01*
X143205Y77700D01*
X142507D01*
X141906Y77099D01*
Y75901D01*
X142507Y75300D01*
X143305D01*
X144012Y74593D01*
Y71972D01*
X142989Y70949D01*
X141880D01*
G01Y87514D02*
X140126Y89268D01*
Y97505D01*
X141604Y98983D01*
Y134948D01*
X143192Y136536D01*
X150432D01*
X152704Y138808D01*
Y140604D01*
X149404Y143904D01*
Y146911D01*
X151093Y148600D01*
X152332D01*
X153204Y149472D01*
Y152747D01*
X251851Y251394D01*
X259846D01*
G01X136780Y89900D02*
X138506Y91626D01*
Y93386D01*
X137392Y94500D01*
X136706D01*
X135986Y95220D01*
Y97570D01*
X138684Y100268D01*
Y101100D01*
X138064Y101720D01*
Y102680D01*
X138684Y103300D01*
Y104300D01*
X138064Y104920D01*
Y105680D01*
X138684Y106300D01*
Y107300D01*
X138064Y107920D01*
Y108680D01*
X138684Y109300D01*
Y110300D01*
X138064Y110920D01*
Y111680D01*
X138684Y112300D01*
Y113300D01*
X138064Y113920D01*
Y114680D01*
X138684Y115300D01*
Y116300D01*
X138064Y116920D01*
Y141497D01*
X139810Y143243D01*
X140905D01*
X143972Y146310D01*
Y147405D01*
X250750Y254183D01*
X259376D01*
G01X136806Y68550D02*
X137576Y69320D01*
X138558D01*
X139886Y70648D01*
Y86794D01*
X136780Y89900D01*
G01X141880Y90114D02*
X143892Y92126D01*
Y93700D01*
X142892Y94700D01*
X141992D01*
X141186Y95506D01*
Y97062D01*
X142664Y98540D01*
Y99372D01*
X143284Y99992D01*
Y100992D01*
X142664Y101612D01*
Y102372D01*
X143284Y102992D01*
Y103992D01*
X142664Y104612D01*
Y105372D01*
X143284Y105992D01*
Y106992D01*
X142664Y107612D01*
Y108372D01*
X143284Y108992D01*
Y109992D01*
X142664Y110612D01*
Y111372D01*
X143284Y111992D01*
Y112992D01*
X142664Y113612D01*
Y134505D01*
X143635Y135476D01*
X150875D01*
X153200Y137800D01*
X153764Y138365D01*
Y141047D01*
X150464Y144347D01*
Y146468D01*
X151536Y147540D01*
X152775D01*
X154264Y149029D01*
Y152304D01*
X252294Y250334D01*
X259846D01*
G01X141880Y68340D02*
X145072Y71532D01*
Y86922D01*
X141880Y90114D01*
G01X136780Y87300D02*
X137879D01*
X138826Y86353D01*
Y83820D01*
X137856Y82850D01*
X137508D01*
X136892Y82234D01*
Y80902D01*
X137394Y80400D01*
X138106D01*
X138826Y79680D01*
Y78720D01*
X138006Y77900D01*
X137506D01*
X136906Y77300D01*
Y76300D01*
X138826Y74380D01*
Y71091D01*
X138115Y70380D01*
X137599D01*
X136780Y71199D01*
G01Y87300D02*
X134926Y89154D01*
Y98013D01*
X137004Y100091D01*
Y141940D01*
X139367Y144303D01*
X140462D01*
X142912Y146753D01*
Y147848D01*
X250307Y255243D01*
X259496D01*
G01X259291Y334836D02*
X254482D01*
X199892Y389426D01*
Y395300D01*
X151992Y443200D01*
X148292D01*
X134541Y456951D01*
Y477751D01*
X132292Y480000D01*
Y510717D01*
X129192Y513817D01*
Y517036D01*
X130313Y518157D01*
G01X259306Y337336D02*
X254649D01*
X201892Y390093D01*
Y395999D01*
X152791Y445100D01*
X149091D01*
X136609Y457582D01*
Y480074D01*
X135882Y480801D01*
X134889D01*
X134279Y481411D01*
Y482801D01*
X134889Y483411D01*
X136359D01*
X137049Y484101D01*
Y485491D01*
X136519Y486021D01*
X134863D01*
X134306Y486578D01*
Y487968D01*
X134969Y488631D01*
X136465D01*
X137075Y489241D01*
Y490631D01*
X136465Y491241D01*
X134757D01*
X134147Y491851D01*
Y493241D01*
X134757Y493851D01*
X136704D01*
X137314Y494461D01*
Y495851D01*
X136704Y496461D01*
X134730D01*
X134120Y497071D01*
Y498461D01*
X134730Y499071D01*
X136439D01*
X137049Y499681D01*
Y501071D01*
X136439Y501681D01*
X134731D01*
X134121Y502291D01*
Y503681D01*
X134880Y504440D01*
Y511193D01*
X132959Y513114D01*
G01X259422Y351460D02*
X256856D01*
X213792Y394524D01*
Y400900D01*
X162192Y452500D01*
Y505100D01*
X161392Y505900D01*
X159792D01*
X158992Y505100D01*
Y489894D01*
X158166Y489068D01*
X156566D01*
X155792Y489842D01*
Y510895D01*
X152380Y514307D01*
Y516799D01*
X153738Y518157D01*
G01X259480Y354000D02*
X256983D01*
X215677Y395306D01*
Y401682D01*
X171180Y446179D01*
Y470600D01*
X170380Y471400D01*
X168780D01*
X167980Y470600D01*
Y453400D01*
X167180Y452600D01*
X165580D01*
X164780Y453400D01*
Y507000D01*
X163680Y508100D01*
X158880D01*
X158380Y508600D01*
Y511870D01*
X157084Y513166D01*
Y513114D01*
G01X259124Y330247D02*
X253739D01*
X196092Y387894D01*
Y393600D01*
X150292Y439400D01*
X146284D01*
X129716Y455968D01*
X127859Y460450D01*
Y504747D01*
X125134Y511327D01*
X123002Y513459D01*
Y517539D01*
X123620Y518157D01*
G01X259233Y332336D02*
X254316D01*
X197992Y388660D01*
Y394500D01*
X151192Y441300D01*
X147144D01*
X131350Y457094D01*
X130136Y460026D01*
Y461345D01*
X130746Y461955D01*
X132053D01*
X132703Y462605D01*
Y463995D01*
X132133Y464565D01*
X130746D01*
X130136Y465175D01*
Y466565D01*
X130746Y467175D01*
X131626D01*
X132236Y467785D01*
Y469175D01*
X131626Y469785D01*
X130380D01*
X129792Y470373D01*
Y472559D01*
X130402Y473169D01*
X132082D01*
X132672Y473759D01*
Y475149D01*
X132042Y475779D01*
X130402D01*
X129792Y476389D01*
Y506900D01*
X128180Y508512D01*
Y511600D01*
X126666Y513114D01*
G01X259334Y347560D02*
X255424D01*
X209992Y392992D01*
Y399300D01*
X157192Y452100D01*
Y468070D01*
X156392Y468870D01*
X154792D01*
X153992Y468070D01*
Y455678D01*
X153218Y454904D01*
X151618D01*
X150792Y455730D01*
Y506300D01*
X149280Y507812D01*
Y510757D01*
X146380Y513657D01*
Y517492D01*
X147045Y518157D01*
G01X259334Y349616D02*
X256034D01*
X211892Y393758D01*
Y400100D01*
X159692Y452300D01*
Y486200D01*
X158792Y487100D01*
X157192D01*
X156492Y486400D01*
Y471863D01*
X155692Y471063D01*
X154092D01*
X153292Y471863D01*
Y507400D01*
X151780Y508912D01*
Y511768D01*
X151737D01*
X150391Y513114D01*
G01X258654Y343817D02*
X255001D01*
X207032Y391786D01*
Y398060D01*
X154968Y450124D01*
X150936D01*
X146812Y454248D01*
Y475520D01*
X145940Y476392D01*
X144801D01*
X143312Y477881D01*
Y480463D01*
X144801Y481952D01*
X145940D01*
X146812Y482824D01*
Y484520D01*
X145940Y485392D01*
X144601D01*
X143112Y486881D01*
Y489463D01*
X144601Y490952D01*
X145940D01*
X146812Y491824D01*
Y493520D01*
X145940Y494392D01*
X144401D01*
X142912Y495881D01*
Y498463D01*
X144401Y499952D01*
X145572D01*
X146812Y501192D01*
Y502749D01*
X143912Y505649D01*
Y507080D01*
X143392Y507600D01*
Y509000D01*
X143912Y509520D01*
Y512280D01*
X143278Y512914D01*
X141880D01*
G01X259012Y341156D02*
X254995D01*
X204892Y391259D01*
Y397399D01*
X154091Y448200D01*
X150191D01*
X141072Y457319D01*
Y458183D01*
X141544Y458655D01*
X142580D01*
X142602Y458676D01*
X143872Y459947D01*
Y462823D01*
X142480Y464215D01*
X141344D01*
X140672Y464887D01*
Y466783D01*
X141544Y467655D01*
X142875D01*
X144064Y468844D01*
Y471726D01*
X142575Y473215D01*
X141044D01*
X140072Y474187D01*
Y512008D01*
X136780Y515300D01*
G01X258654Y344877D02*
X255441D01*
X208092Y392226D01*
Y398500D01*
X155408Y451184D01*
X151376D01*
X147872Y454688D01*
Y475960D01*
X146380Y477452D01*
X145244D01*
X144372Y478324D01*
Y480020D01*
X145244Y480892D01*
X146383D01*
X147872Y482381D01*
Y484963D01*
X146383Y486452D01*
X145044D01*
X144172Y487324D01*
Y489020D01*
X145044Y489892D01*
X146383D01*
X147872Y491381D01*
Y493963D01*
X146383Y495452D01*
X144844D01*
X143972Y496324D01*
Y498020D01*
X144844Y498892D01*
X146015D01*
X147872Y500749D01*
Y503192D01*
X144972Y506092D01*
Y512720D01*
X143718Y513974D01*
X143420D01*
X141880Y515514D01*
G01X258847Y340096D02*
X254555D01*
X203832Y390819D01*
Y396959D01*
X153651Y447140D01*
X149751D01*
X140012Y456879D01*
Y458623D01*
X141104Y459715D01*
X142140D01*
X142812Y460387D01*
Y462383D01*
X142040Y463155D01*
X140904D01*
X139612Y464447D01*
Y467223D01*
X141104Y468715D01*
X142435D01*
X143004Y469284D01*
Y471286D01*
X142135Y472155D01*
X140604D01*
X139012Y473747D01*
Y506680D01*
X138392Y507300D01*
Y508500D01*
X139012Y509120D01*
Y511568D01*
X137761Y512819D01*
X136899D01*
X136780Y512700D01*
G01X130313Y518157D02*
X128608Y519862D01*
Y530349D01*
X132959Y534700D01*
G01X163391D02*
X162403D01*
X159348Y531645D01*
Y530457D01*
X158726Y529835D01*
Y519862D01*
X160431Y518157D01*
G01Y528899D02*
X161503D01*
X162103Y528299D01*
Y527401D01*
X161066Y526364D01*
Y525136D01*
X162003Y524199D01*
Y522801D01*
X161066Y521864D01*
Y520536D01*
X162203Y519399D01*
Y517500D01*
X161703Y517000D01*
Y514800D01*
X163389Y513114D01*
X163477D01*
G01X132959D02*
X132871D01*
X131185Y514800D01*
Y516492D01*
X132092Y517399D01*
Y518992D01*
X130948Y520136D01*
Y521556D01*
X131792Y522400D01*
Y524100D01*
X130948Y524944D01*
Y526156D01*
X131892Y527100D01*
Y528300D01*
X131293Y528899D01*
X130313D01*
G01X153738Y518157D02*
X152033Y519862D01*
Y530049D01*
X157084Y535100D01*
G01Y513114D02*
X156996D01*
X155310Y514800D01*
Y516492D01*
X155485Y516667D01*
Y519300D01*
X154373Y520412D01*
Y521488D01*
X155385Y522500D01*
Y523700D01*
X154373Y524712D01*
Y525788D01*
X155510Y526925D01*
Y528199D01*
X154810Y528899D01*
X153738D01*
G01X123620Y518157D02*
X121915Y522274D01*
Y529277D01*
X122451Y530571D01*
X126580Y534700D01*
G01X126666Y513114D02*
X126578D01*
X124892Y514800D01*
Y517000D01*
X125392Y517500D01*
Y519764D01*
X124255Y520901D01*
Y522229D01*
X125192Y523166D01*
Y524199D01*
X124255Y525136D01*
Y526364D01*
X125292Y527401D01*
Y528299D01*
X124692Y528899D01*
X123620D01*
G01X147045Y518157D02*
X145340Y519862D01*
Y530049D01*
X150391Y535100D01*
G01Y513114D02*
X150303D01*
X148617Y514800D01*
Y516492D01*
X148792Y516667D01*
Y519300D01*
X147680Y520412D01*
Y521488D01*
X148692Y522500D01*
Y523700D01*
X147680Y524712D01*
Y525788D01*
X148817Y526925D01*
Y528199D01*
X148117Y528899D01*
X147045D01*
G01X169770Y534700D02*
X168604D01*
X165419Y531515D01*
Y519862D01*
X167124Y518157D01*
G01X169770Y513114D02*
X168678D01*
X167996Y513796D01*
Y516492D01*
X168903Y517399D01*
Y518992D01*
X167759Y520136D01*
Y521556D01*
X168603Y522400D01*
Y524100D01*
X167759Y524944D01*
Y526156D01*
X168703Y527100D01*
Y528300D01*
X168104Y528899D01*
X167124D01*
G01X141880Y534149D02*
X140175Y532444D01*
Y527500D01*
X139345Y526670D01*
Y520130D01*
X140175Y519300D01*
Y514331D01*
X141592Y512914D01*
X141880D01*
G01X136780Y515300D02*
X138492Y517012D01*
Y518600D01*
X137392Y519700D01*
X136442D01*
X135852Y520290D01*
Y521660D01*
X136372Y522180D01*
X136982D01*
X137592Y522790D01*
Y524180D01*
X136982Y524790D01*
X136402D01*
X135852Y525340D01*
Y526760D01*
X136492Y527400D01*
X137772D01*
X138511Y528139D01*
Y530045D01*
X136806Y531750D01*
G01X141880Y531540D02*
X143692Y529728D01*
Y528000D01*
X142692Y527000D01*
X141176D01*
X140405Y526229D01*
Y525338D01*
X140945Y524798D01*
X141182D01*
X141872Y524108D01*
Y522980D01*
X141192Y522300D01*
X140857D01*
X140405Y521848D01*
Y520571D01*
X141076Y519900D01*
X142592D01*
X143592Y518900D01*
Y517226D01*
X141880Y515514D01*
G01X136780Y512700D02*
X136492D01*
X134792Y514400D01*
Y532411D01*
X136780Y534399D01*
G01X190549Y92757D02*
X189428Y91636D01*
Y88700D01*
X192770Y85358D01*
Y84300D01*
X190970Y82500D01*
Y80925D01*
X192170Y79725D01*
Y78599D01*
X190970Y77399D01*
Y76026D01*
X192328Y74668D01*
Y73467D01*
X193895Y71900D01*
G01Y87714D02*
X195284Y86325D01*
Y73312D01*
X195896Y72700D01*
Y71300D01*
X194096Y69500D01*
X193096D01*
X191796Y68200D01*
Y66946D01*
X190549Y65699D01*
G01X187202Y71900D02*
X185728Y73374D01*
Y74468D01*
X184295Y75901D01*
Y77124D01*
X185795Y78624D01*
Y79976D01*
X184295Y81476D01*
Y82599D01*
X185970Y84274D01*
Y85659D01*
X182928Y88701D01*
Y91829D01*
X183856Y92757D01*
G01X187202Y87714D02*
X188591Y86325D01*
Y73312D01*
X189203Y72700D01*
Y71300D01*
X187403Y69500D01*
X186403D01*
X185103Y68200D01*
Y66946D01*
X183856Y65699D01*
G01X203935Y92757D02*
X201292Y95400D01*
Y97100D01*
X200592Y97800D01*
Y99885D01*
X201152Y100445D01*
X202132D01*
X202692Y101005D01*
Y102445D01*
X202132Y103005D01*
X201152D01*
X200592Y103565D01*
Y105005D01*
X201152Y105565D01*
X202132D01*
X202692Y106125D01*
Y107565D01*
X202132Y108125D01*
X201152D01*
X200592Y108685D01*
Y110125D01*
X201152Y110685D01*
X202132D01*
X202692Y111245D01*
Y112685D01*
X202132Y113245D01*
X201152D01*
X200592Y113805D01*
Y115245D01*
X201152Y115805D01*
X202132D01*
X202692Y116365D01*
Y117805D01*
X202132Y118365D01*
X201152D01*
X200592Y118925D01*
Y120365D01*
X201152Y120925D01*
X202132D01*
X202692Y121485D01*
Y122925D01*
X202132Y123485D01*
X201152D01*
X200592Y124045D01*
Y171336D01*
X257108Y227852D01*
X260840D01*
G01X206581Y71500D02*
X205714Y72367D01*
Y74668D01*
X204081Y76301D01*
Y77600D01*
X205431Y78950D01*
Y79850D01*
X204181Y81100D01*
Y82299D01*
X205714Y83832D01*
Y85800D01*
X202814Y88700D01*
Y91636D01*
X203935Y92757D01*
G01X206581Y87714D02*
X204684Y89611D01*
Y90992D01*
X205866Y92174D01*
Y93774D01*
X204784Y94856D01*
Y128373D01*
X203384Y129773D01*
Y168292D01*
X257092Y222000D01*
Y224300D01*
X258094Y225302D01*
X260209D01*
G01X203935Y65699D02*
Y67821D01*
X205814Y69700D01*
X207214D01*
X208670Y71156D01*
Y72500D01*
X208054Y73116D01*
Y86241D01*
X206581Y87714D01*
G01X227360Y92757D02*
Y93780D01*
X222084Y99056D01*
Y132339D01*
X222945Y133200D01*
X224145D01*
X224945Y132400D01*
Y112600D01*
X225745Y111800D01*
X226945D01*
X227745Y112600D01*
Y169253D01*
X245092Y186600D01*
X248292D01*
X267448Y205756D01*
G01X230706Y71900D02*
X229139Y73467D01*
Y74668D01*
X227781Y76026D01*
Y77399D01*
X228981Y78599D01*
Y79725D01*
X227781Y80925D01*
Y82500D01*
X229581Y84300D01*
Y85358D01*
X226239Y88700D01*
Y91636D01*
X227360Y92757D01*
G01X230706Y87714D02*
X228802Y89618D01*
Y91218D01*
X229584Y92000D01*
Y96139D01*
X231445Y98000D01*
Y106440D01*
X230885Y107000D01*
X229205D01*
X228645Y106440D01*
Y99853D01*
X227631Y98839D01*
X225445D01*
X224645Y99639D01*
Y108800D01*
X225445Y109600D01*
X229445D01*
X230245Y110400D01*
Y145952D01*
X230855Y146562D01*
X231982D01*
X232592Y147172D01*
Y148562D01*
X231982Y149172D01*
X230855D01*
X230245Y149782D01*
Y151172D01*
X230855Y151782D01*
X231982D01*
X232592Y152392D01*
Y153782D01*
X231982Y154392D01*
X230855D01*
X230245Y155002D01*
Y156392D01*
X230855Y157002D01*
X231982D01*
X232592Y157612D01*
Y159002D01*
X231982Y159612D01*
X230855D01*
X230245Y160222D01*
Y161612D01*
X230855Y162222D01*
X231982D01*
X232592Y162832D01*
Y164222D01*
X231982Y164832D01*
X230855D01*
X230245Y165442D01*
Y168053D01*
X244792Y182600D01*
X247899D01*
X268612Y203313D01*
G01X227360Y65699D02*
X228607Y66946D01*
Y68200D01*
X229907Y69500D01*
X230907D01*
X232707Y71300D01*
Y72700D01*
X232095Y73312D01*
Y86325D01*
X230706Y87714D01*
G01X197242Y92757D02*
X195684Y94315D01*
Y173341D01*
X255295Y232952D01*
X261045D01*
G01X200202Y71500D02*
X199114Y72588D01*
Y74468D01*
X197681Y75901D01*
Y77100D01*
X199181Y78600D01*
Y79800D01*
X197731Y81250D01*
Y82649D01*
X199114Y84032D01*
Y85901D01*
X196314Y88701D01*
Y91829D01*
X197242Y92757D01*
G01X200288Y87714D02*
X198384Y89618D01*
Y91192D01*
X199184Y91992D01*
Y95801D01*
X198642Y96343D01*
Y172301D01*
X256743Y230402D01*
X260898D01*
G01X197242Y65699D02*
Y67253D01*
X199489Y69500D01*
X200713D01*
X202289Y71076D01*
Y72700D01*
X201514Y73475D01*
Y86488D01*
X200288Y87714D01*
G01X220667Y92761D02*
X219739Y91833D01*
Y88701D01*
X222781Y85659D01*
Y84274D01*
X221106Y82599D01*
Y81476D01*
X222606Y79976D01*
Y78624D01*
X221106Y77124D01*
Y75901D01*
X222539Y74468D01*
Y73374D01*
X224013Y71900D01*
G01X264608Y212380D02*
X263572D01*
X252792Y201600D01*
X250392D01*
X247433Y198641D01*
Y197849D01*
X248591Y196691D01*
Y195899D01*
X247572Y194880D01*
X246780D01*
X245622Y196038D01*
X244830D01*
X216984Y168192D01*
Y165850D01*
X217544Y165290D01*
X222732D01*
X223292Y164730D01*
Y163290D01*
X222732Y162730D01*
X217544D01*
X216984Y162170D01*
Y160730D01*
X217544Y160170D01*
X222732D01*
X223292Y159610D01*
Y158170D01*
X222732Y157610D01*
X217544D01*
X216984Y157050D01*
Y155610D01*
X217544Y155050D01*
X222732D01*
X223292Y154490D01*
Y153050D01*
X222732Y152490D01*
X217544D01*
X216984Y151930D01*
Y98008D01*
X220667Y94325D01*
Y92761D01*
G01X224013Y87714D02*
X222184Y89543D01*
Y91092D01*
X222984Y91892D01*
Y95008D01*
X219584Y98408D01*
Y149594D01*
X220324Y150334D01*
X221524D01*
X222445Y149413D01*
Y135900D01*
X223245Y135100D01*
X224445D01*
X225245Y135900D01*
Y171653D01*
X244592Y191000D01*
X249792D01*
X263149Y204357D01*
Y208243D01*
X264736Y209830D01*
G01X220667Y65699D02*
X221914Y66946D01*
Y68200D01*
X223214Y69500D01*
X224214D01*
X226014Y71300D01*
Y72700D01*
X225402Y73312D01*
Y86325D01*
X224013Y87714D01*
G01X173591Y89900D02*
X176697Y86794D01*
Y70648D01*
X175369Y69320D01*
X174387D01*
X173617Y68550D01*
G01X210402Y89900D02*
X213508Y86794D01*
Y70648D01*
X212180Y69320D01*
X211198D01*
X210428Y68550D01*
G01X258368Y219025D02*
X257732Y218389D01*
Y217681D01*
X257096Y217045D01*
X256388D01*
X255752Y216409D01*
Y215701D01*
X255116Y215065D01*
X254408D01*
X253715Y214372D01*
Y213664D01*
X253078Y213027D01*
X252370D01*
X251734Y212391D01*
Y211683D01*
X251098Y211047D01*
X250390D01*
X249754Y210411D01*
Y209703D01*
X249118Y209067D01*
X248410D01*
X247640Y208297D01*
Y207589D01*
X247003Y206952D01*
X246295D01*
X245440Y206097D01*
Y205389D01*
X244803Y204752D01*
X244095D01*
X243265Y203922D01*
Y203214D01*
X242628Y202577D01*
X241920D01*
X240840Y201497D01*
Y200789D01*
X240203Y200152D01*
X239495D01*
X238840Y199497D01*
Y198789D01*
X238203Y198152D01*
X237495D01*
X236815Y197472D01*
Y196764D01*
X236178Y196127D01*
X235470D01*
X234834Y195491D01*
Y194783D01*
X234198Y194147D01*
X233490D01*
X232790Y193447D01*
Y192899D01*
X231993Y192102D01*
X231445D01*
X230715Y191372D01*
Y190872D01*
X229870Y190027D01*
X229370D01*
X210464Y171121D01*
Y169572D01*
X208072Y167180D01*
Y166320D01*
X210464Y163928D01*
Y161477D01*
X208972Y159985D01*
X207464D01*
X206592Y159113D01*
Y156447D01*
X207294Y155745D01*
X209653D01*
X211142Y154256D01*
Y150804D01*
X209723Y149385D01*
X207944D01*
X207164Y148605D01*
Y131200D01*
X208564Y129800D01*
Y108264D01*
X209184Y107644D01*
Y106644D01*
X208564Y106024D01*
Y105264D01*
X209184Y104644D01*
Y103644D01*
X208564Y103024D01*
Y102264D01*
X209184Y101644D01*
Y100644D01*
X208564Y100024D01*
Y99264D01*
X209184Y98644D01*
Y97644D01*
X208564Y97024D01*
Y96096D01*
X210160Y94500D01*
X211328D01*
X212128Y93700D01*
Y91626D01*
X210402Y89900D01*
G01X178691Y87514D02*
Y87515D01*
X179789D01*
X180823Y86481D01*
Y83706D01*
X180117Y83000D01*
X179603D01*
X178903Y82300D01*
Y81300D01*
X179603Y80600D01*
X180103D01*
X180823Y79880D01*
Y78507D01*
X180016Y77700D01*
X179318D01*
X178717Y77099D01*
Y75901D01*
X179318Y75300D01*
X180116D01*
X180823Y74593D01*
Y71972D01*
X179800Y70949D01*
X178691D01*
G01X215502Y87514D02*
Y87515D01*
X216600D01*
X217634Y86481D01*
Y83706D01*
X216928Y83000D01*
X216414D01*
X215714Y82300D01*
Y81300D01*
X216414Y80600D01*
X216914D01*
X217634Y79880D01*
Y78507D01*
X216827Y77700D01*
X216129D01*
X215528Y77099D01*
Y75901D01*
X216129Y75300D01*
X216927D01*
X217634Y74593D01*
Y71972D01*
X216611Y70949D01*
X215502D01*
G01X265461Y218396D02*
X263022D01*
X213204Y168578D01*
Y147764D01*
X212332Y146892D01*
X211693D01*
X209904Y145103D01*
Y142021D01*
X211393Y140532D01*
X212332D01*
X213204Y139660D01*
Y137164D01*
X212332Y136292D01*
X211789D01*
X210204Y134707D01*
Y132324D01*
X213204Y129324D01*
Y126400D01*
X210992Y124188D01*
Y121112D01*
X213204Y118900D01*
Y115012D01*
X212436Y114244D01*
Y96721D01*
X213778Y95379D01*
Y89238D01*
X215502Y87514D01*
G01X173591Y87300D02*
X174690D01*
X175637Y86353D01*
Y83820D01*
X174667Y82850D01*
X174319D01*
X173703Y82234D01*
Y80902D01*
X174205Y80400D01*
X174917D01*
X175637Y79680D01*
Y78720D01*
X174817Y77900D01*
X174317D01*
X173717Y77300D01*
Y76300D01*
X175637Y74380D01*
Y71091D01*
X174926Y70380D01*
X174410D01*
X173591Y71199D01*
G01X210402Y87300D02*
X211501D01*
X212448Y86353D01*
Y83820D01*
X211478Y82850D01*
X211130D01*
X210514Y82234D01*
Y80902D01*
X211016Y80400D01*
X211728D01*
X212448Y79680D01*
Y78720D01*
X211628Y77900D01*
X211128D01*
X210528Y77300D01*
Y76300D01*
X212448Y74380D01*
Y71091D01*
X211737Y70380D01*
X211221D01*
X210402Y71199D01*
G01X257618Y219775D02*
X209404Y171561D01*
Y170012D01*
X207012Y167620D01*
Y165880D01*
X209404Y163488D01*
Y161917D01*
X208532Y161045D01*
X207024D01*
X205532Y159553D01*
Y156007D01*
X206854Y154685D01*
X209213D01*
X210082Y153816D01*
Y151244D01*
X209283Y150445D01*
X207501D01*
X206104Y149048D01*
Y130757D01*
X207504Y129357D01*
Y95653D01*
X208428Y94729D01*
Y89274D01*
X210402Y87300D01*
G01X178691Y90114D02*
X181883Y86922D01*
Y71532D01*
X178691Y68340D01*
G01X215502Y90114D02*
X217328Y91940D01*
Y93332D01*
X213496Y97164D01*
Y98092D01*
X214116Y98712D01*
Y99712D01*
X213496Y100332D01*
Y101092D01*
X214116Y101712D01*
Y102712D01*
X213496Y103332D01*
Y104092D01*
X214116Y104712D01*
Y105712D01*
X213496Y106332D01*
Y107092D01*
X214116Y107712D01*
Y108712D01*
X213496Y109332D01*
Y110180D01*
X214116Y110800D01*
Y111800D01*
X213496Y112420D01*
Y113804D01*
X214264Y114572D01*
Y119340D01*
X212052Y121552D01*
Y123748D01*
X214264Y125960D01*
Y129764D01*
X211264Y132764D01*
Y134264D01*
X212232Y135232D01*
X212775D01*
X214264Y136721D01*
Y140103D01*
X212775Y141592D01*
X211836D01*
X210964Y142464D01*
Y144660D01*
X212136Y145832D01*
X212775D01*
X214264Y147321D01*
Y168138D01*
X250847Y204721D01*
X251555D01*
X252191Y205357D01*
Y206065D01*
X252827Y206701D01*
X253535D01*
X254171Y207337D01*
Y208045D01*
X254807Y208681D01*
X255515D01*
X256151Y209317D01*
Y210025D01*
X256787Y210661D01*
X257495D01*
X258131Y211297D01*
Y212005D01*
X259307Y213181D01*
X260015D01*
X260651Y213817D01*
Y214525D01*
X261287Y215161D01*
X261995D01*
X262631Y215797D01*
Y216505D01*
X263462Y217336D01*
X265461D01*
G01X215502Y68340D02*
X218694Y71532D01*
Y86922D01*
X215502Y90114D01*
G01X262499Y363076D02*
X259028D01*
X222457Y399647D01*
Y407873D01*
X197892Y432438D01*
Y497300D01*
X201092Y500500D01*
Y504200D01*
X205592Y508700D01*
Y510900D01*
X202502Y513990D01*
Y516926D01*
X203733Y518157D01*
X203935D01*
G01X262499Y365627D02*
X259143D01*
X224342Y400428D01*
Y409524D01*
X200492Y433374D01*
Y485646D01*
X201052Y486206D01*
X204432D01*
X204992Y486766D01*
Y488206D01*
X204432Y488766D01*
X201052D01*
X200492Y489326D01*
Y490766D01*
X201052Y491326D01*
X204432D01*
X204992Y491886D01*
Y493326D01*
X204432Y493886D01*
X201052D01*
X200492Y494446D01*
Y496300D01*
X201292Y497100D01*
X202892D01*
X203692Y497900D01*
Y503600D01*
X208092Y508000D01*
Y511603D01*
X206581Y513114D01*
G01X263236Y357831D02*
X258941D01*
X218687Y398085D01*
Y404505D01*
X192792Y430400D01*
Y505023D01*
X196753Y514587D01*
Y516976D01*
X197242Y518157D01*
G01X263264Y360381D02*
X259057D01*
X220572Y398866D01*
Y406198D01*
X195292Y431478D01*
Y500712D01*
X195852Y501272D01*
X198632D01*
X199192Y501832D01*
Y503272D01*
X198632Y503832D01*
X196052D01*
X195492Y504392D01*
Y505832D01*
X196052Y506392D01*
X198684D01*
X200288Y507996D01*
Y513114D01*
G01X258331Y371551D02*
X227287Y402595D01*
Y412073D01*
X204572Y434788D01*
Y447848D01*
X207769Y451045D01*
Y454596D01*
X206060Y456305D01*
Y458141D01*
X207972Y460053D01*
Y502922D01*
X208898Y503848D01*
X209776D01*
X210483Y504556D01*
Y505433D01*
X211190Y506140D01*
X212068D01*
X212775Y506848D01*
Y507725D01*
X213482Y508432D01*
Y512220D01*
X210402Y515300D01*
G01X253805Y379826D02*
X229172Y404460D01*
Y414102D01*
X217112Y426162D01*
Y432394D01*
X216240Y433266D01*
X209789D01*
X208300Y434755D01*
Y437337D01*
X209789Y438826D01*
X216240D01*
X217112Y439698D01*
Y441247D01*
X216239Y442120D01*
X209768D01*
X208112Y443776D01*
Y446960D01*
X210812Y449660D01*
Y478157D01*
X210392Y478577D01*
Y479633D01*
X210812Y480053D01*
Y481212D01*
X210212Y481812D01*
Y482852D01*
X210812Y483452D01*
Y484452D01*
X210212Y485052D01*
Y486092D01*
X210812Y486692D01*
Y487692D01*
X210212Y488292D01*
Y489332D01*
X210812Y489932D01*
Y490932D01*
X210212Y491532D01*
Y492572D01*
X210812Y493172D01*
Y494172D01*
X210212Y494772D01*
Y495812D01*
X210812Y496412D01*
Y497412D01*
X210212Y498012D01*
Y499052D01*
X210812Y499652D01*
Y500852D01*
X212569Y502609D01*
Y503487D01*
X213276Y504194D01*
X214154D01*
X214890Y504930D01*
Y505808D01*
X215597Y506515D01*
X216475D01*
X217522Y507562D01*
Y511994D01*
X216602Y512914D01*
X215502D01*
G01X257581Y370801D02*
X226227Y402155D01*
Y411633D01*
X203512Y434348D01*
Y441385D01*
X203112Y441785D01*
Y443615D01*
X203512Y444015D01*
Y448291D01*
X206709Y451488D01*
Y454156D01*
X205000Y455865D01*
Y458581D01*
X206912Y460493D01*
Y503362D01*
X212422Y508872D01*
Y511780D01*
X211502Y512700D01*
X210402D01*
G01X254978Y391041D02*
X238354Y407665D01*
Y418875D01*
X228992Y428237D01*
Y464000D01*
X224592Y468400D01*
Y474400D01*
X224092Y474900D01*
X220392D01*
X219592Y475700D01*
Y477166D01*
X220152Y477726D01*
X223332D01*
X223892Y478286D01*
Y479726D01*
X223332Y480286D01*
X220152D01*
X219592Y480846D01*
Y482286D01*
X220152Y482846D01*
X223332D01*
X223892Y483406D01*
Y484846D01*
X223332Y485406D01*
X220152D01*
X219592Y485966D01*
Y487406D01*
X220152Y487966D01*
X223332D01*
X223892Y488526D01*
Y489966D01*
X223332Y490526D01*
X220152D01*
X219592Y491086D01*
Y492526D01*
X220152Y493086D01*
X223332D01*
X223892Y493646D01*
Y495086D01*
X223332Y495646D01*
X220152D01*
X219592Y496206D01*
Y497500D01*
X221792Y499700D01*
X227692D01*
X228392Y500400D01*
Y505600D01*
X229402Y506610D01*
Y510907D01*
X226002Y514307D01*
Y516799D01*
X227360Y518157D01*
G01X256748Y392878D02*
X240874Y408752D01*
Y419919D01*
X240197Y420596D01*
Y421458D01*
X241283Y422545D01*
Y423407D01*
X239882Y424808D01*
X239020D01*
X237934Y423721D01*
X237072D01*
X235671Y425122D01*
Y425984D01*
X236757Y427071D01*
Y427933D01*
X235356Y429334D01*
X234494D01*
X233408Y428247D01*
X232546D01*
X230892Y429901D01*
Y468017D01*
X230332Y468577D01*
X227052D01*
X226492Y469137D01*
Y470577D01*
X227052Y471137D01*
X230332D01*
X230892Y471697D01*
Y473137D01*
X230332Y473697D01*
X227052D01*
X226492Y474257D01*
Y475697D01*
X227052Y476257D01*
X230332D01*
X230892Y476817D01*
Y478257D01*
X230332Y478817D01*
X227052D01*
X226492Y479377D01*
Y480817D01*
X227052Y481377D01*
X230332D01*
X230892Y481937D01*
Y483377D01*
X230332Y483937D01*
X227052D01*
X226492Y484497D01*
Y485937D01*
X227052Y486497D01*
X230332D01*
X230892Y487057D01*
Y488497D01*
X230332Y489057D01*
X227052D01*
X226492Y489617D01*
Y491057D01*
X227052Y491617D01*
X230332D01*
X230892Y492177D01*
Y493617D01*
X230332Y494177D01*
X227052D01*
X226492Y494737D01*
Y496177D01*
X227052Y496737D01*
X230332D01*
X230892Y497297D01*
Y504100D01*
X232002Y505210D01*
Y511870D01*
X230706Y513166D01*
Y513114D01*
G01X256400Y382405D02*
X233192Y405613D01*
Y416736D01*
X220792Y429136D01*
Y434100D01*
X219592Y435300D01*
Y436600D01*
X220792Y437800D01*
Y455300D01*
X219992Y456100D01*
X218392D01*
X217592Y455300D01*
Y446700D01*
X216792Y445900D01*
X215292D01*
X214492Y446700D01*
Y499299D01*
X220793Y505600D01*
X222992D01*
X223692Y506300D01*
Y508100D01*
X222592Y509200D01*
Y511067D01*
X219192Y514467D01*
Y516686D01*
X220667Y518161D01*
G01X258104Y384308D02*
X257985D01*
X235738Y406555D01*
Y417791D01*
X227092Y426437D01*
Y435577D01*
X226532Y436137D01*
X223452D01*
X222892Y436697D01*
Y438137D01*
X223452Y438697D01*
X226532D01*
X227092Y439257D01*
Y440697D01*
X226532Y441257D01*
X223452D01*
X222892Y441817D01*
Y443257D01*
X223452Y443817D01*
X226532D01*
X227092Y444377D01*
Y445817D01*
X226532Y446377D01*
X223452D01*
X222892Y446937D01*
Y448377D01*
X223452Y448937D01*
X226532D01*
X227092Y449497D01*
Y450937D01*
X226532Y451497D01*
X223452D01*
X222892Y452057D01*
Y453497D01*
X223452Y454057D01*
X226532D01*
X227092Y454617D01*
Y456057D01*
X226532Y456617D01*
X223452D01*
X222892Y457177D01*
Y458617D01*
X223452Y459177D01*
X226532D01*
X227092Y459737D01*
Y463200D01*
X222692Y467600D01*
Y472500D01*
X222192Y473000D01*
X217492D01*
X216992Y473500D01*
Y498200D01*
X220692Y501900D01*
X223892D01*
X224742Y502750D01*
Y504650D01*
X226592Y506500D01*
Y508200D01*
X225402Y509390D01*
Y511768D01*
X225359D01*
X224013Y513114D01*
G01X254556Y380578D02*
X230232Y404904D01*
Y414542D01*
X218172Y426602D01*
Y432834D01*
X216680Y434326D01*
X210229D01*
X209360Y435195D01*
Y436897D01*
X210229Y437766D01*
X216680D01*
X218172Y439258D01*
Y441690D01*
X216682Y443180D01*
X210208D01*
X209172Y444216D01*
Y446520D01*
X211872Y449220D01*
Y500409D01*
X218582Y507119D01*
Y512434D01*
X215502Y515514D01*
G01X193895Y535100D02*
X188844Y530049D01*
Y519862D01*
X190549Y518157D01*
G01X193895Y513114D02*
X193807D01*
X192121Y514800D01*
Y516492D01*
X192296Y516667D01*
Y519300D01*
X191184Y520412D01*
Y521488D01*
X192196Y522500D01*
Y523700D01*
X191184Y524712D01*
Y525788D01*
X192321Y526925D01*
Y528199D01*
X191621Y528899D01*
X190549D01*
G01X187202Y535100D02*
X182151Y530049D01*
Y519862D01*
X183856Y518157D01*
G01Y528899D02*
X184928D01*
X185628Y528199D01*
Y526925D01*
X184491Y525788D01*
Y524712D01*
X185503Y523700D01*
Y522500D01*
X184491Y521488D01*
Y520412D01*
X185603Y519300D01*
Y516667D01*
X185428Y516492D01*
Y514800D01*
X187114Y513114D01*
X187202D01*
G01X203935Y518157D02*
X202230Y519862D01*
Y531515D01*
X205415Y534700D01*
X206581D01*
G01Y513114D02*
X206493D01*
X204807Y514800D01*
Y516492D01*
X205714Y517399D01*
Y518992D01*
X204570Y520136D01*
Y521556D01*
X205414Y522400D01*
Y524100D01*
X204570Y524944D01*
Y526156D01*
X205514Y527100D01*
Y528300D01*
X204915Y528899D01*
X203935D01*
G01X227360Y518157D02*
X225655Y519862D01*
Y530049D01*
X230706Y535100D01*
G01Y513114D02*
X230618D01*
X228932Y514800D01*
Y516492D01*
X229107Y516667D01*
Y519300D01*
X227995Y520412D01*
Y521488D01*
X229007Y522500D01*
Y523700D01*
X227995Y524712D01*
Y525788D01*
X229132Y526925D01*
Y528199D01*
X228432Y528899D01*
X227360D01*
G01X197242Y518157D02*
Y518849D01*
X195537Y520554D01*
Y529835D01*
X196159Y530457D01*
Y531645D01*
X199214Y534700D01*
X200202D01*
G01X200288Y513114D02*
X200200D01*
X198514Y514800D01*
Y517000D01*
X199014Y517500D01*
Y519399D01*
X197877Y520536D01*
Y521864D01*
X198814Y522801D01*
Y524199D01*
X197877Y525136D01*
Y526364D01*
X198914Y527401D01*
Y528299D01*
X198314Y528899D01*
X197242D01*
G01X220667Y518161D02*
X218962Y519866D01*
Y530049D01*
X224013Y535100D01*
G01Y513114D02*
X223925D01*
X222239Y514800D01*
Y516492D01*
X222414Y516667D01*
Y519300D01*
X221302Y520412D01*
Y521488D01*
X222314Y522500D01*
Y523700D01*
X221302Y524712D01*
Y525788D01*
X222439Y526925D01*
Y528199D01*
X221739Y528899D01*
X220667D01*
G01X173617Y531750D02*
X175322Y530045D01*
Y528139D01*
X174583Y527400D01*
X173303D01*
X172663Y526760D01*
Y525340D01*
X173213Y524790D01*
X173793D01*
X174403Y524180D01*
Y522790D01*
X173793Y522180D01*
X173183D01*
X172663Y521660D01*
Y520290D01*
X173253Y519700D01*
X174203D01*
X175303Y518600D01*
Y517012D01*
X173591Y515300D01*
G01X210402D02*
X212114Y517012D01*
Y518600D01*
X211014Y519700D01*
X210064D01*
X209474Y520290D01*
Y521660D01*
X209994Y522180D01*
X210697D01*
X211307Y522790D01*
Y524180D01*
X210697Y524790D01*
X210024D01*
X209474Y525340D01*
Y526760D01*
X210114Y527400D01*
X211114D01*
X212133Y528419D01*
Y530045D01*
X210428Y531750D01*
G01X178691Y534149D02*
X176986Y532444D01*
Y527500D01*
X176156Y526670D01*
Y520130D01*
X176986Y519300D01*
Y514331D01*
X178403Y512914D01*
X178691D01*
G01X215502D02*
X215214D01*
X213797Y514331D01*
Y519300D01*
X212967Y520130D01*
Y526670D01*
X213797Y527500D01*
Y532444D01*
X215502Y534149D01*
G01X173591Y534399D02*
X171603Y532411D01*
Y514400D01*
X173303Y512700D01*
X173591D01*
G01X210402D02*
X210114D01*
X208414Y514400D01*
Y532411D01*
X210402Y534399D01*
G01X178691Y531540D02*
X180503Y529728D01*
Y528000D01*
X179503Y527000D01*
X177987D01*
X177216Y526229D01*
Y525338D01*
X177756Y524798D01*
X177993D01*
X178703Y524088D01*
Y523000D01*
X178003Y522300D01*
X177668D01*
X177216Y521848D01*
Y520571D01*
X177887Y519900D01*
X179403D01*
X180403Y518900D01*
Y517226D01*
X178691Y515514D01*
G01X215502D02*
X217214Y517226D01*
Y518900D01*
X216214Y519900D01*
X214698D01*
X214027Y520571D01*
Y521848D01*
X214479Y522300D01*
X214814D01*
X215514Y523000D01*
Y524088D01*
X214804Y524798D01*
X214567D01*
X214027Y525338D01*
Y526229D01*
X214798Y527000D01*
X216314D01*
X217314Y528000D01*
Y529728D01*
X215502Y531540D01*
G01X240746Y92757D02*
Y101718D01*
X242566Y103538D01*
Y105074D01*
X241466Y106174D01*
Y110474D01*
X242842Y111850D01*
Y115050D01*
X244066Y116274D01*
Y122917D01*
X243266Y123717D01*
X241684D01*
X240884Y124517D01*
Y126117D01*
X241684Y126917D01*
X243266D01*
X244066Y127717D01*
Y129317D01*
X243266Y130117D01*
X241684D01*
X240884Y130917D01*
Y132517D01*
X241684Y133317D01*
X243266D01*
X244066Y134117D01*
Y135717D01*
X243266Y136517D01*
X241684D01*
X240884Y137317D01*
Y138917D01*
X241684Y139717D01*
X242332D01*
X242892Y140277D01*
Y142309D01*
X240884Y144317D01*
Y164293D01*
X247291Y170700D01*
X248658D01*
X275061Y197103D01*
G01X243392Y71500D02*
X242525Y72367D01*
Y74668D01*
X240892Y76301D01*
Y77600D01*
X242242Y78950D01*
Y79850D01*
X240992Y81100D01*
Y82299D01*
X242525Y83832D01*
Y85800D01*
X239625Y88700D01*
Y91636D01*
X240746Y92757D01*
G01X243392Y87714D02*
X241466Y89640D01*
Y90974D01*
X243166Y92674D01*
Y100674D01*
X245316Y102824D01*
Y114024D01*
X246566Y115274D01*
Y142171D01*
X243384Y145353D01*
Y162758D01*
X248726Y168100D01*
X249665D01*
X278366Y196801D01*
G01X240746Y65699D02*
Y67821D01*
X242625Y69700D01*
X244025D01*
X245481Y71156D01*
Y72500D01*
X244865Y73116D01*
Y86241D01*
X243392Y87714D01*
G01X264171Y92757D02*
Y101737D01*
X266266Y103832D01*
Y105274D01*
X265566Y105974D01*
Y110874D01*
X266166Y111474D01*
Y114156D01*
X263884Y116438D01*
Y133556D01*
X264984Y134656D01*
X266832D01*
X267392Y135216D01*
Y137535D01*
X266832Y138095D01*
X264952D01*
X264342Y138705D01*
Y140095D01*
X264952Y140705D01*
X269982D01*
X270592Y141315D01*
Y142705D01*
X269982Y143315D01*
X264952D01*
X264342Y143925D01*
Y145315D01*
X264952Y145925D01*
X269982D01*
X270592Y146535D01*
Y166692D01*
X293841Y189941D01*
G01X267517Y71900D02*
X265950Y73467D01*
Y74668D01*
X264592Y76026D01*
Y77399D01*
X265792Y78599D01*
Y79725D01*
X264592Y80925D01*
Y82500D01*
X266392Y84300D01*
Y85358D01*
X263050Y88700D01*
Y91636D01*
X264171Y92757D01*
G01X267517Y87714D02*
X265684Y89547D01*
Y91392D01*
X268766Y94474D01*
Y95365D01*
X266584Y97547D01*
Y100555D01*
X268766Y102737D01*
Y105524D01*
X269466Y106224D01*
Y110924D01*
X268984Y111406D01*
Y114874D01*
X266384Y117474D01*
Y125090D01*
X266994Y125700D01*
X271232D01*
X271792Y126260D01*
Y128166D01*
X271232Y128726D01*
X267602D01*
X266992Y129336D01*
Y130726D01*
X267602Y131336D01*
X272174D01*
X272784Y131946D01*
Y165277D01*
X295748Y188241D01*
G01X264171Y65699D02*
X265418Y66946D01*
Y68200D01*
X266718Y69500D01*
X267718D01*
X269518Y71300D01*
Y72700D01*
X268906Y73312D01*
Y86325D01*
X267517Y87714D01*
G01X234053Y92757D02*
X236066Y94770D01*
Y96562D01*
X235084Y97544D01*
Y99762D01*
X236066Y100744D01*
Y104974D01*
X235066Y105974D01*
Y110674D01*
X235866Y111474D01*
Y115767D01*
X235256Y116377D01*
X234152D01*
X233542Y116987D01*
Y118377D01*
X234152Y118987D01*
X235256D01*
X235866Y119597D01*
Y120987D01*
X235256Y121597D01*
X234152D01*
X233542Y122207D01*
Y123597D01*
X234152Y124207D01*
X235256D01*
X235866Y124817D01*
Y126207D01*
X235256Y126817D01*
X234652D01*
X234092Y127377D01*
Y128867D01*
X234652Y129427D01*
X235256D01*
X235866Y130037D01*
Y169123D01*
X244543Y177800D01*
X248544D01*
X270723Y199979D01*
G01X237013Y71500D02*
X235925Y72588D01*
Y74468D01*
X234492Y75901D01*
Y77100D01*
X235992Y78600D01*
Y79800D01*
X234542Y81250D01*
Y82649D01*
X235925Y84032D01*
Y85901D01*
X233125Y88701D01*
Y91829D01*
X234053Y92757D01*
G01X237099Y87714D02*
X236927D01*
X235066Y89575D01*
Y91074D01*
X238566Y94574D01*
Y106174D01*
X238966Y106574D01*
Y111074D01*
X238384Y111656D01*
Y113931D01*
X239184Y114731D01*
X239784D01*
X240292Y115239D01*
Y117223D01*
X239584Y117931D01*
X239184D01*
X238384Y118731D01*
Y119656D01*
X239684Y120956D01*
Y122181D01*
X238384Y123481D01*
Y168105D01*
X244579Y174300D01*
X248651D01*
X271755Y197404D01*
G01X234053Y65699D02*
Y67253D01*
X236300Y69500D01*
X237524D01*
X239100Y71076D01*
Y72700D01*
X238325Y73475D01*
Y86488D01*
X237099Y87714D01*
G01X257478Y92757D02*
X256550Y91829D01*
Y88701D01*
X259592Y85659D01*
Y84274D01*
X257917Y82599D01*
Y81476D01*
X259417Y79976D01*
Y78624D01*
X257917Y77124D01*
Y75901D01*
X259350Y74468D01*
Y73374D01*
X260824Y71900D01*
G01X290537Y193852D02*
X266542Y169857D01*
Y165352D01*
X265932Y164742D01*
X262302D01*
X261692Y164132D01*
Y162742D01*
X262302Y162132D01*
X265932D01*
X266542Y161522D01*
Y160132D01*
X265932Y159522D01*
X260202D01*
X259592Y158912D01*
Y157522D01*
X260202Y156912D01*
X262532D01*
X263092Y156352D01*
Y154310D01*
X262532Y153750D01*
X258676D01*
X258066Y153140D01*
Y136126D01*
X258884Y135308D01*
Y113838D01*
X259566Y113156D01*
Y111674D01*
X258666Y110774D01*
Y105974D01*
X259466Y105174D01*
Y103438D01*
X258434Y102406D01*
Y95242D01*
X257478Y94286D01*
Y92757D01*
G01X260824Y87714D02*
X259016Y89522D01*
Y91424D01*
X261216Y93624D01*
Y101588D01*
X261966Y102338D01*
Y105474D01*
X262732Y106240D01*
Y110808D01*
X262166Y111374D01*
Y114456D01*
X261384Y115238D01*
Y136408D01*
X260566Y137226D01*
Y147440D01*
X261126Y148000D01*
X263692D01*
X268692Y153000D01*
Y168626D01*
X292064Y191998D01*
X292291D01*
G01X257478Y65699D02*
X258725Y66946D01*
Y68200D01*
X260025Y69500D01*
X261025D01*
X262825Y71300D01*
Y72700D01*
X262213Y73312D01*
Y86325D01*
X260824Y87714D01*
G01X247213Y89900D02*
X248939Y91626D01*
Y93452D01*
X247891Y94500D01*
X247139D01*
X246419Y95220D01*
Y96888D01*
X250246Y100715D01*
Y115630D01*
X250866Y116250D01*
Y117800D01*
X250246Y118420D01*
Y119180D01*
X250866Y119800D01*
Y120800D01*
X250246Y121420D01*
Y122180D01*
X250866Y122800D01*
Y123800D01*
X250246Y124420D01*
Y125180D01*
X250866Y125800D01*
Y126800D01*
X250246Y127420D01*
Y132622D01*
X250564Y132940D01*
Y144319D01*
X249175Y145708D01*
X248236D01*
X247364Y146580D01*
Y149076D01*
X248236Y149948D01*
X250075D01*
X251564Y151437D01*
Y154819D01*
X250075Y156308D01*
X248236D01*
X247364Y157180D01*
Y159676D01*
X248236Y160548D01*
X250075D01*
X251564Y162037D01*
Y164672D01*
X262270Y175378D01*
X262820D01*
X263614Y176172D01*
Y176722D01*
X264370Y177478D01*
X264820D01*
X265714Y178372D01*
Y178822D01*
X266390Y179498D01*
X267142D01*
X267734Y180090D01*
Y180842D01*
X268370Y181478D01*
X269122D01*
X269714Y182070D01*
Y182822D01*
X270385Y183493D01*
X271137D01*
X271729Y184085D01*
Y184837D01*
X272365Y185473D01*
X273117D01*
X273709Y186065D01*
Y186817D01*
X274345Y187453D01*
X275097D01*
X275689Y188045D01*
Y188797D01*
X276445Y189553D01*
X277197D01*
X277789Y190145D01*
Y190897D01*
X278868Y191976D01*
X279620D01*
X280212Y192568D01*
Y193320D01*
X280848Y193956D01*
X280868D01*
G01X247239Y68550D02*
X248009Y69320D01*
X248991D01*
X250319Y70648D01*
Y86794D01*
X247213Y89900D01*
G01X284024D02*
X285750Y91626D01*
Y94000D01*
X285250Y94500D01*
X283730D01*
X283230Y95000D01*
Y97588D01*
X287046Y101404D01*
Y102236D01*
X287666Y102856D01*
Y103856D01*
X287046Y104476D01*
Y113483D01*
X287964Y114401D01*
Y115401D01*
X288464Y115901D01*
Y116901D01*
X287964Y117401D01*
Y118401D01*
X288464Y118901D01*
Y119901D01*
X287964Y120401D01*
Y121401D01*
X288464Y121901D01*
Y122901D01*
X287964Y123401D01*
Y128404D01*
X288364Y128804D01*
Y130634D01*
X287964Y131034D01*
Y132864D01*
X288876Y133776D01*
X290736D01*
X292164Y135204D01*
Y138429D01*
X290675Y139918D01*
X288836D01*
X287692Y141062D01*
Y143014D01*
X288836Y144158D01*
X290675D01*
X292164Y145647D01*
Y149029D01*
X290675Y150518D01*
X290006D01*
X289352Y151172D01*
Y153834D01*
X289752Y154234D01*
Y156064D01*
X289352Y156464D01*
Y159494D01*
X293514Y163656D01*
X294079D01*
X295374Y164951D01*
Y165516D01*
X296668Y166810D01*
X297233D01*
X298528Y168105D01*
Y168670D01*
X299822Y169964D01*
X300387D01*
X301682Y171259D01*
Y171824D01*
X302976Y173118D01*
X303541D01*
X304836Y174413D01*
Y174978D01*
X306130Y176272D01*
X306695D01*
X307990Y177567D01*
Y178132D01*
X309284Y179426D01*
X309849D01*
X311144Y180721D01*
Y181286D01*
X312438Y182580D01*
X313003D01*
X314298Y183875D01*
Y184440D01*
X315592Y185734D01*
Y188900D01*
G01X284050Y68550D02*
X284820Y69320D01*
X285802D01*
X287130Y70648D01*
Y86794D01*
X284024Y89900D01*
G01X252313Y87514D02*
Y87515D01*
X253411D01*
X254445Y86481D01*
Y83706D01*
X253739Y83000D01*
X253225D01*
X252525Y82300D01*
Y81300D01*
X253225Y80600D01*
X253725D01*
X254445Y79880D01*
Y78507D01*
X253638Y77700D01*
X252940D01*
X252339Y77099D01*
Y75901D01*
X252940Y75300D01*
X253738D01*
X254445Y74593D01*
Y71972D01*
X253422Y70949D01*
X252313D01*
G01X285815Y194683D02*
Y193297D01*
X254386Y161868D01*
Y100158D01*
X251059Y96831D01*
Y94567D01*
X250589Y94097D01*
Y89238D01*
X252313Y87514D01*
G01X289124D02*
Y87515D01*
X290222D01*
X291256Y86481D01*
Y83706D01*
X290550Y83000D01*
X290036D01*
X289336Y82300D01*
Y81300D01*
X290036Y80600D01*
X290536D01*
X291256Y79880D01*
Y78507D01*
X290449Y77700D01*
X289751D01*
X289150Y77099D01*
Y75901D01*
X289751Y75300D01*
X290549D01*
X291256Y74593D01*
Y71972D01*
X290233Y70949D01*
X289124D01*
G01X320132Y192943D02*
Y190774D01*
X317491Y184399D01*
X294904Y161812D01*
Y133908D01*
X291504Y130508D01*
Y113747D01*
X291144Y113387D01*
Y101085D01*
X288435Y98376D01*
Y98373D01*
X287370Y97308D01*
Y89268D01*
X289124Y87514D01*
G01X247213Y87300D02*
X248312D01*
X249259Y86353D01*
Y83820D01*
X248289Y82850D01*
X247941D01*
X247325Y82234D01*
Y80902D01*
X247827Y80400D01*
X248539D01*
X249259Y79680D01*
Y78720D01*
X248439Y77900D01*
X247939D01*
X247339Y77300D01*
Y76300D01*
X249259Y74380D01*
Y71091D01*
X248548Y70380D01*
X248032D01*
X247213Y71199D01*
G01X279992Y194600D02*
X250504Y165112D01*
Y162477D01*
X249635Y161608D01*
X247793D01*
X246304Y160119D01*
Y156737D01*
X247793Y155248D01*
X249632D01*
X250504Y154376D01*
Y151880D01*
X249632Y151008D01*
X247793D01*
X246304Y149519D01*
Y146137D01*
X247793Y144648D01*
X248732D01*
X249504Y143876D01*
Y133383D01*
X249186Y133065D01*
Y101158D01*
X245359Y97331D01*
Y89154D01*
X247213Y87300D01*
G01X284024D02*
X285123D01*
X286070Y86353D01*
Y83820D01*
X285100Y82850D01*
X284752D01*
X284136Y82234D01*
Y80902D01*
X284638Y80400D01*
X285350D01*
X286070Y79680D01*
Y78720D01*
X285250Y77900D01*
X284750D01*
X284150Y77300D01*
Y76300D01*
X286070Y74380D01*
Y71091D01*
X285359Y70380D01*
X284843D01*
X284024Y71199D01*
G01X314532Y188900D02*
Y186174D01*
X288292Y159934D01*
Y150732D01*
X289566Y149458D01*
X290232D01*
X291104Y148586D01*
Y146087D01*
X290235Y145218D01*
X288396D01*
X286632Y143454D01*
Y140622D01*
X288396Y138858D01*
X290232D01*
X291104Y137986D01*
Y135647D01*
X290293Y134836D01*
X288433D01*
X286904Y133307D01*
Y114844D01*
X285986Y113926D01*
Y101847D01*
X282170Y98031D01*
Y89154D01*
X284024Y87300D01*
G01X252313Y90114D02*
X254139Y91940D01*
Y93500D01*
X252119Y95520D01*
Y96388D01*
X253093Y97362D01*
X253969D01*
X254677Y98070D01*
Y98946D01*
X255446Y99715D01*
Y113280D01*
X256066Y113900D01*
Y114900D01*
X255446Y115520D01*
Y116280D01*
X256066Y116900D01*
Y117900D01*
X255446Y118520D01*
Y119280D01*
X256066Y119900D01*
Y120900D01*
X255446Y121520D01*
Y122280D01*
X256066Y122900D01*
Y123900D01*
X255446Y124520D01*
Y125280D01*
X256066Y125900D01*
Y126900D01*
X255446Y127520D01*
Y161428D01*
X286875Y192857D01*
Y194683D01*
G01X252313Y68340D02*
X255505Y71532D01*
Y86922D01*
X252313Y90114D01*
G01X289124D02*
X290950Y91940D01*
Y93942D01*
X290292Y94600D01*
X289192D01*
X288430Y95362D01*
Y96868D01*
X289185Y97623D01*
X290061D01*
X290769Y98331D01*
Y99207D01*
X292204Y100642D01*
Y103480D01*
X292824Y104100D01*
Y105100D01*
X292204Y105720D01*
Y112944D01*
X292564Y113304D01*
Y130065D01*
X295964Y133465D01*
Y161372D01*
X303546Y168954D01*
X304111D01*
X305406Y170249D01*
Y170814D01*
X306700Y172108D01*
X307265D01*
X308560Y173403D01*
Y173968D01*
X309854Y175262D01*
X310419D01*
X311714Y176557D01*
Y177122D01*
X318390Y183798D01*
X321192Y190563D01*
Y192965D01*
G01X289124Y68340D02*
X292316Y71532D01*
Y86922D01*
X289124Y90114D01*
G01X277557Y92757D02*
X276436Y91636D01*
Y88700D01*
X279336Y85800D01*
Y72367D01*
X280203Y71500D01*
G01X309592Y194265D02*
Y186684D01*
X305173Y182265D01*
X304311D01*
X303415Y183161D01*
X302553D01*
X301152Y181760D01*
Y180898D01*
X302048Y180002D01*
Y179140D01*
X300647Y177739D01*
X299785D01*
X298889Y178635D01*
X298027D01*
X296626Y177234D01*
Y176372D01*
X297522Y175476D01*
Y174614D01*
X296121Y173213D01*
X295259D01*
X294363Y174109D01*
X293501D01*
X292100Y172708D01*
Y171846D01*
X292996Y170950D01*
Y170088D01*
X291595Y168687D01*
X290733D01*
X289837Y169583D01*
X288975D01*
X287574Y168182D01*
Y167320D01*
X288470Y166424D01*
Y165562D01*
X287069Y164161D01*
X286207D01*
X285311Y165057D01*
X284449D01*
X283048Y163656D01*
Y162794D01*
X283944Y161898D01*
Y161036D01*
X280192Y157284D01*
Y115599D01*
X279466Y114873D01*
Y111574D01*
X278266Y110374D01*
Y106274D01*
X279684Y104856D01*
Y104014D01*
X277866Y102196D01*
Y93066D01*
X277557Y92757D01*
G01X280203Y87714D02*
X278166Y89751D01*
Y90874D01*
X279966Y92674D01*
Y101338D01*
X282116Y103488D01*
Y113823D01*
X284284Y115991D01*
Y158710D01*
X311868Y186294D01*
Y193991D01*
G01X277557Y65699D02*
Y67821D01*
X279436Y69700D01*
X280836D01*
X282292Y71156D01*
Y72500D01*
X281676Y73116D01*
Y86241D01*
X280203Y87714D01*
G01X273824Y71500D02*
X272736Y72588D01*
Y85901D01*
X269936Y88701D01*
Y91829D01*
X270864Y92757D01*
G01D02*
X273584Y95477D01*
Y96764D01*
X272684Y97664D01*
X271084D01*
X270384Y98364D01*
Y99964D01*
X271184Y100764D01*
X272784D01*
X273584Y101564D01*
Y104856D01*
X271866Y106574D01*
Y110774D01*
X272984Y111892D01*
Y115593D01*
X275668Y118277D01*
Y118811D01*
X275086Y119393D01*
X271052D01*
X270492Y119953D01*
Y122033D01*
X271052Y122593D01*
X275406D01*
X275966Y123153D01*
Y162192D01*
X304218Y190444D01*
Y193611D01*
G01X273910Y87714D02*
X273726D01*
X271874Y89566D01*
Y91032D01*
X275466Y94624D01*
Y105974D01*
X275766Y106274D01*
Y110974D01*
X275566Y111174D01*
Y114574D01*
X278192Y117200D01*
Y161751D01*
X306768Y190327D01*
Y193511D01*
G01X270864Y65699D02*
Y67253D01*
X273111Y69500D01*
X274335D01*
X275911Y71076D01*
Y72700D01*
X275136Y73475D01*
Y86488D01*
X273910Y87714D01*
G01X297635Y71900D02*
X296036Y73499D01*
Y86750D01*
X293036Y89750D01*
Y91504D01*
X294289Y92757D01*
G01X259808Y406667D02*
X252942Y413533D01*
Y426759D01*
X240931Y438770D01*
Y458239D01*
X243692Y461000D01*
Y488042D01*
X241292Y490442D01*
Y505600D01*
X242292Y506600D01*
Y511228D01*
X239977Y513543D01*
Y517388D01*
X240746Y518157D01*
G01X261660Y408422D02*
X255498Y414584D01*
Y427818D01*
X246392Y436924D01*
Y439985D01*
X245782Y440595D01*
X244302D01*
X243692Y441205D01*
Y443185D01*
X244302Y443795D01*
X245782D01*
X246392Y444405D01*
Y446385D01*
X245782Y446995D01*
X243602D01*
X242992Y447605D01*
Y449585D01*
X243602Y450195D01*
X245782D01*
X246392Y450805D01*
Y452785D01*
X245782Y453395D01*
X243602D01*
X242992Y454005D01*
Y455985D01*
X243602Y456595D01*
X245782D01*
X246392Y457205D01*
Y487900D01*
X245366Y488926D01*
Y511140D01*
X243392Y513114D01*
G01X279063Y412356D02*
X271592Y419827D01*
Y454700D01*
X270992Y455300D01*
X269792D01*
X269192Y454700D01*
Y451600D01*
X268492Y450900D01*
X266892D01*
X266292Y451500D01*
Y488000D01*
X265892Y488400D01*
Y494999D01*
X266213Y495320D01*
Y510907D01*
X262813Y514307D01*
Y516799D01*
X264171Y518157D01*
G01X280841Y414135D02*
X274192Y420784D01*
Y435580D01*
X274752Y436140D01*
X276132D01*
X276692Y436700D01*
Y438140D01*
X276132Y438700D01*
X274752D01*
X274192Y439260D01*
Y440700D01*
X274752Y441260D01*
X276132D01*
X276692Y441820D01*
Y443260D01*
X276132Y443820D01*
X274752D01*
X274192Y444380D01*
Y445820D01*
X274752Y446380D01*
X276132D01*
X276692Y446940D01*
Y448380D01*
X276132Y448940D01*
X274752D01*
X274192Y449500D01*
Y459300D01*
X273492Y460000D01*
X272092D01*
X271492Y459400D01*
Y457800D01*
X270992Y457300D01*
X269313D01*
X268813Y457800D01*
Y482621D01*
X269392Y483200D01*
Y497173D01*
X268813Y497752D01*
Y511870D01*
X267517Y513166D01*
Y513114D01*
G01X255750Y403509D02*
X247942Y411317D01*
Y424687D01*
X236841Y435788D01*
Y460749D01*
X238592Y462500D01*
Y477800D01*
X235992Y480400D01*
Y488800D01*
X235166Y489626D01*
Y502075D01*
X235892Y502801D01*
Y510928D01*
X232592Y514228D01*
Y517356D01*
X233393Y518157D01*
X234053D01*
G01X257553Y405313D02*
X250442Y412424D01*
Y425723D01*
X238841Y437324D01*
Y459550D01*
X241592Y462301D01*
Y480739D01*
X240982Y481349D01*
X238902D01*
X238292Y481959D01*
Y483939D01*
X238902Y484549D01*
X240982D01*
X241592Y485159D01*
Y486200D01*
X238692Y489100D01*
Y494100D01*
X237592Y495200D01*
Y501596D01*
X238792Y502796D01*
Y504796D01*
X237592Y505996D01*
Y507996D01*
X238792Y509196D01*
Y512301D01*
X237979Y513114D01*
X237099D01*
G01X274044Y410161D02*
X266392Y417813D01*
Y431545D01*
X260192Y437745D01*
Y466700D01*
X257592Y469300D01*
Y478901D01*
X258392Y479701D01*
X259532D01*
X260192Y480361D01*
Y481761D01*
X259692Y482261D01*
X258152D01*
X257592Y482821D01*
Y484261D01*
X258152Y484821D01*
X259532D01*
X260192Y485481D01*
Y486881D01*
X259692Y487381D01*
X258152D01*
X257592Y487941D01*
Y492999D01*
X259713Y495120D01*
Y510757D01*
X256813Y513657D01*
Y517492D01*
X257478Y518157D01*
G01X275722Y412090D02*
X268492Y419320D01*
Y432400D01*
X262692Y438200D01*
Y440541D01*
X263252Y441101D01*
X267132D01*
X267692Y441661D01*
Y443101D01*
X267132Y443661D01*
X263252D01*
X262692Y444221D01*
Y445661D01*
X263252Y446221D01*
X268732D01*
X269292Y446781D01*
Y448221D01*
X268732Y448781D01*
X263252D01*
X262692Y449341D01*
Y494301D01*
X262213Y494780D01*
Y502788D01*
X263013Y503588D01*
X263292D01*
X264092Y504388D01*
Y505988D01*
X263292Y506788D01*
X263013D01*
X262213Y507588D01*
Y511768D01*
X262170D01*
X260824Y513114D01*
G01X247213Y515300D02*
X250208Y512305D01*
Y438453D01*
X259111Y429550D01*
Y416148D01*
X261800Y413459D01*
X269619Y405641D01*
G01X266596Y412416D02*
X262642Y416370D01*
Y430019D01*
X254174Y438487D01*
Y441851D01*
X256512Y444189D01*
Y445252D01*
X253604Y448160D01*
Y449745D01*
X256412Y452553D01*
Y454249D01*
X255540Y455121D01*
X253727D01*
X252424Y456424D01*
Y459006D01*
X254099Y460681D01*
X255719D01*
X256512Y461474D01*
Y462593D01*
X255892Y463213D01*
Y464213D01*
X256512Y464833D01*
Y465945D01*
X254633Y467824D01*
Y469246D01*
X254013Y469866D01*
Y470866D01*
X254633Y471486D01*
Y472486D01*
X254013Y473106D01*
Y474106D01*
X254633Y474726D01*
Y475726D01*
X254013Y476346D01*
Y477346D01*
X254633Y477966D01*
Y478966D01*
X254013Y479586D01*
Y480586D01*
X254633Y481206D01*
Y482206D01*
X254013Y482826D01*
Y483826D01*
X254633Y484446D01*
Y485446D01*
X254013Y486066D01*
Y487066D01*
X254633Y487686D01*
Y488686D01*
X254013Y489306D01*
Y490306D01*
X254633Y490926D01*
Y491939D01*
X254026Y492546D01*
Y493546D01*
X254633Y494153D01*
Y495312D01*
X254027Y495918D01*
Y496918D01*
X254633Y497524D01*
Y498406D01*
X254013Y499026D01*
Y500026D01*
X254633Y500646D01*
Y501646D01*
X254013Y502266D01*
Y503266D01*
X254633Y503886D01*
Y504886D01*
X254013Y505506D01*
Y506506D01*
X254633Y507126D01*
Y508126D01*
X254013Y508746D01*
Y509746D01*
X254633Y510366D01*
Y511694D01*
X253413Y512914D01*
X252313D01*
G01X268869Y404890D02*
X258051Y415708D01*
Y429110D01*
X249148Y438013D01*
Y503652D01*
X248621Y504179D01*
Y505179D01*
X249148Y505706D01*
Y506799D01*
X248528Y507419D01*
Y508419D01*
X249148Y509039D01*
Y511744D01*
X248192Y512700D01*
X247213D01*
G01X267347Y413165D02*
X263702Y416810D01*
Y430459D01*
X255234Y438927D01*
Y441411D01*
X257572Y443749D01*
Y445692D01*
X254664Y448600D01*
Y449305D01*
X257472Y452113D01*
Y454692D01*
X255983Y456181D01*
X254167D01*
X253484Y456864D01*
Y458566D01*
X254539Y459621D01*
X256159D01*
X257572Y461034D01*
Y466385D01*
X255693Y468264D01*
Y512134D01*
X252313Y515514D01*
G01X318263Y404437D02*
Y410996D01*
X292312Y436947D01*
Y479709D01*
X286044Y485977D01*
Y503144D01*
X285374Y503814D01*
Y504814D01*
X286044Y505484D01*
Y506484D01*
X285374Y507154D01*
Y508154D01*
X286044Y508824D01*
Y511808D01*
X285152Y512700D01*
X284024D01*
G01X313099Y401938D02*
Y408803D01*
X286592Y435310D01*
Y466600D01*
X280708Y472484D01*
Y486784D01*
X278366Y489126D01*
Y493874D01*
X279474Y494982D01*
Y502598D01*
X278674Y503398D01*
X278392D01*
X277592Y504198D01*
Y505798D01*
X278392Y506598D01*
X278674D01*
X279474Y507398D01*
Y510857D01*
X276124Y514207D01*
Y516724D01*
X277557Y518157D01*
G01X315668Y401814D02*
Y409841D01*
X289192Y436317D01*
Y477195D01*
X288492Y477895D01*
X286992D01*
X286192Y477095D01*
Y473359D01*
X285212Y472379D01*
X283612D01*
X282792Y473199D01*
Y480100D01*
X283412Y480720D01*
X285282D01*
X285892Y481330D01*
Y482500D01*
X285062Y483330D01*
X283362D01*
X282792Y483900D01*
Y488400D01*
X282124Y489068D01*
Y511193D01*
X280203Y513114D01*
G01X307971Y399557D02*
Y406859D01*
X281492Y433338D01*
Y465400D01*
X279092Y467800D01*
X277292D01*
X276592Y467100D01*
Y465700D01*
X275992Y465100D01*
X274592D01*
X273992Y465700D01*
Y488700D01*
X271966Y490726D01*
Y494374D01*
X272792Y495200D01*
Y502400D01*
X271692Y503500D01*
Y507900D01*
X272774Y508982D01*
Y510857D01*
X269624Y514007D01*
Y516917D01*
X270864Y518157D01*
G01X310549Y400397D02*
Y407817D01*
X284092Y434274D01*
Y465700D01*
X275988Y473804D01*
Y474614D01*
X276524Y475150D01*
X278213D01*
X278770Y475707D01*
Y477097D01*
X278107Y477760D01*
X276498D01*
X275915Y478343D01*
Y479733D01*
X276552Y480370D01*
X278133D01*
X278743Y480980D01*
Y482370D01*
X278133Y482980D01*
X277092D01*
X276492Y483580D01*
Y494500D01*
X275792Y495200D01*
Y502300D01*
X274982Y503110D01*
X274392D01*
X273592Y503910D01*
Y505510D01*
X274392Y506310D01*
X275002D01*
X275424Y506732D01*
Y511600D01*
X273910Y513114D01*
G01X240746Y518157D02*
X239041Y519862D01*
Y531515D01*
X242226Y534700D01*
X243392D01*
G01Y513114D02*
X243304D01*
X241618Y514800D01*
Y516492D01*
X242525Y517399D01*
Y518992D01*
X241381Y520136D01*
Y521556D01*
X242225Y522400D01*
Y524100D01*
X241381Y524944D01*
Y526156D01*
X242325Y527100D01*
Y528300D01*
X241726Y528899D01*
X240746D01*
G01X264171Y518157D02*
X262466Y519862D01*
Y530049D01*
X267517Y535100D01*
G01Y513114D02*
X267429D01*
X265743Y514800D01*
Y516492D01*
X265918Y516667D01*
Y519300D01*
X264806Y520412D01*
Y521488D01*
X265818Y522500D01*
Y523700D01*
X264806Y524712D01*
Y525788D01*
X265943Y526925D01*
Y528199D01*
X265243Y528899D01*
X264171D01*
G01X234053Y518157D02*
X232348Y519862D01*
Y529835D01*
X232970Y530457D01*
Y531645D01*
X236025Y534700D01*
X237013D01*
G01X237099Y513114D02*
X237011D01*
X235325Y514800D01*
Y517000D01*
X235825Y517500D01*
Y519399D01*
X234688Y520536D01*
Y521864D01*
X235625Y522801D01*
Y524199D01*
X234688Y525136D01*
Y526364D01*
X235725Y527401D01*
Y528299D01*
X235125Y528899D01*
X234053D01*
G01X257478Y518157D02*
X255773Y519862D01*
Y530049D01*
X260824Y535100D01*
G01Y513114D02*
X260736D01*
X259050Y514800D01*
Y516492D01*
X259225Y516667D01*
Y519300D01*
X258113Y520412D01*
Y521488D01*
X259125Y522500D01*
Y523700D01*
X258113Y524712D01*
Y525788D01*
X259250Y526925D01*
Y528199D01*
X258550Y528899D01*
X257478D01*
G01X247239Y531750D02*
X248944Y530045D01*
Y528139D01*
X248205Y527400D01*
X246925D01*
X246285Y526760D01*
Y525340D01*
X246835Y524790D01*
X247415D01*
X248025Y524180D01*
Y522790D01*
X247415Y522180D01*
X246805D01*
X246285Y521660D01*
Y520290D01*
X246875Y519700D01*
X247825D01*
X248925Y518600D01*
Y517012D01*
X247213Y515300D01*
G01X284050Y531750D02*
X285755Y530045D01*
Y528139D01*
X285016Y527400D01*
X283736D01*
X283096Y526760D01*
Y525340D01*
X283646Y524790D01*
X284226D01*
X284836Y524180D01*
Y522790D01*
X284226Y522180D01*
X283616D01*
X283096Y521660D01*
Y520290D01*
X283686Y519700D01*
X284636D01*
X285736Y518600D01*
Y517012D01*
X284024Y515300D01*
G01D02*
X284053D01*
X287104Y512249D01*
Y486420D01*
X293372Y480152D01*
Y437390D01*
X319323Y411439D01*
Y404437D01*
G01X252313Y512914D02*
X252025D01*
X250608Y514331D01*
Y519300D01*
X249778Y520130D01*
Y526670D01*
X250608Y527500D01*
Y532444D01*
X252313Y534149D01*
G01X322226Y407587D02*
Y412435D01*
X303242Y431419D01*
X303240D01*
Y434864D01*
X302371Y435733D01*
X299752D01*
X298263Y437222D01*
Y439801D01*
X299755Y441293D01*
X301540D01*
X302412Y442165D01*
Y443878D01*
X301570Y444720D01*
X298204D01*
X296924Y446000D01*
Y468237D01*
X296304Y468857D01*
Y469857D01*
X296924Y470477D01*
Y471477D01*
X296304Y472097D01*
Y473097D01*
X296924Y473717D01*
Y474717D01*
X296304Y475337D01*
Y476337D01*
X296924Y476957D01*
Y477957D01*
X296304Y478577D01*
Y479577D01*
X296924Y480197D01*
Y481197D01*
X296028Y482093D01*
X295150D01*
X294443Y482801D01*
Y483678D01*
X293736Y484385D01*
X292858D01*
X292151Y485093D01*
Y485970D01*
X291444Y486677D01*
Y488287D01*
X290824Y488907D01*
Y489907D01*
X291444Y490527D01*
Y491633D01*
X290903Y492174D01*
Y493174D01*
X291444Y493715D01*
Y494885D01*
X290929Y495400D01*
Y496400D01*
X291444Y496915D01*
Y498100D01*
X290917Y498627D01*
Y499627D01*
X291444Y500154D01*
Y501247D01*
X290824Y501867D01*
Y502867D01*
X291444Y503487D01*
Y504487D01*
X290824Y505107D01*
Y506107D01*
X291444Y506727D01*
Y507727D01*
X290824Y508347D01*
Y509347D01*
X291444Y509967D01*
Y511694D01*
X290224Y512914D01*
X289124D01*
G01D02*
X288836D01*
X287419Y514331D01*
Y519300D01*
X286589Y520130D01*
Y526670D01*
X287419Y527500D01*
Y532444D01*
X289124Y534149D01*
G01X247213Y512700D02*
X246925D01*
X245225Y514400D01*
Y532411D01*
X247213Y534399D01*
G01X284024Y512700D02*
X283736D01*
X282036Y514400D01*
Y532411D01*
X284024Y534399D01*
G01X252313Y515514D02*
X254025Y517226D01*
Y518900D01*
X253025Y519900D01*
X251509D01*
X250838Y520571D01*
Y521848D01*
X251290Y522300D01*
X251625D01*
X252325Y523000D01*
Y524088D01*
X251615Y524798D01*
X251378D01*
X250838Y525338D01*
Y526229D01*
X251609Y527000D01*
X253125D01*
X254125Y528000D01*
Y529728D01*
X252313Y531540D01*
G01X323286Y407587D02*
Y412875D01*
X304300Y431861D01*
Y435304D01*
X302811Y436793D01*
X300192D01*
X299323Y437662D01*
Y439361D01*
X300195Y440233D01*
X301980D01*
X303472Y441725D01*
Y444318D01*
X302010Y445780D01*
X298644D01*
X297984Y446440D01*
Y481637D01*
X292504Y487117D01*
Y512134D01*
X289124Y515514D01*
G01D02*
X290836Y517226D01*
Y518900D01*
X289836Y519900D01*
X288320D01*
X287649Y520571D01*
Y521848D01*
X288101Y522300D01*
X288436D01*
X289136Y523000D01*
Y524088D01*
X288426Y524798D01*
X288189D01*
X287649Y525338D01*
Y526229D01*
X288420Y527000D01*
X289936D01*
X290936Y528000D01*
Y529728D01*
X289124Y531540D01*
G01X277557Y518157D02*
X275852Y519862D01*
Y531515D01*
X279037Y534700D01*
X280203D01*
G01Y513114D02*
X280115D01*
X278429Y514800D01*
Y516492D01*
X279336Y517399D01*
Y518992D01*
X278192Y520136D01*
Y521556D01*
X279036Y522400D01*
Y524100D01*
X278192Y524944D01*
Y526156D01*
X279136Y527100D01*
Y528300D01*
X278537Y528899D01*
X277557D01*
G01X270864Y518157D02*
X269159Y519862D01*
Y529835D01*
X269781Y530457D01*
Y531645D01*
X272836Y534700D01*
X273824D01*
G01X273910Y513114D02*
X273822D01*
X272136Y514800D01*
Y517000D01*
X272636Y517500D01*
Y519399D01*
X271499Y520536D01*
Y521864D01*
X272436Y522801D01*
Y524199D01*
X271499Y525136D01*
Y526364D01*
X272536Y527401D01*
Y528299D01*
X271936Y528899D01*
X270864D01*
G01X294289Y518157D02*
X292584Y519862D01*
Y530049D01*
X297635Y535100D01*
G01X321061Y-7108D02*
Y-4669D01*
X319356Y-2964D01*
Y1448D01*
X319966Y2058D01*
X321017D01*
X321627Y2668D01*
Y4568D01*
X321017Y5178D01*
X319966D01*
X319356Y5788D01*
Y14464D01*
X321061Y16169D01*
Y17057D01*
G01D02*
Y24469D01*
X322692Y26100D01*
Y28999D01*
X323452Y29759D01*
Y34239D01*
X322792Y34899D01*
Y48014D01*
X323452Y48674D01*
Y51140D01*
X322772Y51820D01*
Y66879D01*
X323092Y67199D01*
Y72391D01*
X322788Y72695D01*
Y75523D01*
X322452Y75859D01*
Y85474D01*
X322861Y85883D01*
Y88815D01*
X322607Y89069D01*
Y91429D01*
X322892Y91714D01*
Y95800D01*
X329592Y102500D01*
Y109597D01*
X345298Y125303D01*
Y200336D01*
G01X347298Y201105D02*
Y122550D01*
X331792Y107044D01*
Y102100D01*
X325821Y96129D01*
Y91805D01*
X326552Y91074D01*
Y88974D01*
X325852Y88274D01*
Y86374D01*
X326352Y85874D01*
Y81630D01*
X326106Y81384D01*
Y72705D01*
X326352Y72459D01*
Y69959D01*
X325752Y69359D01*
Y67359D01*
X326022Y67089D01*
Y53804D01*
X326102Y53724D01*
Y32709D01*
X325592Y32199D01*
Y29719D01*
X326049Y29262D01*
Y22186D01*
X322692Y18829D01*
Y14176D01*
X327754Y9114D01*
G01D02*
X327192Y8552D01*
Y800D01*
X327754Y238D01*
Y-1743D01*
G01X349298Y200994D02*
Y121721D01*
X333592Y106015D01*
Y101400D01*
X329752Y97560D01*
Y91674D01*
X329052Y90974D01*
Y89230D01*
X330035Y88247D01*
Y86557D01*
X329152Y85674D01*
Y75359D01*
X329382Y75129D01*
Y72949D01*
X328821Y72388D01*
Y70390D01*
X330095Y69116D01*
Y67220D01*
X329492Y66617D01*
Y53614D01*
X328774Y52896D01*
Y51352D01*
X329987Y50139D01*
Y48709D01*
X329372Y48094D01*
Y34779D01*
X328833Y34240D01*
Y32578D01*
X330252Y31159D01*
Y29485D01*
X329492Y28725D01*
Y26519D01*
X329752Y26259D01*
Y22402D01*
X324407Y17057D01*
G01D02*
X329392Y12072D01*
Y4708D01*
X329986Y4114D01*
Y-2206D01*
X324407Y-7785D01*
Y-9901D01*
G01X343273Y200681D02*
Y127012D01*
X322592Y106331D01*
Y101200D01*
X318492Y97100D01*
Y92148D01*
X319666Y90974D01*
Y88974D01*
X319066Y88374D01*
Y86174D01*
X319666Y85574D01*
Y83774D01*
X319331Y83439D01*
Y69624D01*
X319092Y69385D01*
Y67533D01*
X319456Y67169D01*
Y53024D01*
X319342Y52910D01*
Y34683D01*
X318866Y34207D01*
Y29959D01*
X319446Y29379D01*
Y26439D01*
X318400Y25393D01*
Y20207D01*
X315992Y17799D01*
Y11053D01*
X316105Y10940D01*
Y-2987D01*
X314368Y-4724D01*
Y-7108D01*
G01X337273Y190678D02*
Y129942D01*
X316592Y109261D01*
Y104200D01*
X310066Y97674D01*
Y92274D01*
X309066Y91274D01*
Y89224D01*
X310066Y88224D01*
Y86474D01*
X309066Y85474D01*
Y79859D01*
X310066Y78859D01*
Y67559D01*
X309316Y66809D01*
Y52207D01*
X309992Y51531D01*
Y49572D01*
X309380Y48960D01*
Y33413D01*
X310066Y32727D01*
Y29759D01*
X309292Y28985D01*
Y15000D01*
X309992Y14300D01*
Y11074D01*
X309392Y10474D01*
Y3700D01*
X311021Y2071D01*
Y-4536D01*
G01X341273Y200481D02*
Y127950D01*
X320892Y107569D01*
Y102500D01*
X316366Y97974D01*
Y91674D01*
X315666Y90974D01*
Y88874D01*
X316366Y88174D01*
Y86274D01*
X315766Y85674D01*
Y75359D01*
X316091Y75034D01*
Y72684D01*
X315766Y72359D01*
Y70059D01*
X316366Y69459D01*
Y67459D01*
X315992Y67085D01*
Y48960D01*
X316092Y48860D01*
Y34885D01*
X315766Y34559D01*
Y32259D01*
X316366Y31659D01*
Y29659D01*
X316009Y29302D01*
Y20117D01*
X314373Y18481D01*
Y17062D01*
X314368Y17057D01*
G01X339273Y191212D02*
Y128579D01*
X318892Y108198D01*
Y103500D01*
X312435Y97043D01*
Y91805D01*
X313166Y91074D01*
Y88974D01*
X312466Y88274D01*
Y86374D01*
X312966Y85874D01*
Y76395D01*
X312688Y76117D01*
Y72737D01*
X312966Y72459D01*
Y69959D01*
X312366Y69359D01*
Y67359D01*
X312763Y66962D01*
Y48710D01*
X312642Y48589D01*
Y30000D01*
X312726Y29916D01*
Y10819D01*
X311021Y9114D01*
G01X354526Y17057D02*
X352920Y15451D01*
Y3428D01*
X352692Y3200D01*
Y-2900D01*
X354526Y-4734D01*
Y-7108D01*
G01X363298Y196375D02*
Y106436D01*
X352593Y95731D01*
Y91805D01*
X353324Y91074D01*
Y88974D01*
X352624Y88274D01*
Y86374D01*
X352911Y86087D01*
Y69746D01*
X352822Y69657D01*
Y48376D01*
X352892Y48306D01*
Y26800D01*
X354526Y25166D01*
Y17057D01*
G01X354525Y-1742D02*
X354679Y-1588D01*
Y8968D01*
X354525Y9122D01*
G01D02*
X354892Y9489D01*
Y14901D01*
X356136Y16145D01*
Y28756D01*
X355292Y29600D01*
Y34200D01*
X356592Y35500D01*
Y45100D01*
X356167Y45525D01*
Y48032D01*
X355924Y48275D01*
Y53900D01*
X356153Y54129D01*
Y66630D01*
X355660Y67123D01*
Y72539D01*
X356206Y73085D01*
Y75077D01*
X355924Y75359D01*
Y85674D01*
X356120Y85870D01*
Y96429D01*
X365298Y105607D01*
Y196325D01*
G01X351179Y17057D02*
Y11888D01*
X349464Y10173D01*
Y7328D01*
X350392Y6400D01*
Y-1280D01*
X349451Y-3552D01*
Y-5759D01*
X351164Y-9895D01*
X351179Y-9901D01*
G01X361298Y191275D02*
Y107265D01*
X359649Y105616D01*
X358517D01*
X358079Y106054D01*
X356947D01*
X355816Y104923D01*
Y103791D01*
X356254Y103353D01*
Y102221D01*
X355123Y101090D01*
X353991D01*
X353103Y101978D01*
X351971D01*
X350840Y100847D01*
Y99715D01*
X351728Y98827D01*
Y97695D01*
X349766Y95733D01*
Y91816D01*
X349224Y91274D01*
Y89224D01*
X350224Y88224D01*
Y86474D01*
X349224Y85474D01*
Y83393D01*
X350241Y82376D01*
Y80273D01*
X349224Y79256D01*
Y75859D01*
X349443Y75640D01*
Y72578D01*
X349224Y72359D01*
Y70259D01*
X350224Y69259D01*
Y67559D01*
X349542Y66877D01*
Y64633D01*
X350647Y63528D01*
Y60881D01*
X349542Y59776D01*
Y53792D01*
X349101Y53351D01*
Y51547D01*
X350073Y50575D01*
Y48523D01*
X349452Y47902D01*
Y45664D01*
X350497Y44619D01*
Y42469D01*
X349452Y41424D01*
Y34975D01*
X350297Y34130D01*
Y30790D01*
X349574Y30067D01*
Y24918D01*
X351692Y22800D01*
Y17570D01*
X351179Y17057D01*
G01X347833Y-1743D02*
Y9122D01*
G01D02*
Y11800D01*
X349538Y13505D01*
Y20954D01*
X346092Y24400D01*
Y34545D01*
X346172Y34625D01*
Y48040D01*
X346102Y48110D01*
Y59638D01*
X347093Y60629D01*
Y62758D01*
X346102Y63749D01*
Y67295D01*
X345638Y67759D01*
Y69159D01*
X346438Y69959D01*
Y72159D01*
X346190Y72407D01*
Y83526D01*
X346438Y83774D01*
Y85574D01*
X345838Y86174D01*
Y88374D01*
X346438Y88974D01*
Y90974D01*
X345652Y91760D01*
Y96092D01*
X346262Y96702D01*
X347971D01*
X349316Y98047D01*
Y98909D01*
X348143Y100082D01*
Y101105D01*
X355630Y108592D01*
X357591D01*
X359298Y110299D01*
Y191225D01*
G01X357298Y191175D02*
Y114195D01*
X356144Y113041D01*
X353202D01*
X352278Y112117D01*
Y108069D01*
X343138Y98929D01*
Y91674D01*
X342438Y90974D01*
Y88874D01*
X343138Y88174D01*
Y86274D01*
X342538Y85674D01*
Y75359D01*
X342862Y75035D01*
Y72683D01*
X342822Y72643D01*
Y50690D01*
X342881Y50631D01*
Y24411D01*
X346121Y21171D01*
Y13617D01*
X344486Y11982D01*
Y9122D01*
G01D02*
X345332D01*
X345833Y8621D01*
Y7329D01*
X345223Y6719D01*
X344389D01*
X343752Y6082D01*
Y5092D01*
X344335Y4509D01*
X345460D01*
X346070Y3899D01*
Y2909D01*
X345460Y2299D01*
X344322D01*
X343751Y1728D01*
Y738D01*
X344400Y89D01*
X345387D01*
X346108Y-632D01*
Y-2682D01*
X347249Y-3823D01*
Y-4818D01*
X346425Y-5642D01*
X345592D01*
X344486Y-4536D01*
G01X355298Y190725D02*
Y119234D01*
X349707Y113643D01*
Y108327D01*
X339207Y97827D01*
Y91805D01*
X339938Y91074D01*
Y88974D01*
X339238Y88274D01*
Y86374D01*
X339738Y85874D01*
Y81630D01*
X339405Y81297D01*
Y69959D01*
X339512Y69852D01*
Y50748D01*
X339402Y50638D01*
Y43553D01*
X339398Y43549D01*
Y31819D01*
X339535Y31682D01*
Y24757D01*
X344486Y19806D01*
Y17057D01*
G01D02*
X342863Y13138D01*
Y8231D01*
X342123Y7491D01*
Y-211D01*
X342992Y-1080D01*
Y-3100D01*
X342666Y-3426D01*
Y-5392D01*
X344486Y-9786D01*
G01X351298Y200173D02*
Y120892D01*
X335792Y105386D01*
Y100801D01*
X332452Y97461D01*
Y91574D01*
X333052Y90974D01*
Y88974D01*
X332452Y88374D01*
Y86174D01*
X333052Y85574D01*
Y83774D01*
X332806Y83528D01*
Y72405D01*
X332485Y72084D01*
Y67526D01*
X332812Y67199D01*
Y52800D01*
X332310Y52298D01*
Y49602D01*
X332812Y49100D01*
Y45734D01*
X332452Y45374D01*
Y38339D01*
X332842Y37949D01*
Y33857D01*
X332446Y33461D01*
Y29765D01*
X332792Y29419D01*
Y21900D01*
X336052Y18640D01*
Y10855D01*
X337793Y9114D01*
G01D02*
Y6858D01*
X337183Y6248D01*
X333511D01*
X332901Y5638D01*
Y3738D01*
X333511Y3128D01*
X337183D01*
X337793Y2518D01*
Y316D01*
X337092Y-385D01*
Y-1644D01*
X335492Y-3244D01*
Y-4700D01*
X336092Y-5300D01*
X337029D01*
X337793Y-4536D01*
G01X353298Y200493D02*
Y120063D01*
X347707Y114472D01*
Y109156D01*
X346704Y108153D01*
X345602D01*
X343923Y109832D01*
X342745D01*
X341569Y108656D01*
Y107659D01*
X343311Y105917D01*
Y104760D01*
X342178Y103627D01*
X341049D01*
X339898Y104778D01*
X338599D01*
X337568Y103747D01*
Y102581D01*
X338785Y101364D01*
Y100234D01*
X336366Y97815D01*
Y91802D01*
X335838Y91274D01*
Y89256D01*
X336563Y88531D01*
Y85881D01*
X335838Y85156D01*
Y75859D01*
X336130Y75567D01*
Y66851D01*
X336072Y66793D01*
Y48220D01*
X336092Y48200D01*
Y32205D01*
X336838Y31459D01*
Y29759D01*
X336088Y29009D01*
Y25205D01*
X341140Y20153D01*
Y17057D01*
G01D02*
X339435Y15352D01*
Y6557D01*
X339892Y6100D01*
Y-400D01*
X339340Y-952D01*
Y-3148D01*
X339942Y-3750D01*
Y-5910D01*
X341140Y-7108D01*
G01X300982Y92757D02*
Y100290D01*
X301692Y101000D01*
X303293D01*
X303992Y101699D01*
Y102500D01*
X302266Y104226D01*
Y108374D01*
X302892Y109000D01*
Y111500D01*
X304148Y112756D01*
X305984D01*
X306884Y113656D01*
Y115612D01*
X306084Y116412D01*
X302052D01*
X301492Y116972D01*
Y119240D01*
X302052Y119800D01*
X306084D01*
X306884Y120600D01*
Y162958D01*
X308230Y164304D01*
X309022D01*
X310663Y162663D01*
X311455D01*
X312474Y163682D01*
Y164474D01*
X310833Y166115D01*
Y166907D01*
X319611Y175685D01*
X323477D01*
X329220Y181428D01*
Y194186D01*
G01X304328Y71900D02*
X302729Y73499D01*
Y86306D01*
X299736Y89299D01*
Y91511D01*
X300982Y92757D01*
G01X304328Y87714D02*
X306266Y89652D01*
Y91274D01*
X303784Y93756D01*
Y97092D01*
X307792Y101100D01*
Y105762D01*
X306584Y106970D01*
Y108570D01*
X307384Y109370D01*
X308418D01*
X309384Y110336D01*
Y155856D01*
X314792Y161264D01*
Y168199D01*
X320393Y173800D01*
X324992D01*
X331789Y180597D01*
Y194186D01*
G01X300982Y65699D02*
X302229Y66946D01*
Y68200D01*
X303529Y69500D01*
X304529D01*
X306329Y71300D01*
Y72364D01*
X305717Y72976D01*
Y86325D01*
X304328Y87714D01*
G01X294289Y92757D02*
Y92761D01*
X296184Y94656D01*
Y103508D01*
X295666Y104026D01*
Y108574D01*
X296766Y109674D01*
Y112674D01*
X295184Y114256D01*
Y128857D01*
X298892Y132565D01*
Y135785D01*
X298584Y136093D01*
Y137693D01*
X299384Y138493D01*
X301092D01*
X301892Y139293D01*
Y140893D01*
X301092Y141693D01*
X299384D01*
X298584Y142493D01*
Y144093D01*
X299384Y144893D01*
X301492D01*
X302292Y145693D01*
Y147293D01*
X301492Y148093D01*
X299384D01*
X298584Y148893D01*
Y150493D01*
X299384Y151293D01*
X301592D01*
X302392Y152093D01*
Y153693D01*
X301592Y154493D01*
X299384D01*
X298584Y155293D01*
Y158093D01*
X299236Y158745D01*
X300948D01*
X301884Y159681D01*
Y163291D01*
X318048Y179455D01*
X320747D01*
X324028Y182736D01*
Y192131D01*
G01X297635Y87714D02*
X295792Y89557D01*
Y91300D01*
X298584Y94092D01*
Y103192D01*
X299566Y104174D01*
Y108426D01*
X299084Y108908D01*
Y114056D01*
X297684Y115456D01*
Y123640D01*
X298244Y124200D01*
X303824D01*
X304384Y124760D01*
Y163124D01*
X318830Y177570D01*
X321962D01*
X326578Y182186D01*
Y192141D01*
G01X294289Y65699D02*
X295536Y66946D01*
Y68200D01*
X296836Y69500D01*
X297836D01*
X299636Y71300D01*
Y72700D01*
X299024Y73312D01*
Y86325D01*
X297635Y87714D01*
G01X331150Y406691D02*
Y415842D01*
X312045Y434947D01*
Y466131D01*
X306190Y471986D01*
Y473644D01*
X306990Y474444D01*
X308258D01*
X308881Y475067D01*
Y477067D01*
X308304Y477644D01*
X306712D01*
X305792Y478564D01*
Y486300D01*
X304292Y487800D01*
Y492400D01*
X302692Y494000D01*
Y499368D01*
X303024Y499700D01*
Y510907D01*
X299624Y514307D01*
Y516799D01*
X300982Y518157D01*
G01X333700Y406691D02*
Y416592D01*
X314699Y435593D01*
Y478038D01*
X312637Y480100D01*
X309099D01*
X308299Y480900D01*
Y483017D01*
X308909Y483627D01*
X312865D01*
X313449Y484211D01*
Y485601D01*
X312813Y486237D01*
X308909D01*
X308299Y486847D01*
Y488237D01*
X308909Y488847D01*
X312141D01*
X312710Y489416D01*
Y490806D01*
X312059Y491457D01*
X307719D01*
X306692Y492484D01*
Y499474D01*
X306166Y500000D01*
Y511328D01*
X304328Y513166D01*
Y513114D01*
G01X326050Y406691D02*
Y413934D01*
X306988Y432996D01*
Y447601D01*
X306088Y448501D01*
X301592D01*
X300792Y449301D01*
Y450901D01*
X301592Y451701D01*
X302640D01*
X303440Y452501D01*
Y454004D01*
X302444Y455000D01*
X301292D01*
X300492Y455800D01*
Y483200D01*
X296992Y486700D01*
Y493400D01*
X295992Y494400D01*
Y499500D01*
X296524Y500032D01*
Y510757D01*
X293624Y513657D01*
Y517492D01*
X294289Y518157D01*
G01X328600Y406691D02*
Y414993D01*
X309492Y434101D01*
Y456171D01*
X308096Y457567D01*
X303692D01*
X302892Y458367D01*
Y459467D01*
X303692Y460267D01*
X309090D01*
X309748Y460925D01*
Y462226D01*
X308974Y463000D01*
X303592D01*
X303092Y463500D01*
Y465466D01*
X303702Y466076D01*
X306662D01*
X307219Y466633D01*
Y468123D01*
X306556Y468786D01*
X303702D01*
X303092Y469396D01*
Y484300D01*
X299024Y488368D01*
Y493732D01*
X300192Y494900D01*
Y498200D01*
X299024Y499368D01*
Y511768D01*
X298981D01*
X297635Y513114D01*
G01X345792Y398948D02*
Y480458D01*
X331092Y495158D01*
Y504599D01*
X326392Y509299D01*
Y511600D01*
X325973Y512019D01*
Y513981D01*
X326197Y514205D01*
Y516495D01*
X326034Y516658D01*
Y537707D01*
X324772Y538969D01*
Y540441D01*
X325382Y541051D01*
X326591D01*
X327145Y541605D01*
Y543140D01*
X326479Y543806D01*
X325452D01*
X324814Y544444D01*
Y545624D01*
X326034Y546844D01*
Y570942D01*
X326049Y570957D01*
Y576843D01*
X319320Y583572D01*
Y591012D01*
X321061Y592753D01*
Y593657D01*
G01X347792Y395781D02*
Y481400D01*
X333092Y496100D01*
Y505700D01*
X329300Y509492D01*
Y511208D01*
X329792Y511700D01*
Y513800D01*
X329192Y514400D01*
Y516500D01*
X329472Y516780D01*
Y531596D01*
X329369Y531699D01*
Y538415D01*
X329384Y538430D01*
Y554592D01*
X329486Y554694D01*
Y570906D01*
X329383Y571009D01*
Y577309D01*
X322787Y583905D01*
Y588948D01*
X324407Y590568D01*
Y593657D01*
G01X349792Y405706D02*
Y485999D01*
X348243Y487548D01*
X347111D01*
X346358Y486795D01*
X345226D01*
X344095Y487926D01*
Y489058D01*
X344848Y489811D01*
Y490943D01*
X343717Y492074D01*
X342585D01*
X341936Y491425D01*
X340817D01*
X339686Y492556D01*
Y493701D01*
X340322Y494337D01*
Y495469D01*
X335092Y500699D01*
Y507324D01*
X333092Y509324D01*
Y511200D01*
X332592Y511700D01*
Y514000D01*
X332992Y514400D01*
Y516300D01*
X332392Y516900D01*
Y525800D01*
X332792Y526200D01*
Y530300D01*
X332492Y530600D01*
Y534397D01*
X332807Y534712D01*
Y549185D01*
X332292Y549700D01*
Y552622D01*
X332777Y553107D01*
Y558015D01*
X332192Y558600D01*
Y564400D01*
X332734Y564942D01*
Y568158D01*
X332192Y568700D01*
Y572742D01*
X332821Y573371D01*
Y577300D01*
X324407Y585714D01*
G01X343792Y399647D02*
Y479629D01*
X329092Y494329D01*
Y502600D01*
X322492Y509200D01*
Y511000D01*
X322992Y511500D01*
Y513800D01*
X322492Y514300D01*
Y516400D01*
X323092Y517000D01*
Y526100D01*
X322743Y526449D01*
Y530351D01*
X323286Y530894D01*
Y533845D01*
X322802Y534329D01*
Y545390D01*
X322787Y545405D01*
Y549395D01*
X322831Y549439D01*
Y553753D01*
X322698Y553886D01*
Y564816D01*
X322787Y564905D01*
Y568195D01*
X323092Y568500D01*
Y571784D01*
X322787Y572089D01*
Y576605D01*
X316087Y583305D01*
Y589805D01*
X315999Y589893D01*
Y597975D01*
X314368Y599606D01*
Y607292D01*
G01X337792Y399687D02*
Y476800D01*
X312892Y501700D01*
Y511400D01*
X312292Y512000D01*
Y513500D01*
X313092Y514300D01*
Y516400D01*
X312392Y517100D01*
Y519500D01*
X312752Y519860D01*
Y533060D01*
X313092Y533400D01*
Y534900D01*
X312649Y535343D01*
Y552057D01*
X312738Y552146D01*
Y568254D01*
X312634Y568358D01*
Y577158D01*
X309402Y580390D01*
Y586810D01*
X309992Y587400D01*
Y591392D01*
X309285Y592099D01*
Y596807D01*
X308892Y597200D01*
Y605300D01*
X311021Y607429D01*
Y609864D01*
G01X341792Y399889D02*
Y478800D01*
X319592Y501000D01*
Y511500D01*
X319192Y511900D01*
Y513900D01*
X319692Y514400D01*
Y516300D01*
X319092Y516900D01*
Y519500D01*
X319422Y519830D01*
Y530570D01*
X319319Y530673D01*
Y549273D01*
X319092Y549500D01*
Y553804D01*
X319423Y554135D01*
Y568169D01*
X319192Y568400D01*
Y573600D01*
X319319Y573727D01*
Y577073D01*
X312649Y583743D01*
Y590070D01*
X314368Y591789D01*
Y593657D01*
G01X311021Y585714D02*
Y581988D01*
X316087Y576922D01*
Y568395D01*
X315999Y568307D01*
Y552093D01*
X316087Y552005D01*
Y533105D01*
X316392Y532800D01*
Y530700D01*
X315999Y530307D01*
Y519493D01*
X316392Y519100D01*
Y517000D01*
X315592Y516200D01*
Y514400D01*
X316192Y513800D01*
Y511500D01*
X315892Y511200D01*
Y501800D01*
X339792Y477900D01*
Y399607D01*
G01X351792Y406100D02*
Y486828D01*
X337092Y501528D01*
Y508154D01*
X335892Y509354D01*
Y511100D01*
X336292Y511500D01*
Y513900D01*
X335792Y514400D01*
Y516300D01*
X336692Y517200D01*
Y524800D01*
X336084Y525408D01*
Y549292D01*
X336492Y549700D01*
Y552376D01*
X336068Y552800D01*
Y568176D01*
X336492Y568600D01*
Y572048D01*
X336157Y572383D01*
Y575835D01*
X334446Y577546D01*
Y585714D01*
G01X353792Y405714D02*
Y491628D01*
X352837Y492583D01*
X351721D01*
X350871Y491733D01*
X349897D01*
X348587Y493043D01*
Y493975D01*
X349265Y494653D01*
Y495771D01*
X348134Y496902D01*
X346988D01*
X346334Y496248D01*
X345202D01*
X344392Y497058D01*
Y498978D01*
X342596Y500774D01*
X341220D01*
X339692Y502302D01*
Y511200D01*
X339192Y511700D01*
Y513700D01*
X339792Y514300D01*
Y516500D01*
X338592Y517700D01*
Y520800D01*
X339506Y521714D01*
Y535686D01*
X339411Y535781D01*
Y551043D01*
X339528Y551160D01*
Y568064D01*
X339404Y568188D01*
Y576288D01*
X337793Y577899D01*
Y585714D01*
G01X355792Y413600D02*
Y492292D01*
X342292Y505792D01*
Y510900D01*
X343092Y511700D01*
Y513800D01*
X342492Y514400D01*
Y516500D01*
X342992Y517000D01*
Y521800D01*
X342768Y522024D01*
Y535676D01*
X342871Y535779D01*
Y577021D01*
X339419Y580473D01*
Y589527D01*
X341140Y591248D01*
Y593657D01*
G01X300982Y518157D02*
X299277Y519862D01*
Y530049D01*
X304328Y535100D01*
G01Y513114D02*
X304240D01*
X302554Y514800D01*
Y516492D01*
X302729Y516667D01*
Y519300D01*
X301617Y520412D01*
Y521488D01*
X302629Y522500D01*
Y523700D01*
X301617Y524712D01*
Y525788D01*
X302754Y526925D01*
Y528199D01*
X302054Y528899D01*
X300982D01*
G01X297635Y513114D02*
X297547D01*
X295861Y514800D01*
Y516492D01*
X296036Y516667D01*
Y519300D01*
X294924Y520412D01*
Y521488D01*
X295936Y522500D01*
Y523700D01*
X294924Y524712D01*
Y525788D01*
X296061Y526925D01*
Y528199D01*
X295361Y528899D01*
X294289D01*
G01X360532Y404760D02*
Y409737D01*
X361792Y410997D01*
Y495758D01*
X360403Y497147D01*
Y498279D01*
X361668Y499544D01*
Y500635D01*
X360537Y501766D01*
X359364D01*
X358305Y500707D01*
X357338D01*
X356207Y501838D01*
Y503135D01*
X357701Y504629D01*
Y505584D01*
X356433Y506852D01*
X355398D01*
X354164Y505618D01*
X353115D01*
X351825Y506908D01*
Y508099D01*
X353056Y509330D01*
Y511036D01*
X352492Y511600D01*
Y513800D01*
X353192Y514500D01*
Y516600D01*
X352392Y517400D01*
Y519900D01*
X352892Y520400D01*
Y577000D01*
X349453Y580439D01*
Y591931D01*
X351179Y593657D01*
G01X358501Y405305D02*
Y410535D01*
X359792Y411826D01*
Y494928D01*
X348598Y506122D01*
Y510606D01*
X349698Y511706D01*
Y514194D01*
X349292Y514600D01*
Y516300D01*
X350292Y517300D01*
Y524200D01*
X349555Y524937D01*
Y532837D01*
X349468Y532924D01*
Y554576D01*
X349542Y554650D01*
Y573344D01*
X349439Y573447D01*
Y577153D01*
X344486Y582106D01*
Y585722D01*
G01X357792Y413816D02*
Y492678D01*
X353590Y496880D01*
Y497848D01*
X351795Y499643D01*
X350947D01*
X349064Y501526D01*
Y502826D01*
X345739Y506151D01*
Y508747D01*
X346392Y509400D01*
Y511400D01*
X346060Y511732D01*
Y513868D01*
X346292Y514100D01*
Y516600D01*
X345692Y517200D01*
Y520800D01*
X346119Y521227D01*
Y533027D01*
X346492Y533400D01*
Y535400D01*
X346207Y535685D01*
Y551835D01*
X346117Y551925D01*
Y570925D01*
X346191Y570999D01*
Y576901D01*
X342871Y580221D01*
Y592042D01*
X344486Y593657D01*
G01X324407Y585714D02*
Y587677D01*
X326551Y589821D01*
Y592241D01*
X326049Y592743D01*
Y594801D01*
X326539Y595291D01*
Y605553D01*
X324407Y607685D01*
Y609864D01*
G01X334446Y585714D02*
X332307Y587853D01*
Y591761D01*
X332718Y592172D01*
Y599326D01*
X333092Y599700D01*
Y605600D01*
X332592Y606100D01*
Y608500D01*
X334447Y610355D01*
Y612457D01*
G01X362532Y401713D02*
Y408908D01*
X363792Y410168D01*
Y502438D01*
X356792Y509438D01*
Y524824D01*
X359615Y527647D01*
Y556903D01*
X356153Y560365D01*
Y567961D01*
X355757Y568357D01*
Y573617D01*
X356156Y574016D01*
Y577336D01*
X352891Y580601D01*
Y587201D01*
X352592Y587500D01*
Y591723D01*
X354526Y593657D01*
G01X344486Y585722D02*
Y587894D01*
X346492Y589900D01*
Y592300D01*
X346117Y592675D01*
Y594559D01*
X348155Y596597D01*
Y604181D01*
X345911Y606425D01*
X344486Y609864D01*
G01X337793Y585714D02*
X336992Y586515D01*
Y591572D01*
X336068Y592496D01*
Y594604D01*
X335993Y594679D01*
Y605599D01*
X336247Y605853D01*
Y608318D01*
X337793Y609864D01*
G01X321061Y593657D02*
X319931Y594787D01*
Y606162D01*
X321061Y607292D01*
G01X324407Y593657D02*
Y595196D01*
X323797Y595806D01*
X322872D01*
X322262Y596416D01*
Y597406D01*
X322872Y598016D01*
X323797D01*
X324407Y598626D01*
Y599616D01*
X323797Y600226D01*
X322454D01*
X321844Y600836D01*
Y601826D01*
X322454Y602436D01*
X323797D01*
X324407Y603046D01*
Y604499D01*
G01X354526Y593657D02*
Y607292D01*
G01X351179Y593657D02*
X352753Y595231D01*
Y596832D01*
X352143Y597442D01*
X350518D01*
X349908Y598052D01*
Y599442D01*
X350518Y600052D01*
X352143D01*
X352753Y600662D01*
Y602925D01*
X351179Y604499D01*
G01X344486Y593657D02*
Y595615D01*
X343754Y596347D01*
X340149D01*
X339631Y596865D01*
Y598502D01*
X340228Y599099D01*
X345886D01*
X346400Y599613D01*
Y601155D01*
X345846Y601709D01*
X341984D01*
X341377Y602316D01*
Y604797D01*
X342380Y605800D01*
X343300D01*
X344486Y604614D01*
G01X341140Y593657D02*
X340330D01*
X337993Y595994D01*
Y602153D01*
X339593Y603753D01*
Y605245D01*
X338423Y606415D01*
Y607971D01*
X339692Y609240D01*
Y610062D01*
X340192Y610562D01*
X341492D01*
X341992Y610062D01*
Y608144D01*
X341140Y607292D01*
G01X404722Y-9901D02*
Y-7430D01*
X402792Y-5500D01*
Y-3400D01*
X403392Y-2800D01*
Y600D01*
X403065Y927D01*
Y10373D01*
X403592Y10900D01*
Y15926D01*
X404723Y17057D01*
G01X384632Y190071D02*
Y116530D01*
X385561Y115601D01*
X386693D01*
X387376Y116284D01*
X388508D01*
X389639Y115153D01*
Y114021D01*
X388956Y113338D01*
Y112206D01*
X394992Y106170D01*
Y101292D01*
X399377Y96907D01*
Y91674D01*
X399851Y91200D01*
Y88648D01*
X399487Y88284D01*
Y86164D01*
X400433Y85218D01*
Y82049D01*
X399629Y81245D01*
X398799D01*
X398213Y80659D01*
Y78759D01*
X398847Y78125D01*
X399641D01*
X400141Y77625D01*
Y75523D01*
X399739Y75121D01*
Y72597D01*
X399977Y72359D01*
Y70059D01*
X399377Y69459D01*
Y67459D01*
X399762Y67074D01*
Y57462D01*
X399658Y57358D01*
Y53593D01*
X399738Y53513D01*
Y22042D01*
X404723Y17057D01*
G01X378428Y189302D02*
Y108744D01*
X382572Y104600D01*
Y80720D01*
X383792Y79500D01*
Y46500D01*
X385052Y45240D01*
Y40020D01*
X383852Y38820D01*
Y7101D01*
X380191Y3440D01*
X376232D01*
X374352Y1560D01*
Y-2847D01*
X370534Y-6665D01*
X364245D01*
X363346Y-7564D01*
Y-8567D01*
X364565Y-9786D01*
G01X371778Y188688D02*
Y84177D01*
X370548Y82947D01*
X367402D01*
X366821Y82366D01*
Y80976D01*
X367460Y80337D01*
X370548D01*
X371778Y79107D01*
Y62214D01*
X374872Y59120D01*
Y54570D01*
X377092Y52350D01*
Y43300D01*
X374872Y41080D01*
Y23896D01*
X370796Y19820D01*
X365050D01*
X364355Y19125D01*
Y17998D01*
X365311Y17042D01*
G01X375128Y189209D02*
Y106341D01*
X378846Y102623D01*
Y55646D01*
X379892Y54600D01*
Y42000D01*
X378846Y40954D01*
Y10901D01*
X376794Y8849D01*
X375326D01*
X371314Y4837D01*
Y1224D01*
X370082Y-8D01*
X367758D01*
X366525Y1225D01*
Y5353D01*
X365749Y6129D01*
X358699D01*
X358046Y5476D01*
Y3577D01*
X358636Y2987D01*
X362030D01*
X363346Y1671D01*
Y-639D01*
X364565Y-1858D01*
G01X368478Y196219D02*
Y102615D01*
X360730Y94867D01*
Y86133D01*
X362392Y84471D01*
Y72100D01*
X365052Y69440D01*
Y62840D01*
X371372Y56520D01*
Y53770D01*
X373992Y51150D01*
Y45500D01*
X371372Y42880D01*
Y26367D01*
X369325Y24320D01*
X364174D01*
X360957Y21103D01*
Y15523D01*
X363346Y13134D01*
Y10333D01*
X364565Y9114D01*
G01X377368Y189302D02*
Y108304D01*
X381512Y104160D01*
Y80280D01*
X382732Y79060D01*
Y46060D01*
X383992Y44800D01*
Y40460D01*
X382792Y39260D01*
Y7541D01*
X379751Y4500D01*
X375792D01*
X373292Y2000D01*
Y-2407D01*
X370094Y-5605D01*
X363805D01*
X362286Y-7124D01*
Y-8718D01*
X361218Y-9786D01*
G01X370718Y188688D02*
Y84617D01*
X370108Y84007D01*
X366962D01*
X365761Y82806D01*
Y80536D01*
X367020Y79277D01*
X370108D01*
X370718Y78667D01*
Y61774D01*
X373812Y58680D01*
Y54130D01*
X376032Y51910D01*
Y43740D01*
X373812Y41520D01*
Y24336D01*
X370356Y20880D01*
X364610D01*
X363295Y19565D01*
Y17647D01*
X362662Y17014D01*
G01X374068Y189367D02*
Y105901D01*
X377786Y102183D01*
Y55206D01*
X378832Y54160D01*
Y42440D01*
X377786Y41394D01*
Y11341D01*
X376354Y9909D01*
X374886D01*
X370254Y5277D01*
Y1664D01*
X369642Y1052D01*
X368198D01*
X367585Y1665D01*
Y5793D01*
X366189Y7189D01*
X358259D01*
X356986Y5916D01*
Y3137D01*
X358196Y1927D01*
X361590D01*
X362286Y1231D01*
Y-790D01*
X361218Y-1858D01*
G01X367418Y196219D02*
Y103055D01*
X359670Y95307D01*
Y85693D01*
X361332Y84031D01*
Y71660D01*
X363992Y69000D01*
Y62400D01*
X370312Y56080D01*
Y53330D01*
X372932Y50710D01*
Y45940D01*
X370312Y43320D01*
Y26807D01*
X368885Y25380D01*
X363734D01*
X359897Y21543D01*
Y15083D01*
X362286Y12694D01*
Y10182D01*
X361218Y9114D01*
G01X388632Y190084D02*
Y121992D01*
X398992Y111632D01*
Y102952D01*
X405677Y96267D01*
Y92274D01*
X406982Y90969D01*
Y89529D01*
X405677Y88224D01*
Y86474D01*
X406677Y85474D01*
Y75859D01*
X406332Y75514D01*
Y69914D01*
X405677Y69259D01*
Y67559D01*
X406333Y66903D01*
Y53818D01*
X405677Y53162D01*
Y48674D01*
X406344Y48007D01*
Y43486D01*
X407081Y42749D01*
Y38463D01*
X406352Y37734D01*
Y32134D01*
X405677Y31459D01*
Y29759D01*
X406331Y29105D01*
Y21961D01*
X409687Y18605D01*
Y15146D01*
X410767Y14066D01*
Y11090D01*
X409801Y10124D01*
Y6427D01*
X410411Y5817D01*
X411754D01*
X412568Y5003D01*
Y3403D01*
X411782Y2617D01*
X410668D01*
X409868Y1817D01*
Y-3024D01*
X409492Y-3400D01*
Y-5702D01*
X410898Y-7108D01*
X414761D01*
G01X390632Y190240D02*
Y122822D01*
X404292Y109162D01*
Y101042D01*
X410166Y95168D01*
Y91677D01*
X409463Y90974D01*
Y88974D01*
X410063Y88374D01*
Y86174D01*
X409463Y85574D01*
Y83774D01*
X409791Y83446D01*
Y72259D01*
X410263Y71787D01*
Y67759D01*
X409775Y67271D01*
Y62420D01*
X409707Y62352D01*
Y53102D01*
X410063Y52746D01*
Y48374D01*
X409776Y48087D01*
Y33700D01*
X410263Y33213D01*
Y29959D01*
X409798Y29494D01*
Y22022D01*
X414762Y17058D01*
G01X382632Y190375D02*
Y115700D01*
X392992Y105340D01*
Y100462D01*
X396615Y96839D01*
Y91805D01*
X395884Y91074D01*
Y88974D01*
X396584Y88274D01*
Y86374D01*
X396084Y85874D01*
Y69959D01*
X396684Y69359D01*
Y67359D01*
X396084Y66759D01*
Y63408D01*
X396245Y63247D01*
Y50813D01*
X396584Y50474D01*
Y48574D01*
X396084Y48074D01*
Y43889D01*
X396650Y43323D01*
Y38151D01*
X396303Y37804D01*
Y29178D01*
X396084Y28959D01*
Y27208D01*
X397392Y25900D01*
Y17679D01*
X398029Y17042D01*
G01D02*
Y11763D01*
X399741Y10051D01*
Y649D01*
X399425Y333D01*
Y-2733D01*
X400057Y-3365D01*
Y-5555D01*
X398029Y-7583D01*
Y-9901D01*
G01X392632Y190218D02*
Y123652D01*
X406292Y109992D01*
Y101872D01*
X412266Y95898D01*
Y92171D01*
X413463Y90974D01*
Y88874D01*
X412763Y88174D01*
Y86274D01*
X413363Y85674D01*
Y75359D01*
X413029Y75025D01*
Y72693D01*
X413363Y72359D01*
Y67341D01*
X413122Y67100D01*
Y53515D01*
X413463Y53174D01*
Y51074D01*
X412763Y50374D01*
Y48474D01*
X413158Y48079D01*
Y34764D01*
X413363Y34559D01*
Y32259D01*
X412763Y31659D01*
Y29659D01*
X413138Y29284D01*
Y24106D01*
X416386Y20858D01*
Y15794D01*
X414761Y14169D01*
Y9124D01*
X414763Y9122D01*
G01D02*
X414761Y9120D01*
Y7799D01*
X415371Y7189D01*
X418571D01*
X419181Y6579D01*
Y115D01*
X418543Y-523D01*
X417553D01*
X416971Y59D01*
Y4249D01*
X416361Y4859D01*
X415371D01*
X414761Y4249D01*
Y-1743D01*
G01X386632Y190168D02*
Y121162D01*
X392757Y115037D01*
Y113905D01*
X391988Y113136D01*
Y112004D01*
X393119Y110873D01*
X394251D01*
X395020Y111642D01*
X396152D01*
X396992Y110802D01*
Y102122D01*
X403308Y95806D01*
Y91805D01*
X402471Y90968D01*
Y89080D01*
X403277Y88274D01*
Y86374D01*
X402777Y85874D01*
Y77115D01*
X403014Y76878D01*
Y72696D01*
X402493Y72175D01*
Y70243D01*
X403377Y69359D01*
Y67359D01*
X403109Y67091D01*
Y53806D01*
X402348Y53045D01*
Y51403D01*
X403277Y50474D01*
Y48574D01*
X403098Y48395D01*
Y34980D01*
X402275Y34157D01*
Y32661D01*
X403377Y31559D01*
Y29559D01*
X403056Y29238D01*
Y22055D01*
X408069Y17042D01*
G01D02*
X406192Y15165D01*
Y10200D01*
X406363Y10029D01*
Y-901D01*
X406192Y-1072D01*
Y-3000D01*
X406842Y-3650D01*
Y-5882D01*
X408068Y-7108D01*
G01X394632Y190266D02*
Y124481D01*
X395752Y123360D01*
X411019Y108094D01*
Y99974D01*
X416694Y94299D01*
Y91805D01*
X416245Y91356D01*
Y88692D01*
X416663Y88274D01*
Y86374D01*
X416163Y85874D01*
Y75929D01*
X416381Y75711D01*
Y31941D01*
X416370Y31930D01*
Y23704D01*
X419815Y20259D01*
Y14944D01*
X419302Y14431D01*
Y12468D01*
X420820Y10950D01*
X422042D01*
X423074Y9918D01*
Y1711D01*
X423491Y1294D01*
Y-2921D01*
X423074Y-3338D01*
Y-5984D01*
X424801Y-7711D01*
Y-9786D01*
G01X394683Y-2200D02*
Y-1141D01*
X394682Y-1140D01*
Y11792D01*
G01D02*
Y13410D01*
X392692Y15400D01*
Y97932D01*
X390992Y99632D01*
Y104510D01*
X380632Y114870D01*
Y190271D01*
X380630Y190273D01*
G01X431494Y-9901D02*
Y-7202D01*
X429692Y-5400D01*
Y-3400D01*
X430092Y-3000D01*
Y-100D01*
X429757Y235D01*
Y12435D01*
X426408Y15784D01*
Y19325D01*
X423070Y22663D01*
Y29380D01*
X423791Y30101D01*
Y33457D01*
X423065Y34183D01*
Y47990D01*
X423168Y48093D01*
Y57358D01*
X423075Y57451D01*
Y67185D01*
X423649Y67759D01*
Y71035D01*
X423076Y71608D01*
Y75015D01*
X422849Y75242D01*
Y85574D01*
X423449Y86174D01*
Y88374D01*
X422849Y88974D01*
Y90974D01*
X423449Y91574D01*
Y93342D01*
X417392Y99399D01*
Y107381D01*
X398632Y126141D01*
Y191296D01*
G01X406632Y189743D02*
Y129461D01*
X430192Y105901D01*
Y102299D01*
X436835Y95656D01*
Y91574D01*
X436235Y90974D01*
Y88974D01*
X436835Y88374D01*
Y86174D01*
X436235Y85574D01*
Y83774D01*
X436549Y83460D01*
Y72473D01*
X436235Y72159D01*
Y69959D01*
X437035Y69159D01*
Y67759D01*
X436582Y67306D01*
Y53521D01*
X436235Y53174D01*
Y51174D01*
X436835Y50574D01*
Y48374D01*
X436565Y48104D01*
Y45644D01*
X436835Y45374D01*
Y38983D01*
X436501Y38176D01*
Y31893D01*
X437035Y31359D01*
Y29959D01*
X436584Y29508D01*
Y21907D01*
X439819Y18672D01*
Y-373D01*
X439592Y-600D01*
Y-2744D01*
X444880Y-8032D01*
Y-9786D01*
G01X408632Y189343D02*
Y130290D01*
X432292Y106630D01*
Y103199D01*
X439535Y95956D01*
Y91674D01*
X440235Y90974D01*
Y88874D01*
X439535Y88174D01*
Y86274D01*
X440135Y85674D01*
Y75359D01*
X439803Y75027D01*
Y72691D01*
X440135Y72359D01*
Y70059D01*
X439535Y69459D01*
Y67459D01*
X439814Y67180D01*
Y53595D01*
X440235Y53174D01*
Y50840D01*
X439813Y50418D01*
Y43966D01*
X440135Y43644D01*
Y37559D01*
X439825Y37249D01*
Y34869D01*
X440135Y34559D01*
Y32259D01*
X439535Y31659D01*
Y29659D01*
X439819Y29375D01*
Y22073D01*
X443256Y18636D01*
Y7236D01*
X444880Y5612D01*
Y-4536D01*
G01X431494Y17042D02*
X430392Y18144D01*
Y18170D01*
X426516Y22046D01*
Y36846D01*
X427466Y37796D01*
Y39572D01*
X426856Y40182D01*
X425637D01*
X425027Y40792D01*
Y42182D01*
X425637Y42792D01*
X426856D01*
X427466Y43402D01*
Y45076D01*
X426541Y46001D01*
Y48082D01*
X426149Y48474D01*
Y50374D01*
X426849Y51074D01*
Y53174D01*
X426429Y53594D01*
Y57357D01*
X426521Y57449D01*
Y67087D01*
X426149Y67459D01*
Y69459D01*
X426749Y70059D01*
Y72359D01*
X426511Y72597D01*
Y74625D01*
X427320Y75434D01*
Y78568D01*
X426710Y79178D01*
X425431D01*
X424858Y79751D01*
Y81141D01*
X425505Y81788D01*
X426710D01*
X427320Y82398D01*
Y85103D01*
X426149Y86274D01*
Y88174D01*
X426849Y88874D01*
Y90974D01*
X426292Y91531D01*
Y95700D01*
X423480Y98512D01*
X421716D01*
X419598Y100630D01*
Y108005D01*
X400632Y126971D01*
Y190799D01*
G01X410632Y188943D02*
Y131119D01*
X436050Y105701D01*
Y104571D01*
X435501Y104023D01*
Y102893D01*
X436634Y101760D01*
X437765D01*
X438313Y102308D01*
X439443D01*
X440576Y101175D01*
Y100045D01*
X440027Y99497D01*
Y98367D01*
X441160Y97234D01*
X442291D01*
X442839Y97782D01*
X443969D01*
X444923Y96828D01*
Y93262D01*
X442735Y91074D01*
Y88974D01*
X443435Y88274D01*
Y86374D01*
X442935Y85874D01*
Y75757D01*
X443249Y75443D01*
Y72119D01*
X442357Y71227D01*
Y68752D01*
X443249Y67860D01*
Y64916D01*
X442229Y63896D01*
Y62460D01*
X442928Y61761D01*
X444415D01*
X445025Y61151D01*
Y59761D01*
X444415Y59151D01*
X442830D01*
X442114Y58435D01*
Y56957D01*
X443249Y55822D01*
Y53256D01*
X442735Y52742D01*
Y50936D01*
X443238Y50433D01*
Y43586D01*
X443501Y43323D01*
Y38735D01*
X443257Y38491D01*
Y31837D01*
X443244Y31824D01*
Y22648D01*
X444880Y21012D01*
Y17059D01*
G01X412740Y188712D02*
Y131840D01*
X446835Y97745D01*
Y52240D01*
X446489Y51894D01*
Y26761D01*
X446992Y26258D01*
Y16084D01*
X445819Y14911D01*
Y10061D01*
X444880Y9122D01*
G01X438187Y-9786D02*
Y-7695D01*
X433008Y-2516D01*
Y316D01*
X433233Y541D01*
Y10052D01*
X431633Y11652D01*
Y14811D01*
X433107Y16285D01*
Y18285D01*
X429764Y21628D01*
Y53689D01*
X429881Y53806D01*
Y57276D01*
X429776Y57381D01*
Y69732D01*
X429549Y69959D01*
Y72459D01*
X429764Y72674D01*
Y83727D01*
X429549Y83942D01*
Y85874D01*
X430049Y86374D01*
Y88274D01*
X429349Y88974D01*
Y91074D01*
X430080Y91805D01*
Y95012D01*
X423492Y101600D01*
Y106941D01*
X402632Y127801D01*
Y190520D01*
G01X396632Y191585D02*
Y125311D01*
X413019Y108924D01*
Y100873D01*
X419063Y94829D01*
Y92274D01*
X420063Y91274D01*
Y89224D01*
X419063Y88224D01*
Y86474D01*
X420866Y84671D01*
Y82933D01*
X420256Y82323D01*
X419000D01*
X418390Y81713D01*
Y80323D01*
X419000Y79713D01*
X420256D01*
X420866Y79103D01*
Y76662D01*
X419831Y75627D01*
Y71727D01*
X419063Y70959D01*
Y67559D01*
X419820Y66802D01*
Y64733D01*
X420379Y64174D01*
Y61892D01*
X419821Y61334D01*
Y59550D01*
X420647Y58724D01*
Y57163D01*
X419820Y56336D01*
Y53717D01*
X418802Y52699D01*
Y48935D01*
X419838Y47899D01*
Y44906D01*
X418996Y44064D01*
Y42296D01*
X419838Y41454D01*
Y34604D01*
X418754Y33520D01*
Y30068D01*
X419816Y29006D01*
Y23087D01*
X424020Y18883D01*
Y17823D01*
X424801Y17042D01*
G01X438187Y17059D02*
X433235Y22011D01*
Y28973D01*
X431773Y30435D01*
Y33325D01*
X433228Y34780D01*
Y47895D01*
X431748Y49375D01*
Y52465D01*
X433103Y53820D01*
Y57731D01*
X433222Y57850D01*
Y66786D01*
X431723Y68285D01*
Y70985D01*
X433210Y72472D01*
Y85713D01*
X432449Y86474D01*
Y88224D01*
X433449Y89224D01*
Y91274D01*
X432492Y92231D01*
Y95599D01*
X425592Y102499D01*
Y107671D01*
X404632Y128631D01*
Y190277D01*
G01X383192Y402828D02*
Y491912D01*
X384192Y492912D01*
X385324D01*
X386447Y491789D01*
X387579D01*
X388710Y492920D01*
Y494052D01*
X387587Y495175D01*
Y496307D01*
X399858Y508578D01*
Y511134D01*
X399402Y511590D01*
Y513702D01*
X399886Y514186D01*
Y516706D01*
X399492Y517100D01*
Y526700D01*
X399744Y526952D01*
Y533052D01*
X399747Y533055D01*
Y554345D01*
X399656Y554436D01*
Y556964D01*
X400341Y557649D01*
Y562811D01*
X399744Y563408D01*
Y579824D01*
X402999Y583079D01*
Y587207D01*
X404723Y588931D01*
Y593657D01*
G01X371412Y401381D02*
Y405391D01*
X372512Y406491D01*
Y496248D01*
X376700Y500436D01*
Y510884D01*
X378599Y512783D01*
Y520701D01*
X378151Y521149D01*
Y522979D01*
X378599Y523427D01*
Y525257D01*
X378151Y525705D01*
Y527535D01*
X378599Y527983D01*
Y529813D01*
X378151Y530261D01*
Y532091D01*
X378599Y532539D01*
Y534369D01*
X378151Y534817D01*
Y536647D01*
X378599Y537095D01*
Y572588D01*
X378151Y573036D01*
Y574866D01*
X378599Y575314D01*
Y586351D01*
X378151Y586799D01*
Y588629D01*
X378599Y589077D01*
Y590907D01*
X378151Y591355D01*
Y593185D01*
X378599Y593633D01*
Y595463D01*
X377329Y596733D01*
X371552D01*
X371211Y596392D01*
X369381D01*
X369040Y596733D01*
X367085D01*
X365853Y597965D01*
Y600837D01*
X367085Y602069D01*
X369023D01*
X369363Y602409D01*
X371193D01*
X371533Y602069D01*
X374164D01*
X375226Y603131D01*
Y606677D01*
X374034Y607869D01*
X369954D01*
X369542Y607457D01*
X367712D01*
X367300Y607869D01*
X364303D01*
X363378Y606944D01*
Y605801D01*
X364565Y604614D01*
G01X364716Y401277D02*
Y408095D01*
X365912Y409291D01*
Y499488D01*
X368732Y502308D01*
Y525360D01*
X370012Y526640D01*
Y548900D01*
X371932Y550820D01*
Y557860D01*
X370012Y559780D01*
Y574613D01*
X364513Y580112D01*
X361022D01*
X358753Y582381D01*
Y597098D01*
X359873Y598218D01*
X362052D01*
X364157Y596113D01*
Y594796D01*
X365311Y593642D01*
G01X374812Y401699D02*
Y404091D01*
X376012Y405291D01*
Y494888D01*
X380605Y499481D01*
Y509093D01*
X382073Y510561D01*
Y533775D01*
X381625Y534223D01*
Y536053D01*
X382073Y536501D01*
Y538331D01*
X381625Y538779D01*
Y540609D01*
X382073Y541057D01*
Y542887D01*
X381625Y543335D01*
Y545165D01*
X382073Y545613D01*
Y547443D01*
X381625Y547891D01*
Y549721D01*
X382073Y550169D01*
Y553099D01*
X381632Y553540D01*
Y560040D01*
X381965Y560373D01*
Y597677D01*
X381517Y598125D01*
Y599955D01*
X381965Y600403D01*
Y602233D01*
X381517Y602681D01*
Y604511D01*
X381965Y604959D01*
Y606789D01*
X379216Y609538D01*
X378583D01*
X377288Y610833D01*
Y611466D01*
X375994Y612760D01*
X375361D01*
X374066Y614055D01*
Y614688D01*
X372772Y615982D01*
X369853D01*
X369477Y615606D01*
X367647D01*
X367271Y615982D01*
X364360D01*
X363272Y614894D01*
Y613535D01*
X364565Y612242D01*
G01X364265Y585714D02*
X363370Y586609D01*
Y588178D01*
X364592Y589400D01*
X366656D01*
X367104Y588952D01*
X368934D01*
X369382Y589400D01*
X372061D01*
X374032Y587429D01*
Y585129D01*
X373584Y584681D01*
Y582851D01*
X374032Y582403D01*
Y580573D01*
X373584Y580125D01*
Y578295D01*
X374032Y577847D01*
Y572360D01*
X375732Y570660D01*
Y568830D01*
X375284Y568382D01*
Y566552D01*
X375732Y566104D01*
Y561273D01*
X375284Y560825D01*
Y558995D01*
X375732Y558547D01*
Y556717D01*
X375284Y556269D01*
Y554439D01*
X375732Y553991D01*
Y549639D01*
X373785Y547692D01*
Y529569D01*
X373337Y529121D01*
Y527291D01*
X373785Y526843D01*
Y525013D01*
X372332Y523560D01*
Y510223D01*
X371884Y509775D01*
Y507945D01*
X372332Y507497D01*
Y505667D01*
X371884Y505219D01*
Y503389D01*
X372332Y502941D01*
Y501111D01*
X369212Y497991D01*
Y407891D01*
X368087Y406766D01*
Y401923D01*
G01X372472Y401501D02*
Y404948D01*
X373572Y406048D01*
Y495808D01*
X377760Y499996D01*
Y510444D01*
X379659Y512343D01*
Y595903D01*
X377769Y597793D01*
X367525D01*
X366913Y598405D01*
Y600397D01*
X367525Y601009D01*
X374604D01*
X376286Y602691D01*
Y607117D01*
X374474Y608929D01*
X363863D01*
X362318Y607384D01*
Y605714D01*
X361218Y604614D01*
G01X365776Y401397D02*
Y407652D01*
X366972Y408848D01*
Y499048D01*
X369792Y501868D01*
Y511377D01*
X370133Y511718D01*
Y513548D01*
X369792Y513889D01*
Y515808D01*
X370240Y516256D01*
Y518086D01*
X369792Y518534D01*
Y520364D01*
X370240Y520812D01*
Y522642D01*
X369792Y523090D01*
Y524920D01*
X371072Y526200D01*
Y530236D01*
X371520Y530684D01*
Y532514D01*
X371072Y532962D01*
Y534792D01*
X371520Y535240D01*
Y537070D01*
X371072Y537518D01*
Y539348D01*
X371520Y539796D01*
Y541626D01*
X371072Y542074D01*
Y543904D01*
X371520Y544352D01*
Y546182D01*
X371072Y546630D01*
Y548460D01*
X372992Y550380D01*
Y558300D01*
X371072Y560220D01*
Y564199D01*
X371520Y564647D01*
Y566477D01*
X371072Y566925D01*
Y568809D01*
X371466Y569203D01*
Y571033D01*
X371072Y571427D01*
Y575053D01*
X368668Y577457D01*
Y577894D01*
X367373Y579189D01*
X366936D01*
X364953Y581172D01*
X361462D01*
X359813Y582821D01*
Y596658D01*
X360313Y597158D01*
X361612D01*
X363097Y595673D01*
Y594775D01*
X361964Y593642D01*
G01X375872Y401579D02*
Y403648D01*
X377072Y404848D01*
Y494448D01*
X381665Y499041D01*
Y508653D01*
X383133Y510121D01*
Y553539D01*
X382692Y553980D01*
Y559600D01*
X383025Y559933D01*
Y607229D01*
X373212Y617042D01*
X363920D01*
X362212Y615334D01*
Y613236D01*
X361218Y612242D01*
G01X369147Y401923D02*
Y406326D01*
X370269Y407448D01*
X370271D01*
X370272Y407449D01*
Y497551D01*
X373392Y500671D01*
Y523120D01*
X374845Y524573D01*
Y547252D01*
X376792Y549199D01*
Y571100D01*
X375092Y572800D01*
Y587869D01*
X372501Y590460D01*
X364152D01*
X362310Y588618D01*
Y586506D01*
X361518Y585714D01*
G01X387192Y405200D02*
Y485434D01*
X393505Y491747D01*
Y492879D01*
X392380Y494004D01*
Y495148D01*
X393610Y496378D01*
X394532D01*
X395769Y495141D01*
X396873D01*
X397692Y495960D01*
Y500400D01*
X406514Y509222D01*
Y511778D01*
X406153Y512139D01*
Y513861D01*
X406487Y514195D01*
Y516705D01*
X405792Y517400D01*
Y525800D01*
X406341Y526349D01*
Y533049D01*
X406355Y533063D01*
Y551863D01*
X406371Y551879D01*
Y558079D01*
X406345Y558105D01*
Y570653D01*
X406356Y570664D01*
Y579540D01*
X409793Y582977D01*
Y588867D01*
X413143Y592217D01*
Y595417D01*
X413892Y596166D01*
Y606423D01*
X414761Y607292D01*
G01X397292Y406829D02*
Y481389D01*
X422792Y506889D01*
Y511100D01*
X423317Y511625D01*
Y514075D01*
X423034Y514358D01*
Y516942D01*
X423692Y517600D01*
Y525900D01*
X423061Y526531D01*
Y530469D01*
X423090Y530498D01*
Y549098D01*
X423149Y549157D01*
Y564943D01*
X423061Y565031D01*
Y568269D01*
X423076Y568284D01*
Y577384D01*
X426528Y580836D01*
Y589536D01*
X429878Y592886D01*
Y602883D01*
X431494Y604499D01*
G01X399676Y367060D02*
X401192Y368576D01*
Y369700D01*
X401792Y370300D01*
Y371600D01*
X401192Y372200D01*
Y373600D01*
X401692Y374100D01*
Y375600D01*
X401192Y376100D01*
Y377600D01*
X401592Y378000D01*
Y379600D01*
X401192Y380000D01*
Y381400D01*
X404992Y385200D01*
Y401000D01*
X404392Y401600D01*
Y403000D01*
X405392Y404000D01*
Y474087D01*
X419781Y488476D01*
Y492489D01*
X436292Y509000D01*
Y511500D01*
X436650Y511858D01*
Y513842D01*
X436409Y514083D01*
Y516917D01*
X436891Y517399D01*
Y526301D01*
X436474Y526718D01*
Y529782D01*
X436548Y529856D01*
Y558944D01*
X436462Y559030D01*
Y573570D01*
X436519Y573627D01*
Y576527D01*
X439825Y579833D01*
Y587067D01*
X441675Y588917D01*
Y591283D01*
X443249Y592857D01*
Y602983D01*
X444880Y604614D01*
G01X399676Y363160D02*
X400842Y364326D01*
Y365550D01*
X402392Y367100D01*
X404192D01*
X408892Y371800D01*
Y379200D01*
X410292Y380600D01*
X411792D01*
X412885Y381693D01*
Y405453D01*
X411392Y406946D01*
Y471600D01*
X446743Y506951D01*
Y511049D01*
X445966Y511826D01*
Y513774D01*
X446892Y514700D01*
Y517200D01*
X446485Y517607D01*
Y533293D01*
X446692Y533500D01*
Y548700D01*
X446502Y548890D01*
Y568090D01*
X446207Y568385D01*
Y570815D01*
X446510Y571118D01*
Y576318D01*
X446745Y576553D01*
Y586547D01*
X445792Y587500D01*
Y589000D01*
X446792Y590000D01*
Y602600D01*
X447092Y602900D01*
Y605100D01*
X444880Y607312D01*
Y609864D01*
G01X389192Y405821D02*
Y484605D01*
X399692Y495105D01*
Y499571D01*
X409292Y509171D01*
Y511000D01*
X410292Y512000D01*
Y513600D01*
X409492Y514400D01*
Y516200D01*
X409808Y516516D01*
Y530616D01*
X409992Y530800D01*
Y534176D01*
X409793Y534375D01*
Y538959D01*
X410192Y539358D01*
Y545300D01*
X409793Y545699D01*
Y549301D01*
X409892Y549400D01*
Y553199D01*
X409706Y553385D01*
Y563882D01*
X409808Y563984D01*
Y568516D01*
X410045Y568753D01*
Y573727D01*
X409780Y573992D01*
Y579690D01*
X413099Y583009D01*
Y588857D01*
X414763Y590521D01*
Y593657D01*
G01X431494Y593642D02*
Y590964D01*
X430792Y590262D01*
Y588000D01*
X429777Y586985D01*
Y580385D01*
X426528Y577136D01*
Y558636D01*
X426440Y558548D01*
Y552048D01*
X426514Y551974D01*
Y530278D01*
X426544Y530248D01*
Y521552D01*
X426092Y521100D01*
Y517200D01*
X426692Y516600D01*
Y514500D01*
X425992Y513800D01*
Y512000D01*
X426692Y511300D01*
Y507960D01*
X412810Y494078D01*
Y493092D01*
X413781Y492121D01*
Y490989D01*
X412533Y489741D01*
X411635D01*
X410281Y491095D01*
X409412D01*
X408024Y489707D01*
Y488826D01*
X409255Y487595D01*
Y486463D01*
X408055Y485263D01*
X407061D01*
X405797Y486527D01*
X404741D01*
X403461Y485247D01*
Y484337D01*
X404776Y483022D01*
Y481930D01*
X403587Y480741D01*
X402531D01*
X401588Y481684D01*
X400436D01*
X399293Y480541D01*
Y476475D01*
X399292Y476474D01*
Y407111D01*
G01X444880Y593659D02*
Y590964D01*
X443792Y589876D01*
Y587500D01*
X443248Y586956D01*
Y580056D01*
X439810Y576618D01*
Y557436D01*
X439819Y557427D01*
Y552127D01*
X439810Y552118D01*
Y527918D01*
X439592Y527700D01*
Y517000D01*
X439992Y516600D01*
Y514600D01*
X439192Y513800D01*
Y512000D01*
X439987Y511205D01*
Y509367D01*
X438954Y508334D01*
X438455D01*
X421781Y491660D01*
Y487647D01*
X407392Y473258D01*
Y405300D01*
X408492Y404200D01*
Y397100D01*
X406992Y395600D01*
Y384300D01*
X404992Y382300D01*
Y374845D01*
X403056Y372909D01*
G01Y369010D02*
X406892Y372846D01*
Y381100D01*
X409092Y383300D01*
Y394910D01*
X410492Y396310D01*
Y405016D01*
X409392Y406116D01*
Y472429D01*
X423781Y486818D01*
Y490831D01*
X427110Y494160D01*
X427972D01*
X428905Y493227D01*
X429767D01*
X430751Y494211D01*
Y495073D01*
X429818Y496006D01*
Y496868D01*
X439317Y506367D01*
X440205D01*
X442992Y509154D01*
Y511300D01*
X443692Y512000D01*
Y513900D01*
X442792Y514800D01*
Y516200D01*
X443692Y517100D01*
Y526100D01*
X443248Y526544D01*
Y576656D01*
X444880Y578288D01*
Y585722D01*
G01X381192Y405204D02*
Y492741D01*
X396092Y507641D01*
Y510912D01*
X396543Y511363D01*
Y513949D01*
X396140Y514352D01*
Y516348D01*
X396307Y516515D01*
Y529791D01*
X396321Y529805D01*
Y546071D01*
X396192Y546200D01*
Y549300D01*
X396409Y549517D01*
Y563763D01*
X396194Y563978D01*
Y568002D01*
X396497Y568305D01*
Y570895D01*
X396306Y571086D01*
Y587014D01*
X398029Y588737D01*
Y593642D01*
G01X391258Y405606D02*
Y483842D01*
X402938Y495522D01*
Y496654D01*
X402085Y497507D01*
Y498665D01*
X403216Y499796D01*
X404322D01*
X405174Y498944D01*
X406319D01*
X407092Y499717D01*
Y503244D01*
X413153Y509305D01*
Y511339D01*
X412914Y511578D01*
Y513922D01*
X413273Y514281D01*
Y516319D01*
X412977Y516615D01*
Y519385D01*
X414126Y520534D01*
Y526266D01*
X413041Y527351D01*
Y539449D01*
X413129Y539537D01*
Y551637D01*
X413143Y551651D01*
Y557704D01*
X413949Y558510D01*
X414883D01*
X415517Y559144D01*
Y561058D01*
X414865Y561710D01*
X413861D01*
X413100Y562471D01*
Y570448D01*
X413070Y570478D01*
Y579466D01*
X414500Y580896D01*
X416697D01*
X417281Y581480D01*
Y582870D01*
X416645Y583506D01*
X415373D01*
X414763Y584116D01*
Y585722D01*
G01X385192Y405100D02*
Y486263D01*
X390760Y491831D01*
Y496651D01*
X402792Y508683D01*
Y511100D01*
X403592Y511900D01*
Y513700D01*
X402792Y514500D01*
Y516600D01*
X403192Y517000D01*
Y520400D01*
X403050Y520542D01*
Y530158D01*
X403192Y530300D01*
Y532700D01*
X403021Y532871D01*
Y549229D01*
X403109Y549317D01*
Y557765D01*
X403392Y558048D01*
Y563500D01*
X403079Y563813D01*
Y570613D01*
X403035Y570657D01*
Y579575D01*
X406341Y582881D01*
Y591914D01*
X408069Y593642D01*
G01X393292Y405741D02*
Y483047D01*
X409092Y498847D01*
Y502415D01*
X415342Y508665D01*
Y510686D01*
X416651Y511995D01*
Y513841D01*
X416092Y514400D01*
Y516300D01*
X417392Y517600D01*
Y526200D01*
X416391Y527201D01*
Y549199D01*
X416376Y549214D01*
Y556598D01*
X417492Y557714D01*
Y563700D01*
X416391Y564801D01*
Y577999D01*
X419792Y581400D01*
Y586348D01*
X423149Y589705D01*
Y595860D01*
X424801Y597512D01*
Y604614D01*
G01X438187D02*
X436577Y603004D01*
Y590249D01*
X433228Y586900D01*
Y580136D01*
X429769Y576677D01*
Y559429D01*
X429863Y559335D01*
Y554571D01*
X429761Y554469D01*
Y527731D01*
X430192Y527300D01*
Y517100D01*
X429309Y516217D01*
Y514483D01*
X430278Y513514D01*
Y511886D01*
X429392Y511000D01*
Y507830D01*
X415781Y494219D01*
Y490134D01*
X401292Y475645D01*
Y407111D01*
G01X395292Y406265D02*
Y482218D01*
X411933Y498859D01*
Y499991D01*
X411474Y500450D01*
Y501582D01*
X412605Y502713D01*
X413737D01*
X414196Y502254D01*
X415328D01*
X416459Y503385D01*
Y504517D01*
X416000Y504976D01*
Y506108D01*
X417131Y507239D01*
X418263D01*
X418722Y506780D01*
X419854D01*
X420971Y507897D01*
Y510121D01*
X419392Y511700D01*
Y513332D01*
X420381Y514321D01*
Y516011D01*
X419492Y516900D01*
Y520200D01*
X419828Y520536D01*
Y530064D01*
X419300Y530592D01*
Y535164D01*
X419814Y535678D01*
Y549478D01*
X419300Y549992D01*
Y554276D01*
X419843Y554819D01*
Y567949D01*
X419292Y568500D01*
Y573026D01*
X419829Y573563D01*
Y577637D01*
X423075Y580883D01*
Y586883D01*
X424801Y588609D01*
Y593642D01*
G01X438187Y593659D02*
Y588495D01*
X436519Y586827D01*
Y580227D01*
X433214Y576922D01*
Y573530D01*
X431742Y572058D01*
Y569022D01*
X433215Y567549D01*
Y562323D01*
X433125Y562233D01*
Y554467D01*
X431773Y553115D01*
Y550419D01*
X433214Y548978D01*
Y535678D01*
X431670Y534134D01*
Y532098D01*
X433213Y530555D01*
Y520621D01*
X432992Y520400D01*
Y517000D01*
X433392Y516600D01*
Y514700D01*
X432892Y514200D01*
Y511700D01*
X433292Y511300D01*
Y508900D01*
X417781Y493389D01*
Y489305D01*
X403292Y474816D01*
Y405300D01*
X402192Y404200D01*
Y402300D01*
X401092Y401200D01*
Y391800D01*
X401692Y391200D01*
Y389700D01*
X401026Y389034D01*
Y387966D01*
X401592Y387400D01*
Y385800D01*
X400292Y384500D01*
X398892D01*
X397692Y383300D01*
Y381900D01*
X398192Y381400D01*
Y380000D01*
X397692Y379500D01*
Y378100D01*
X398192Y377600D01*
Y376100D01*
X397792Y375700D01*
Y374100D01*
X398192Y373700D01*
Y372100D01*
X397792Y371700D01*
Y370200D01*
X398192Y369800D01*
Y368200D01*
X397658Y367666D01*
Y366534D01*
X398192Y366000D01*
Y364400D01*
X396296Y362504D01*
Y361209D01*
G01X379192Y405271D02*
Y493570D01*
X392792Y507170D01*
Y586502D01*
X394682Y588392D01*
G01X414763Y585722D02*
X416398Y587357D01*
Y597094D01*
X416308Y597184D01*
Y605516D01*
X416561Y605769D01*
Y608261D01*
X414761Y610061D01*
Y612657D01*
G01X404723Y593657D02*
X404143Y594237D01*
Y603920D01*
X404722Y604499D01*
G01X398029Y593642D02*
X398531Y594144D01*
Y603997D01*
X398029Y604499D01*
G01X408069Y593642D02*
Y595848D01*
X407569Y596348D01*
X406535D01*
X405818Y597065D01*
Y598971D01*
X406554Y599707D01*
X411361D01*
X412116Y600462D01*
Y601950D01*
X411471Y602595D01*
X407666D01*
X406774Y603487D01*
Y605998D01*
X408068Y607292D01*
G01X394682Y588392D02*
Y595722D01*
X396057Y597097D01*
Y606065D01*
X396409Y606417D01*
Y608283D01*
X394682Y610010D01*
Y612657D01*
G01X458266Y92757D02*
X457145Y91636D01*
Y88700D01*
X460045Y85800D01*
Y83832D01*
X458512Y82299D01*
Y81100D01*
X459762Y79850D01*
Y78950D01*
X458412Y77600D01*
Y76301D01*
X460045Y74668D01*
Y72367D01*
X460912Y71500D01*
G01Y87714D02*
X462385Y86241D01*
Y73116D01*
X463001Y72500D01*
Y71156D01*
X461545Y69700D01*
X460145D01*
X458266Y67821D01*
Y65699D01*
G01X451573Y92757D02*
X450645Y91829D01*
Y88701D01*
X453445Y85901D01*
Y84032D01*
X452062Y82649D01*
Y81250D01*
X453512Y79800D01*
Y78600D01*
X452012Y77100D01*
Y75901D01*
X453445Y74468D01*
Y72588D01*
X454533Y71500D01*
G01X454619Y87714D02*
X455845Y86488D01*
Y73475D01*
X456620Y72700D01*
Y71076D01*
X455044Y69500D01*
X453820D01*
X451573Y67253D01*
Y65699D01*
G01X474998Y92757D02*
X474070Y91829D01*
Y88701D01*
X477112Y85659D01*
Y84274D01*
X475437Y82599D01*
Y81476D01*
X476937Y79976D01*
Y78624D01*
X475437Y77124D01*
Y75901D01*
X476870Y74468D01*
Y73374D01*
X478344Y71900D01*
G01Y87714D02*
X479733Y86325D01*
Y73312D01*
X480345Y72700D01*
Y71300D01*
X478545Y69500D01*
X477545D01*
X474998Y66953D01*
Y65699D01*
G01X464732Y89900D02*
X467838Y86794D01*
Y70648D01*
X466510Y69320D01*
X465528D01*
X464758Y68550D01*
G01X469832Y87514D02*
Y87515D01*
X470930D01*
X471964Y86481D01*
Y83706D01*
X471258Y83000D01*
X470744D01*
X470044Y82300D01*
Y81300D01*
X470744Y80600D01*
X471244D01*
X471964Y79880D01*
Y78507D01*
X471157Y77700D01*
X470459D01*
X469858Y77099D01*
Y75901D01*
X470459Y75300D01*
X471257D01*
X471964Y74593D01*
Y71972D01*
X470941Y70949D01*
X469832D01*
G01X464732Y87300D02*
X465831D01*
X466778Y86353D01*
Y83820D01*
X465808Y82850D01*
X465460D01*
X464844Y82234D01*
Y80902D01*
X465346Y80400D01*
X466058D01*
X466778Y79680D01*
Y78720D01*
X465958Y77900D01*
X465458D01*
X464858Y77300D01*
Y76300D01*
X466778Y74380D01*
Y71091D01*
X466067Y70380D01*
X465551D01*
X464732Y71199D01*
G01X469832Y90114D02*
X473024Y86922D01*
Y71532D01*
X469832Y68340D01*
G01X424692Y185300D02*
Y131800D01*
X430205Y126287D01*
X431067D01*
X432505Y127725D01*
X433367D01*
X434351Y126741D01*
Y125879D01*
X432913Y124441D01*
Y123579D01*
X433897Y122595D01*
X434759D01*
X436197Y124033D01*
X437059D01*
X438043Y123049D01*
Y122187D01*
X436605Y120749D01*
Y119887D01*
X437589Y118903D01*
X438451D01*
X439889Y120341D01*
X440751D01*
X441735Y119357D01*
Y118495D01*
X440297Y117057D01*
Y116195D01*
X454792Y101700D01*
X479528D01*
X483071Y98157D01*
X484062D01*
X485745Y96474D01*
X494118D01*
X495077Y95515D01*
Y92757D01*
G01X426592Y184999D02*
Y140800D01*
X451056Y116336D01*
Y115136D01*
X452564Y113628D01*
X453764D01*
X458440Y108952D01*
Y108090D01*
X457052Y106702D01*
Y105840D01*
X458036Y104856D01*
X458898D01*
X460286Y106244D01*
X461148D01*
X462492Y104900D01*
X479865D01*
X486465Y98300D01*
X495792D01*
X497066Y97026D01*
Y92174D01*
X495816Y90924D01*
Y89621D01*
X497723Y87714D01*
G01X440092Y186600D02*
Y157500D01*
X474392Y123200D01*
X507329D01*
X516517Y114012D01*
Y111423D01*
X517292Y110648D01*
Y107584D01*
X518676Y106200D01*
X519292D01*
X520366Y105126D01*
Y96874D01*
X519692Y96200D01*
X517892D01*
X517292Y95600D01*
Y93967D01*
X518502Y92757D01*
G01X441992Y187097D02*
Y159800D01*
X475792Y126000D01*
X508066D01*
X522992Y111074D01*
Y105300D01*
X522866Y105174D01*
Y94374D01*
X519766Y91274D01*
Y89796D01*
X521848Y87714D01*
G01X419592Y185535D02*
Y177506D01*
X418982Y176896D01*
X417802D01*
X417192Y176286D01*
Y174896D01*
X417802Y174286D01*
X418982D01*
X419592Y173676D01*
Y172286D01*
X418982Y171676D01*
X417802D01*
X417192Y171066D01*
Y169676D01*
X417802Y169066D01*
X418982D01*
X419592Y168456D01*
Y167066D01*
X418982Y166456D01*
X417802D01*
X417192Y165846D01*
Y164456D01*
X417802Y163846D01*
X418982D01*
X419592Y163236D01*
Y161846D01*
X418982Y161236D01*
X417802D01*
X417192Y160626D01*
Y159236D01*
X417802Y158626D01*
X418982D01*
X419592Y158016D01*
Y156626D01*
X418982Y156016D01*
X417802D01*
X417192Y155406D01*
Y133299D01*
X454691Y95800D01*
X478356D01*
X479599Y94557D01*
X482570D01*
X484353Y92774D01*
X488367D01*
X488384Y92757D01*
G01X421692Y184700D02*
Y131700D01*
X455292Y98100D01*
X459291D01*
X460191Y99000D01*
X462601D01*
X463501Y98100D01*
X465191D01*
X466791Y99700D01*
X468193D01*
X469793Y98100D01*
X471191D01*
X472791Y99700D01*
X474593D01*
X476193Y98100D01*
X479592D01*
X481335Y96357D01*
X483316D01*
X484999Y94674D01*
X491166D01*
X491666Y94174D01*
Y93324D01*
X489580Y91238D01*
Y89564D01*
X491430Y87714D01*
G01X436292Y185900D02*
Y149399D01*
X437781Y147910D01*
X439582D01*
X442492Y145000D01*
Y143199D01*
X467391Y118300D01*
X505156D01*
X509892Y113564D01*
Y112500D01*
X508592Y111200D01*
Y110047D01*
X509292Y109347D01*
X509892D01*
X510692Y108547D01*
Y106947D01*
X509892Y106147D01*
X509292D01*
X508592Y105447D01*
Y103400D01*
X509092Y102900D01*
X510892D01*
X512392Y101400D01*
Y100500D01*
X511748Y99856D01*
X509700D01*
X508800Y98956D01*
Y97356D01*
X509600Y96556D01*
X511937D01*
X512492Y96001D01*
Y93444D01*
X511809Y92761D01*
Y92757D01*
G01X438192Y186200D02*
Y155300D01*
X472792Y120700D01*
X506292D01*
X513854Y113138D01*
Y111262D01*
X512784Y110192D01*
Y106454D01*
X514692Y104546D01*
Y92700D01*
X513292Y91300D01*
Y89577D01*
X515155Y87714D01*
G01X452318Y188936D02*
Y163575D01*
X453778Y162115D01*
X454640D01*
X455576Y163052D01*
X456438D01*
X457422Y162068D01*
Y161206D01*
X456486Y160269D01*
Y159407D01*
X457470Y158423D01*
X458332D01*
X459268Y159360D01*
X460130D01*
X461114Y158376D01*
Y157514D01*
X460178Y156577D01*
Y155715D01*
X461162Y154731D01*
X462024D01*
X462960Y155668D01*
X463822D01*
X464806Y154684D01*
Y153822D01*
X463870Y152885D01*
Y152023D01*
X464854Y151039D01*
X465716D01*
X466652Y151976D01*
X467514D01*
X468498Y150992D01*
Y150130D01*
X467577Y149209D01*
Y148416D01*
X468630Y147363D01*
X469423D01*
X470344Y148284D01*
X471206D01*
X484890Y134600D01*
X513492D01*
X533792Y114300D01*
Y111700D01*
X532566Y110474D01*
Y106074D01*
X533566Y105074D01*
Y103238D01*
X531888Y101560D01*
Y92757D01*
G01X454868Y188936D02*
Y168824D01*
X485792Y137900D01*
X503692D01*
X504892Y136700D01*
X510392D01*
X511592Y137900D01*
X513592D01*
X536466Y115026D01*
Y102738D01*
X534066Y100338D01*
Y92474D01*
X532566Y90974D01*
Y89682D01*
X534534Y87714D01*
G01X447218Y193436D02*
X445092Y191310D01*
Y187911D01*
X445702Y187301D01*
X446982D01*
X447592Y186691D01*
Y185301D01*
X446982Y184691D01*
X445702D01*
X445092Y184081D01*
Y182691D01*
X445702Y182081D01*
X446982D01*
X447592Y181471D01*
Y180081D01*
X446982Y179471D01*
X445702D01*
X445092Y178861D01*
Y177471D01*
X445702Y176861D01*
X446982D01*
X447592Y176251D01*
Y173646D01*
X447032Y173086D01*
X445552D01*
X444992Y172526D01*
Y171086D01*
X445552Y170526D01*
X447032D01*
X447592Y169966D01*
Y162301D01*
X480793Y129100D01*
X511392D01*
X527566Y112926D01*
Y111974D01*
X526366Y110774D01*
Y106274D01*
X527266Y105374D01*
Y103238D01*
X525784Y101756D01*
Y94656D01*
X525195Y94067D01*
Y92757D01*
G01X449768Y193436D02*
X449592Y193260D01*
Y163301D01*
X469342Y143551D01*
X472942D01*
X483993Y132500D01*
X511091D01*
X530066Y113525D01*
Y105674D01*
X529866Y105474D01*
Y100468D01*
X529066Y99668D01*
X528684D01*
X527884Y98868D01*
Y97268D01*
X528684Y96468D01*
X529066D01*
X529866Y95668D01*
Y94724D01*
X529098Y93956D01*
X528084D01*
X527491Y93363D01*
Y92199D01*
X526266Y90974D01*
Y89689D01*
X528241Y87714D01*
G01X430457Y185287D02*
Y183900D01*
X429692Y183135D01*
Y182050D01*
X430142Y181600D01*
Y180600D01*
X429692Y180150D01*
Y179150D01*
X430142Y178700D01*
Y177700D01*
X429692Y177250D01*
Y176250D01*
X430142Y175800D01*
Y174800D01*
X429692Y174350D01*
Y173350D01*
X430142Y172900D01*
Y171900D01*
X429692Y171450D01*
Y170450D01*
X430142Y170000D01*
Y169000D01*
X429692Y168550D01*
Y167550D01*
X430142Y167100D01*
Y166100D01*
X429692Y165650D01*
Y164650D01*
X430142Y164200D01*
Y163200D01*
X429692Y162750D01*
Y161752D01*
X430142Y161302D01*
Y160300D01*
X429692Y159850D01*
Y158850D01*
X430142Y158400D01*
Y157400D01*
X429692Y156950D01*
Y155550D01*
X430142Y155100D01*
Y154100D01*
X429692Y153650D01*
Y152550D01*
X430142Y152100D01*
Y151100D01*
X429692Y150650D01*
Y142400D01*
X431610Y140482D01*
X432472D01*
X433421Y141431D01*
X435161D01*
X436769Y139823D01*
Y138083D01*
X435820Y137134D01*
Y136272D01*
X436804Y135288D01*
X437666D01*
X438615Y136237D01*
X440355D01*
X441963Y134629D01*
Y132889D01*
X441014Y131940D01*
Y131078D01*
X443362Y128730D01*
X444224D01*
X444923Y129429D01*
X446663D01*
X448271Y127821D01*
Y126081D01*
X447572Y125382D01*
Y124520D01*
X448556Y123536D01*
X449418D01*
X450117Y124235D01*
X451857D01*
X453465Y122627D01*
Y120887D01*
X452766Y120188D01*
Y119326D01*
X462432Y109660D01*
X466092D01*
X467132Y110700D01*
X474152D01*
X475192Y109660D01*
X480133D01*
X481770Y108023D01*
X482407D01*
X483115Y107315D01*
Y106678D01*
X487433Y102360D01*
X489942D01*
X490392Y102810D01*
X491392D01*
X491842Y102360D01*
X497900D01*
X500630Y99630D01*
Y97800D01*
X501080Y97350D01*
Y96350D01*
X500630Y95900D01*
Y94900D01*
X501030Y94500D01*
X501932D01*
X503270Y93162D01*
Y91626D01*
X501544Y89900D01*
G01X458502Y189726D02*
Y188726D01*
X458952Y188276D01*
Y187276D01*
X458502Y186826D01*
Y185650D01*
X458952Y185200D01*
Y184200D01*
X458502Y183750D01*
Y182750D01*
X458952Y182300D01*
Y181300D01*
X458502Y180850D01*
Y179850D01*
X458952Y179400D01*
Y178400D01*
X458502Y177950D01*
Y176650D01*
X458952Y176200D01*
Y175200D01*
X458502Y174750D01*
Y171390D01*
X459209Y170683D01*
X459845D01*
X460553Y169975D01*
Y169339D01*
X461370Y168522D01*
X462006D01*
X462714Y167814D01*
Y167178D01*
X463520Y166372D01*
X464156D01*
X464864Y165664D01*
Y165028D01*
X465571Y164321D01*
X466207D01*
X466915Y163613D01*
Y162977D01*
X467920Y161972D01*
X468556D01*
X469264Y161264D01*
Y160628D01*
X470320Y159572D01*
X470956D01*
X471664Y158864D01*
Y158228D01*
X488032Y141860D01*
X520833D01*
X523703Y138990D01*
Y137248D01*
X522926Y136471D01*
Y135767D01*
X524070Y134623D01*
X524774D01*
X525551Y135400D01*
X527293D01*
X528897Y133796D01*
Y132054D01*
X528070Y131227D01*
Y130523D01*
X529214Y129379D01*
X529918D01*
X530745Y130206D01*
X532487D01*
X534091Y128602D01*
Y126860D01*
X533114Y125883D01*
Y125179D01*
X534258Y124035D01*
X538658D01*
X541446Y121247D01*
Y118420D01*
X542066Y117800D01*
Y116800D01*
X541446Y116180D01*
Y104093D01*
X542066Y103473D01*
Y102473D01*
X541446Y101853D01*
Y101021D01*
X537561Y97136D01*
Y95220D01*
X538281Y94500D01*
X539281D01*
X540081Y93700D01*
Y91626D01*
X538355Y89900D01*
G01X432555Y185287D02*
Y147936D01*
X465291Y115200D01*
X502221D01*
X503512Y113909D01*
Y98612D01*
X504890Y97234D01*
Y89268D01*
X506644Y87514D01*
G01X462373Y190613D02*
Y171820D01*
X489593Y144600D01*
X521692D01*
X545486Y120806D01*
Y100761D01*
X541701Y96976D01*
Y89268D01*
X543230Y87738D01*
X543455Y87514D01*
G01X429397Y185287D02*
Y184340D01*
X428632Y183575D01*
Y141960D01*
X431170Y139422D01*
X432912D01*
X433861Y140371D01*
X434721D01*
X435709Y139383D01*
Y138523D01*
X434760Y137574D01*
Y135832D01*
X436364Y134228D01*
X438106D01*
X439055Y135177D01*
X439915D01*
X440903Y134189D01*
Y133329D01*
X439954Y132380D01*
Y130638D01*
X442922Y127670D01*
X444664D01*
X445363Y128369D01*
X446223D01*
X447211Y127381D01*
Y126521D01*
X446512Y125822D01*
Y124080D01*
X448116Y122476D01*
X449858D01*
X450557Y123175D01*
X451417D01*
X452405Y122187D01*
Y121327D01*
X451706Y120628D01*
Y118886D01*
X461992Y108600D01*
X466532D01*
X467572Y109640D01*
X473712D01*
X474752Y108600D01*
X479693D01*
X486993Y101300D01*
X497460D01*
X499570Y99190D01*
Y89274D01*
X501544Y87300D01*
G01X457442Y189726D02*
Y170950D01*
X487592Y140800D01*
X520393D01*
X522643Y138550D01*
Y137688D01*
X521866Y136911D01*
Y135327D01*
X523630Y133563D01*
X525214D01*
X525991Y134340D01*
X526853D01*
X527837Y133356D01*
Y132494D01*
X527010Y131667D01*
Y130083D01*
X528774Y128319D01*
X530358D01*
X531185Y129146D01*
X532047D01*
X533031Y128162D01*
Y127300D01*
X532054Y126323D01*
Y124739D01*
X533818Y122975D01*
X538218D01*
X540386Y120807D01*
Y101464D01*
X536501Y97579D01*
Y89154D01*
X538174Y87482D01*
X538355Y87300D01*
G01X433615Y185287D02*
Y148376D01*
X465731Y116260D01*
X502661D01*
X504572Y114349D01*
Y102220D01*
X505192Y101600D01*
Y100600D01*
X504572Y99980D01*
Y99052D01*
X505950Y97674D01*
Y95542D01*
X506792Y94700D01*
X507993D01*
X508692Y94001D01*
Y92162D01*
X506644Y90114D01*
G01X471108Y193596D02*
Y174283D01*
X493391Y152000D01*
X532448D01*
X549564Y134884D01*
Y133527D01*
X550732Y132359D01*
X551524D01*
X551647Y132482D01*
X552508D01*
X553492Y131498D01*
Y130636D01*
X552455Y129598D01*
Y128736D01*
X554666Y126525D01*
Y116274D01*
X557166Y113774D01*
Y111374D01*
X556666Y110874D01*
Y106174D01*
X558284Y104556D01*
Y102556D01*
X557584Y101856D01*
X556284D01*
X555484Y101056D01*
Y99856D01*
X556084Y99256D01*
X557484D01*
X558284Y98456D01*
Y97556D01*
X557184Y96456D01*
X555748D01*
X555313Y96021D01*
Y92757D01*
G01X473658Y193596D02*
Y175133D01*
X494591Y154200D01*
X534492D01*
X557384Y131308D01*
Y117218D01*
X560566Y114036D01*
Y95339D01*
X556892Y91665D01*
Y89481D01*
X558659Y87714D01*
G01X466008Y190596D02*
Y173484D01*
X491592Y147900D01*
X522891D01*
X525303Y145488D01*
X526165D01*
X527152Y146476D01*
X528014D01*
X528998Y145492D01*
Y144630D01*
X528011Y143642D01*
Y142780D01*
X528995Y141796D01*
X529857D01*
X530844Y142784D01*
X531706D01*
X532690Y141800D01*
Y140938D01*
X531703Y139950D01*
Y139088D01*
X532687Y138104D01*
X533549D01*
X534522Y139077D01*
X535315D01*
X536368Y138024D01*
Y137231D01*
X535395Y136258D01*
Y135396D01*
X536379Y134412D01*
X539480D01*
X541192Y132700D01*
Y129599D01*
X549666Y121125D01*
Y114366D01*
X550732Y113300D01*
Y111840D01*
X550166Y111274D01*
Y105774D01*
X550420Y105520D01*
Y99529D01*
X546700Y95809D01*
Y94677D01*
X547407Y93970D01*
X548434Y92942D01*
X548620Y92757D01*
G01X468558Y190596D02*
Y173634D01*
X492292Y149900D01*
X527792D01*
X552166Y125526D01*
Y114826D01*
X553366Y113626D01*
Y111574D01*
X553766Y111174D01*
Y105474D01*
X553266Y104974D01*
Y97438D01*
X552466Y96638D01*
X551392D01*
X550592Y95838D01*
Y92100D01*
X550092Y91600D01*
Y89588D01*
X551966Y87714D01*
G01X483392Y197701D02*
X488292Y192801D01*
Y190484D01*
X488902Y189874D01*
X490482D01*
X491092Y189264D01*
Y187874D01*
X490482Y187264D01*
X488902D01*
X488292Y186654D01*
Y184881D01*
X488852Y184321D01*
X490932D01*
X491492Y183761D01*
Y182321D01*
X490932Y181761D01*
X488852D01*
X488292Y181201D01*
Y180200D01*
X489633Y178859D01*
X505634D01*
X520193Y164300D01*
X536893D01*
X562721Y138472D01*
X569566D01*
X571092Y136946D01*
Y135672D01*
X569566Y134146D01*
Y132872D01*
X571092Y131346D01*
Y130072D01*
X569566Y128546D01*
Y127272D01*
X571092Y125746D01*
Y124472D01*
X569566Y122946D01*
Y121672D01*
X571092Y120146D01*
Y118872D01*
X569566Y117346D01*
Y116072D01*
X571092Y114546D01*
Y113272D01*
X569566Y111746D01*
Y110472D01*
X571092Y108946D01*
Y107672D01*
X569566Y106146D01*
Y104872D01*
X571092Y103346D01*
Y102072D01*
X569566Y100546D01*
Y99673D01*
X567784Y97891D01*
Y93672D01*
X568699Y92757D01*
G01X484992Y198962D02*
Y198900D01*
X503148Y180744D01*
X507249D01*
X518593Y169400D01*
X522055D01*
X522665Y168790D01*
Y167510D01*
X523275Y166900D01*
X524665D01*
X525275Y167510D01*
Y168790D01*
X525885Y169400D01*
X527275D01*
X527885Y168790D01*
Y167510D01*
X528495Y166900D01*
X529885D01*
X530495Y167510D01*
Y168790D01*
X531105Y169400D01*
X536592D01*
X564692Y141300D01*
X570593D01*
X573592Y138301D01*
Y100265D01*
X570766Y97439D01*
Y92274D01*
X569366Y90874D01*
Y89693D01*
X571345Y87714D01*
G01X479692Y194501D02*
Y191157D01*
X480302Y190547D01*
X483282D01*
X483892Y189937D01*
Y188547D01*
X483282Y187937D01*
X477902D01*
X477292Y187327D01*
Y185937D01*
X477902Y185327D01*
X483082D01*
X483692Y184717D01*
Y183327D01*
X483082Y182717D01*
X480302D01*
X479692Y182107D01*
Y178101D01*
X482993Y174800D01*
X502993D01*
X519293Y158500D01*
X535392D01*
X560892Y133000D01*
Y118400D01*
X564566Y114726D01*
Y101173D01*
X563166Y99773D01*
Y93917D01*
X562006Y92757D01*
G01X481192Y196301D02*
X485892Y191601D01*
Y178401D01*
X487319Y176974D01*
X504118D01*
X519392Y161700D01*
X535992D01*
X567066Y130626D01*
Y128546D01*
X566456Y127936D01*
X564592D01*
X564092Y127436D01*
Y125826D01*
X564592Y125326D01*
X566456D01*
X567066Y124716D01*
Y123326D01*
X566456Y122716D01*
X564502D01*
X563892Y122106D01*
Y120716D01*
X564502Y120106D01*
X566456D01*
X567066Y119496D01*
Y100275D01*
X565666Y98875D01*
Y93260D01*
X565052Y92646D01*
Y87588D01*
X565266Y87374D01*
G01X487458Y200542D02*
X505371Y182629D01*
X508464D01*
X518793Y172300D01*
X522303D01*
X523533Y173530D01*
Y176530D01*
X524143Y177140D01*
X525533D01*
X526143Y176530D01*
Y173530D01*
X527373Y172300D01*
X538392D01*
X563451Y147241D01*
X574251D01*
X576392Y145100D01*
Y99700D01*
X573592Y96900D01*
Y93661D01*
X573192Y93261D01*
Y89274D01*
X575166Y87300D01*
G01X463433Y190613D02*
Y189550D01*
X463883Y189100D01*
Y188100D01*
X463433Y187650D01*
Y186150D01*
X463883Y185700D01*
Y184700D01*
X463433Y184250D01*
Y182950D01*
X463883Y182500D01*
Y181500D01*
X463433Y181050D01*
Y180050D01*
X463883Y179600D01*
Y178600D01*
X463433Y178150D01*
Y176750D01*
X463883Y176300D01*
Y175300D01*
X463433Y174850D01*
Y172260D01*
X464140Y171553D01*
X464776D01*
X465484Y170845D01*
Y170209D01*
X490033Y145660D01*
X522132D01*
X546546Y121246D01*
Y100321D01*
X542761Y96536D01*
Y95281D01*
X543442Y94600D01*
X544181D01*
X544736Y94044D01*
X545281Y93500D01*
Y91940D01*
X543455Y90114D01*
G01X426498Y417287D02*
Y457106D01*
X444385Y474993D01*
Y476125D01*
X443217Y477293D01*
Y478425D01*
X444348Y479556D01*
X445480D01*
X446648Y478388D01*
X447780D01*
X448911Y479519D01*
Y480651D01*
X447843Y481719D01*
Y482851D01*
X448974Y483982D01*
X450106D01*
X451124Y482964D01*
X452256D01*
X453387Y484095D01*
Y485227D01*
X452419Y486195D01*
Y487327D01*
X465692Y500600D01*
X476591D01*
X482505Y506514D01*
X491506D01*
X492792Y507800D01*
Y511175D01*
X493592Y511975D01*
Y517356D01*
X494393Y518157D01*
X495077D01*
G01X429048Y417287D02*
Y456056D01*
X457451Y484459D01*
Y485591D01*
X456143Y486899D01*
Y488031D01*
X457274Y489162D01*
X458406D01*
X460026Y487542D01*
X461158D01*
X462289Y488673D01*
Y489805D01*
X460735Y491359D01*
Y492491D01*
X461866Y493622D01*
X462998D01*
X464684Y491936D01*
X465816D01*
X466947Y493067D01*
Y494199D01*
X465283Y495863D01*
Y497017D01*
X466366Y498100D01*
X477891D01*
X484505Y504714D01*
X500506D01*
X501072Y505280D01*
Y506820D01*
X500492Y507400D01*
X497292D01*
X496492Y508200D01*
Y509332D01*
X497192Y510032D01*
X498392D01*
X499192Y510832D01*
Y511964D01*
X498042Y513114D01*
X497723D01*
G01X448092Y417141D02*
Y451899D01*
X476037Y479844D01*
X511735D01*
X519092Y487201D01*
Y494600D01*
X519592Y495100D01*
Y496700D01*
X520544Y497652D01*
Y499515D01*
X519744Y500315D01*
X519492D01*
X518692Y501115D01*
Y502715D01*
X519492Y503515D01*
X519744D01*
X520544Y504315D01*
Y511047D01*
X517892Y513699D01*
Y517547D01*
X518502Y518157D01*
G01X450666Y417141D02*
Y451772D01*
X451377Y452483D01*
X452239D01*
X453537Y451185D01*
X454399D01*
X455383Y452169D01*
Y453031D01*
X454085Y454329D01*
Y455191D01*
X456239Y457345D01*
X457101D01*
X457489Y456957D01*
X458350D01*
X459751Y458358D01*
Y459220D01*
X459364Y459608D01*
Y460470D01*
X460765Y461871D01*
X461627D01*
X462015Y461483D01*
X462876D01*
X464277Y462884D01*
Y463746D01*
X463890Y464134D01*
Y464996D01*
X465291Y466397D01*
X466153D01*
X466541Y466009D01*
X467402D01*
X468803Y467410D01*
Y468272D01*
X468416Y468660D01*
Y469522D01*
X469817Y470923D01*
X470679D01*
X471067Y470535D01*
X471928D01*
X473329Y471936D01*
Y472798D01*
X472942Y473186D01*
Y474048D01*
X476238Y477344D01*
X512935D01*
X522992Y487401D01*
Y491478D01*
X522792Y491678D01*
Y502000D01*
X523292Y502500D01*
Y511670D01*
X521848Y513114D01*
G01X421049Y417187D02*
Y463457D01*
X449914Y492322D01*
Y497328D01*
X457686Y505100D01*
X462436D01*
X463046Y505710D01*
Y506970D01*
X463656Y507580D01*
X465046D01*
X465656Y506970D01*
Y505710D01*
X466266Y505100D01*
X467656D01*
X468266Y505710D01*
Y507763D01*
X468898Y508395D01*
X470288D01*
X470876Y507807D01*
Y505710D01*
X471486Y505100D01*
X473914D01*
X480766Y511952D01*
X482666D01*
X483566Y511052D01*
X485844D01*
X487592Y512800D01*
Y517365D01*
X488384Y518157D01*
G01X423948Y417187D02*
Y458156D01*
X431608Y465816D01*
Y466948D01*
X429992Y468564D01*
Y469674D01*
X431123Y470805D01*
X432277D01*
X433871Y469211D01*
X435003D01*
X436141Y470349D01*
Y471481D01*
X434886Y472736D01*
Y473694D01*
X454246Y493054D01*
Y494186D01*
X452485Y495947D01*
Y497079D01*
X453616Y498210D01*
X454748D01*
X456509Y496449D01*
X457641D01*
X458772Y497580D01*
Y498712D01*
X457253Y500231D01*
Y501363D01*
X458384Y502494D01*
X459516D01*
X461035Y500975D01*
X462167D01*
X464392Y503200D01*
X475492D01*
X480606Y508314D01*
X489992D01*
X490792Y509114D01*
Y512476D01*
X491430Y513114D01*
G01X442498Y417467D02*
Y455006D01*
X472336Y484844D01*
X509536D01*
X511992Y487300D01*
Y493600D01*
X513492Y495100D01*
Y504500D01*
X513692Y504700D01*
Y511109D01*
X511144Y513657D01*
Y517492D01*
X511809Y518157D01*
G01X445428Y417407D02*
Y451925D01*
X453949Y460446D01*
Y461318D01*
X453361Y461906D01*
Y462768D01*
X454762Y464169D01*
X455624D01*
X456212Y463581D01*
X457074D01*
X458475Y464982D01*
Y465844D01*
X457887Y466432D01*
Y467294D01*
X459288Y468695D01*
X460150D01*
X460738Y468107D01*
X461600D01*
X463001Y469508D01*
Y470370D01*
X462413Y470958D01*
Y471820D01*
X463814Y473221D01*
X464676D01*
X465264Y472633D01*
X466126D01*
X467527Y474034D01*
Y474896D01*
X466939Y475484D01*
Y476346D01*
X468340Y477747D01*
X469202D01*
X469790Y477159D01*
X470652D01*
X472053Y478560D01*
Y479422D01*
X471465Y480010D01*
Y480872D01*
X472937Y482344D01*
X510635D01*
X516492Y488201D01*
Y494400D01*
X515592Y495300D01*
Y503342D01*
X516992Y504742D01*
X517792D01*
X518592Y505542D01*
Y507142D01*
X517792Y507942D01*
X516792D01*
X515992Y508742D01*
Y512314D01*
X515192Y513114D01*
X515155D01*
G01X459168Y415450D02*
Y436777D01*
X468242Y445851D01*
Y450649D01*
X485937Y468344D01*
X526352D01*
X528104Y470096D01*
Y471403D01*
X524644Y474863D01*
Y475952D01*
X532666Y483974D01*
Y496452D01*
X533792Y497578D01*
Y502744D01*
X534624Y503576D01*
Y508168D01*
X533692Y509100D01*
Y510906D01*
X531033Y513565D01*
Y517302D01*
X531888Y518157D01*
G01X461718Y415485D02*
Y436126D01*
X470392Y444800D01*
Y449100D01*
X487136Y465844D01*
X527336D01*
X538497Y477005D01*
Y478225D01*
X537366Y479356D01*
X536322D01*
X530694Y473728D01*
X529562D01*
X528431Y474859D01*
Y475991D01*
X536455Y484015D01*
Y501964D01*
X537492Y503001D01*
Y508300D01*
X536455Y509337D01*
Y510843D01*
X534534Y512764D01*
Y513114D01*
G01X477514Y420136D02*
Y429422D01*
X483792Y435700D01*
Y442931D01*
X493552Y452691D01*
X508187D01*
X515422Y445456D01*
X530947D01*
X554192Y468701D01*
Y485956D01*
X557355Y489119D01*
Y491352D01*
X556892Y491815D01*
Y497278D01*
X557113Y497499D01*
Y511379D01*
X553955Y514537D01*
Y516799D01*
X555313Y518157D01*
G01X479092Y418277D02*
X479592Y418777D01*
Y427200D01*
X487117Y434725D01*
Y443403D01*
X494476Y450762D01*
X507204D01*
X514416Y443550D01*
X518944D01*
X519554Y442940D01*
Y441550D01*
X520164Y440940D01*
X521554D01*
X522164Y441550D01*
Y442940D01*
X522774Y443550D01*
X524164D01*
X524774Y442940D01*
Y441550D01*
X525384Y440940D01*
X526774D01*
X527384Y441550D01*
Y442940D01*
X527994Y443550D01*
X532741D01*
X556692Y467501D01*
Y484920D01*
X560466Y488694D01*
Y497100D01*
X559613Y497953D01*
Y512212D01*
X558659Y513166D01*
Y513114D01*
G01X454068Y414736D02*
Y444277D01*
X468754Y458963D01*
Y460093D01*
X467885Y460961D01*
Y462091D01*
X469018Y463224D01*
X470148D01*
X471017Y462356D01*
X472147D01*
X473280Y463489D01*
Y464619D01*
X472411Y465487D01*
Y466617D01*
X473544Y467750D01*
X474674D01*
X475543Y466882D01*
X476673D01*
X477806Y468015D01*
Y469145D01*
X476937Y470013D01*
Y471143D01*
X478070Y472276D01*
X479200D01*
X480069Y471408D01*
X481199D01*
X483135Y473344D01*
X514636D01*
X525992Y484700D01*
Y491826D01*
X526292Y492126D01*
Y496979D01*
X526492Y497179D01*
Y500000D01*
X525992Y500500D01*
Y508099D01*
X527003Y509110D01*
Y511207D01*
X524735Y513475D01*
Y517697D01*
X525195Y518157D01*
G01X456618Y414706D02*
Y437920D01*
X460892Y442194D01*
Y443447D01*
X458900Y445439D01*
Y446212D01*
X460636Y447948D01*
X461542D01*
X463878Y445612D01*
X464740D01*
X466141Y447013D01*
Y447875D01*
X464329Y449687D01*
Y450937D01*
X484236Y470844D01*
X515737D01*
X517708Y472815D01*
X518839D01*
X521182Y470472D01*
X522366D01*
X523560Y471666D01*
Y472620D01*
X521101Y475079D01*
Y476207D01*
X530067Y485173D01*
Y494125D01*
X528692Y495500D01*
Y501400D01*
X527892Y502200D01*
Y504000D01*
X528463Y504571D01*
X531592D01*
X532392Y505371D01*
Y506971D01*
X531592Y507771D01*
X529792D01*
X528992Y508571D01*
Y512363D01*
X528241Y513114D01*
G01X471668Y418391D02*
Y432476D01*
X479292Y440100D01*
Y443763D01*
X491990Y456461D01*
X510755D01*
X515000Y452216D01*
X530307D01*
X549192Y471101D01*
Y494100D01*
X550192Y495100D01*
Y497389D01*
X550692Y497889D01*
Y510920D01*
X547955Y513657D01*
Y517492D01*
X548620Y518157D01*
G01X551966Y513114D02*
X552813Y512267D01*
Y506126D01*
X553422Y505517D01*
X554647D01*
X555257Y504907D01*
Y503517D01*
X554647Y502907D01*
X553502D01*
X552747Y502152D01*
Y494845D01*
X554377Y493215D01*
Y489677D01*
X551692Y486992D01*
Y469801D01*
X529351Y447460D01*
X527706D01*
X527096Y448070D01*
Y449536D01*
X526486Y450146D01*
X525096D01*
X524486Y449536D01*
Y448070D01*
X523876Y447460D01*
X522486D01*
X521876Y448070D01*
Y449536D01*
X521266Y450146D01*
X519876D01*
X519266Y449536D01*
Y448070D01*
X518656Y447460D01*
X516412D01*
X509296Y454576D01*
X492771D01*
X481392Y443197D01*
Y437600D01*
X474218Y430426D01*
Y419224D01*
G01X432703Y418187D02*
Y454479D01*
X469856Y491632D01*
X480495D01*
X484772Y495909D01*
Y498801D01*
X486560Y500589D01*
X501452D01*
X504624Y503761D01*
Y512220D01*
X501544Y515300D01*
G01X465398Y416387D02*
Y434406D01*
X473492Y442500D01*
Y446668D01*
X488977Y462153D01*
X529666D01*
X529664Y462154D01*
X541462Y473952D01*
Y512193D01*
X538355Y515300D01*
G01X438843Y418487D02*
Y444152D01*
X438233Y444762D01*
X437061D01*
X435853Y445970D01*
Y448240D01*
X437105Y449492D01*
X438233D01*
X438843Y450102D01*
Y456375D01*
X470992Y488524D01*
X478507D01*
X479127Y489144D01*
X480127D01*
X480747Y488524D01*
X481747D01*
X482367Y489144D01*
X483367D01*
X483987Y488524D01*
X484987D01*
X485607Y489144D01*
X486607D01*
X487227Y488524D01*
X488227D01*
X488847Y489144D01*
X489847D01*
X490467Y488524D01*
X491467D01*
X492087Y489144D01*
X493087D01*
X493707Y488524D01*
X497947D01*
X498567Y489144D01*
X499567D01*
X500187Y488524D01*
X501187D01*
X501807Y489144D01*
X502807D01*
X503427Y488524D01*
X504427D01*
X505047Y489144D01*
X506047D01*
X506667Y488524D01*
X507925D01*
X508964Y489563D01*
Y492740D01*
X508476Y493228D01*
Y494228D01*
X508964Y494716D01*
Y496275D01*
X508510Y496729D01*
Y497729D01*
X508964Y498183D01*
Y500443D01*
X508344Y501063D01*
Y502063D01*
X508964Y502683D01*
Y503683D01*
X508344Y504303D01*
Y505303D01*
X508964Y505923D01*
Y506923D01*
X508344Y507543D01*
Y508543D01*
X508964Y509163D01*
Y511694D01*
X507744Y512914D01*
X506644D01*
G01X468028Y419887D02*
Y433636D01*
X475932Y441540D01*
Y444569D01*
X490769Y459406D01*
X514890D01*
X516382Y457914D01*
Y456152D01*
X517254Y455280D01*
X518950D01*
X519822Y456152D01*
Y457768D01*
X521202Y459148D01*
X524002D01*
X525382Y457768D01*
Y456152D01*
X526254Y455280D01*
X527850D01*
X538592Y466022D01*
Y466872D01*
X539320Y467600D01*
X540170D01*
X540992Y468422D01*
Y469272D01*
X541720Y470000D01*
X542570D01*
X543292Y470722D01*
Y471572D01*
X543920Y472200D01*
X544770D01*
X545475Y472905D01*
Y474980D01*
X544775Y475680D01*
Y476400D01*
X545475Y477100D01*
Y478220D01*
X544775Y478920D01*
Y479640D01*
X545475Y480340D01*
Y481460D01*
X544775Y482160D01*
Y482880D01*
X545475Y483580D01*
Y484700D01*
X544775Y485400D01*
Y486120D01*
X545475Y486820D01*
Y487940D01*
X544775Y488640D01*
Y489360D01*
X545475Y490060D01*
Y499816D01*
X544775Y500516D01*
Y501584D01*
X545475Y502284D01*
Y503516D01*
X544775Y504216D01*
Y505084D01*
X545475Y505784D01*
Y506916D01*
X544775Y507616D01*
Y508560D01*
X545475Y509260D01*
Y511994D01*
X544359Y513110D01*
X543651D01*
X543455Y512914D01*
G01X431643Y418187D02*
Y454919D01*
X469416Y492692D01*
X480055D01*
X481343Y493980D01*
Y494736D01*
X482050Y495443D01*
X482806D01*
X483712Y496349D01*
Y499241D01*
X486120Y501649D01*
X487952D01*
X488572Y502269D01*
X489572D01*
X490192Y501649D01*
X491192D01*
X491812Y502269D01*
X492812D01*
X493432Y501649D01*
X494432D01*
X495052Y502269D01*
X496052D01*
X496672Y501649D01*
X497672D01*
X498292Y502269D01*
X499292D01*
X499912Y501649D01*
X501012D01*
X503564Y504201D01*
Y506922D01*
X502944Y507542D01*
Y508542D01*
X503564Y509162D01*
Y511780D01*
X502644Y512700D01*
X501544D01*
G01X464338Y416387D02*
Y434846D01*
X472432Y442940D01*
Y447108D01*
X488537Y463213D01*
X529223D01*
X540402Y474392D01*
Y506416D01*
X539782Y507036D01*
Y508036D01*
X540402Y508656D01*
Y511753D01*
X539455Y512700D01*
X538355D01*
G01X439903Y418487D02*
Y444592D01*
X438673Y445822D01*
X437501D01*
X436913Y446410D01*
Y447800D01*
X437545Y448432D01*
X438673D01*
X439903Y449662D01*
Y455935D01*
X471432Y487464D01*
X508365D01*
X510024Y489123D01*
Y512134D01*
X506644Y515514D01*
G01X469088Y419887D02*
Y433196D01*
X476992Y441100D01*
Y444129D01*
X491209Y458346D01*
X514450D01*
X515322Y457474D01*
Y455709D01*
X516811Y454220D01*
X519390D01*
X520882Y455712D01*
Y457328D01*
X521642Y458088D01*
X523562D01*
X524322Y457328D01*
Y455712D01*
X525814Y454220D01*
X528290D01*
X546535Y472465D01*
Y512434D01*
X543455Y515514D01*
G01X460912Y534700D02*
X459746D01*
X456561Y531515D01*
Y519862D01*
X458266Y518157D01*
G01Y528899D02*
X459246D01*
X459845Y528300D01*
Y527100D01*
X458901Y526156D01*
Y524944D01*
X459745Y524100D01*
Y522400D01*
X458901Y521556D01*
Y520136D01*
X460045Y518992D01*
Y517399D01*
X459138Y516492D01*
Y514800D01*
X460824Y513114D01*
X460912D01*
G01X454533Y534700D02*
X453545D01*
X450490Y531645D01*
Y530457D01*
X449868Y529835D01*
Y519862D01*
X451573Y518157D01*
G01Y528899D02*
X452645D01*
X453245Y528299D01*
Y527401D01*
X452208Y526364D01*
Y525136D01*
X453145Y524199D01*
Y522801D01*
X452208Y521864D01*
Y520536D01*
X453345Y519399D01*
Y517500D01*
X452845Y517000D01*
Y514800D01*
X454531Y513114D01*
X454619D01*
G01X478344Y535100D02*
X473293Y530049D01*
Y519862D01*
X474998Y518157D01*
G01Y528899D02*
X476070D01*
X476770Y528199D01*
Y526925D01*
X475633Y525788D01*
Y524712D01*
X476645Y523700D01*
Y522500D01*
X475633Y521488D01*
Y520412D01*
X476745Y519300D01*
Y516667D01*
X476570Y516492D01*
Y514800D01*
X478256Y513114D01*
X478344D01*
G01X464758Y531750D02*
X464759D01*
X466464Y530045D01*
Y528139D01*
X465725Y527400D01*
X464445D01*
X463805Y526760D01*
Y525340D01*
X464355Y524790D01*
X464935D01*
X465545Y524180D01*
Y522790D01*
X464935Y522180D01*
X464325D01*
X463805Y521660D01*
Y520290D01*
X464395Y519700D01*
X465345D01*
X466445Y518600D01*
Y517013D01*
X464732Y515300D01*
G01X469832Y534149D02*
X468127Y532444D01*
Y527499D01*
X467298Y526670D01*
Y520130D01*
X468127Y519301D01*
Y514265D01*
X469478Y512914D01*
X469832D01*
G01X464732Y534399D02*
X462745Y532412D01*
Y514347D01*
X464392Y512700D01*
X464732D01*
G01X469832Y531540D02*
X469833D01*
X471645Y529728D01*
Y528000D01*
X470645Y527000D01*
X469129D01*
X468358Y526229D01*
Y525338D01*
X468898Y524798D01*
X469135D01*
X469845Y524088D01*
Y523000D01*
X469145Y522300D01*
X468810D01*
X468358Y521848D01*
Y520571D01*
X469029Y519900D01*
X470545D01*
X471545Y518900D01*
Y517226D01*
X469833Y515514D01*
X469832D01*
G01X777571Y-43720D02*
X583560D01*
G03Y-46380I0J-1330D01*
G01X777171D01*
G02Y-51160I0J-2390D01*
G01X576040D01*
X572711Y-47831D01*
X491716D01*
X487246Y-52301D01*
G01X777571Y-42660D02*
X583560D01*
G03Y-47440I0J-2390D01*
G01X777171D01*
G02Y-50100I0J-1330D01*
G01X576480D01*
X573151Y-46771D01*
X491716D01*
X487246Y-42301D01*
G01X481691Y92757D02*
X480570Y91636D01*
Y88700D01*
X483912Y85358D01*
Y84300D01*
X482112Y82500D01*
Y80925D01*
X483312Y79725D01*
Y78599D01*
X482112Y77399D01*
Y76026D01*
X483470Y74668D01*
Y73467D01*
X485037Y71900D01*
G01Y87714D02*
X486426Y86325D01*
Y73312D01*
X487038Y72700D01*
Y71300D01*
X485238Y69500D01*
X484238D01*
X481691Y66953D01*
Y65699D01*
G01X495077Y92757D02*
X493956Y91636D01*
Y88700D01*
X496856Y85800D01*
Y83832D01*
X495323Y82299D01*
Y81100D01*
X496573Y79850D01*
Y78950D01*
X495223Y77600D01*
Y76301D01*
X496856Y74668D01*
Y72367D01*
X497723Y71500D01*
G01Y87714D02*
X499196Y86241D01*
Y73116D01*
X499812Y72500D01*
Y71156D01*
X498356Y69700D01*
X496956D01*
X495077Y67821D01*
Y65699D01*
G01X518502Y92757D02*
X517381Y91636D01*
Y88700D01*
X520723Y85358D01*
Y84300D01*
X518923Y82500D01*
Y80925D01*
X520123Y79725D01*
Y78599D01*
X518923Y77399D01*
Y76026D01*
X520281Y74668D01*
Y73467D01*
X521848Y71900D01*
G01Y87714D02*
X523237Y86325D01*
Y73312D01*
X523849Y72700D01*
Y71300D01*
X522049Y69500D01*
X521049D01*
X518502Y66953D01*
Y65699D01*
G01X488384Y92757D02*
X487456Y91829D01*
Y88701D01*
X490256Y85901D01*
Y84032D01*
X488873Y82649D01*
Y81250D01*
X490323Y79800D01*
Y78600D01*
X488823Y77100D01*
Y75901D01*
X490256Y74468D01*
Y72588D01*
X491344Y71500D01*
G01X491430Y87714D02*
X492656Y86488D01*
Y73475D01*
X493431Y72700D01*
Y71076D01*
X491855Y69500D01*
X490631D01*
X488384Y67253D01*
Y65699D01*
G01X511809Y92757D02*
X510881Y91829D01*
Y88701D01*
X513923Y85659D01*
Y84274D01*
X512248Y82599D01*
Y81476D01*
X513748Y79976D01*
Y78624D01*
X512248Y77124D01*
Y75901D01*
X513681Y74468D01*
Y73374D01*
X515155Y71900D01*
G01Y87714D02*
X516544Y86325D01*
Y73312D01*
X517156Y72700D01*
Y71300D01*
X515356Y69500D01*
X514356D01*
X511809Y66953D01*
Y65699D01*
G01X531888Y92757D02*
X530767Y91636D01*
Y88700D01*
X533667Y85800D01*
Y83832D01*
X532134Y82299D01*
Y81100D01*
X533384Y79850D01*
Y78950D01*
X532034Y77600D01*
Y76301D01*
X533667Y74668D01*
Y72367D01*
X534534Y71500D01*
G01Y87714D02*
X536007Y86241D01*
Y73116D01*
X536623Y72500D01*
Y71156D01*
X535167Y69700D01*
X533767D01*
X531888Y67821D01*
Y65699D01*
G01X525195Y92757D02*
X524267Y91829D01*
Y88701D01*
X527067Y85901D01*
Y84032D01*
X525684Y82649D01*
Y81250D01*
X527134Y79800D01*
Y78600D01*
X525634Y77100D01*
Y75901D01*
X527067Y74468D01*
Y72588D01*
X528155Y71500D01*
G01X528241Y87714D02*
X529467Y86488D01*
Y73475D01*
X530242Y72700D01*
Y71076D01*
X528666Y69500D01*
X527442D01*
X525195Y67253D01*
Y65699D01*
G01X501544Y89900D02*
X504650Y86794D01*
Y70648D01*
X503322Y69320D01*
X502340D01*
X501570Y68550D01*
G01X538355Y89900D02*
X539474Y88782D01*
X540989Y87266D01*
X541461Y86794D01*
Y70648D01*
X540133Y69320D01*
X539151D01*
X538381Y68550D01*
G01X506644Y87514D02*
Y87515D01*
X507742D01*
X508776Y86481D01*
Y83706D01*
X508070Y83000D01*
X507556D01*
X506856Y82300D01*
Y81300D01*
X507556Y80600D01*
X508056D01*
X508776Y79880D01*
Y78507D01*
X507969Y77700D01*
X507271D01*
X506670Y77099D01*
Y75901D01*
X507271Y75300D01*
X508069D01*
X508776Y74593D01*
Y71972D01*
X507753Y70949D01*
X506644D01*
G01X501544Y87300D02*
X502641D01*
X503590Y86351D01*
Y83820D01*
X502620Y82850D01*
X502272D01*
X501656Y82234D01*
Y80902D01*
X502158Y80400D01*
X502870D01*
X503590Y79680D01*
Y78720D01*
X502770Y77900D01*
X502270D01*
X501670Y77300D01*
Y76300D01*
X503590Y74380D01*
Y71091D01*
X502879Y70380D01*
X502363D01*
X501544Y71199D01*
G01X538355Y87300D02*
X539456D01*
X540401Y86355D01*
Y83820D01*
X539431Y82850D01*
X539083D01*
X538467Y82234D01*
Y80902D01*
X538969Y80400D01*
X539681D01*
X540401Y79680D01*
Y78720D01*
X539581Y77900D01*
X539081D01*
X538481Y77300D01*
Y76300D01*
X540401Y74380D01*
Y71091D01*
X539690Y70380D01*
X539174D01*
X538355Y71199D01*
G01X506644Y90114D02*
X509836Y86922D01*
Y71532D01*
X506644Y68340D01*
G01X501097Y205294D02*
X511736Y194655D01*
X517336D01*
X523691Y188300D01*
X526297D01*
X526857Y188860D01*
Y191740D01*
X527417Y192300D01*
X528857D01*
X529417Y191740D01*
Y188860D01*
X529977Y188300D01*
X540992D01*
X566418Y162874D01*
X577066D01*
X592124Y147816D01*
Y92757D01*
G01X502292Y206900D02*
X505876Y203316D01*
X540092Y193500D01*
X566268Y167324D01*
X576216D01*
X594692Y148848D01*
Y92200D01*
X593692Y91200D01*
Y89492D01*
X595470Y87714D01*
G01X495592Y202900D02*
X509892Y188600D01*
X514492D01*
X519492Y183600D01*
X538492D01*
X566518Y155574D01*
X576518D01*
X583792Y148300D01*
Y120067D01*
X584592Y119267D01*
X586192D01*
X586992Y118467D01*
Y116867D01*
X586192Y116067D01*
X584592D01*
X583792Y115267D01*
Y113667D01*
X584592Y112867D01*
X586192D01*
X586992Y112067D01*
Y110467D01*
X586192Y109667D01*
X584592D01*
X583792Y108867D01*
Y107259D01*
X584592Y106459D01*
X586184D01*
X586984Y105659D01*
Y104759D01*
X586284Y104059D01*
X585384D01*
X584484Y103159D01*
Y100859D01*
X585343Y100000D01*
X586184D01*
X586984Y99200D01*
Y97659D01*
X586184Y96859D01*
X585284D01*
X584484Y96059D01*
Y94808D01*
X585431Y93861D01*
Y92757D01*
G01X497392Y203900D02*
X510076Y191216D01*
X516476D01*
X521592Y186100D01*
X539892D01*
X566568Y159424D01*
X576716D01*
X586292Y149848D01*
Y135230D01*
X587092Y134430D01*
X588784D01*
X589392Y133822D01*
Y131838D01*
X588784Y131230D01*
X587092D01*
X586292Y130430D01*
Y128830D01*
X587092Y128030D01*
X588784D01*
X589584Y127230D01*
Y93768D01*
X586866Y91050D01*
Y89625D01*
X588777Y87714D01*
G01X488204Y201289D02*
X488911Y200582D01*
X489547D01*
X490255Y199874D01*
Y199238D01*
X490962Y198531D01*
X491598D01*
X492306Y197823D01*
Y197187D01*
X493013Y196480D01*
X493649D01*
X494357Y195772D01*
Y195136D01*
X495120Y194373D01*
X495757D01*
X496465Y193665D01*
Y193028D01*
X497172Y192321D01*
X497808D01*
X498516Y191613D01*
Y190977D01*
X499270Y190223D01*
X499907D01*
X500615Y189515D01*
Y188878D01*
X501322Y188171D01*
X501958D01*
X502666Y187463D01*
Y186827D01*
X503372Y186120D01*
X504009D01*
X504717Y185412D01*
Y184776D01*
X505803Y183689D01*
X508904D01*
X509611Y182982D01*
X510247D01*
X510955Y182274D01*
Y181638D01*
X511662Y180931D01*
X512298D01*
X513006Y180223D01*
Y179587D01*
X513713Y178880D01*
X514349D01*
X515057Y178172D01*
Y177536D01*
X515764Y176829D01*
X516400D01*
X517108Y176121D01*
Y175485D01*
X519233Y173360D01*
X521863D01*
X522473Y173970D01*
Y176970D01*
X523703Y178200D01*
X525973D01*
X527203Y176970D01*
Y173970D01*
X527813Y173360D01*
X538832D01*
X563891Y148301D01*
X574691D01*
X577452Y145540D01*
Y104150D01*
X577902Y103700D01*
Y99710D01*
X574652Y96460D01*
Y94940D01*
X575192Y94400D01*
X575892D01*
X576892Y93400D01*
Y91626D01*
X575166Y89900D01*
G01X490241Y203538D02*
X508205Y185574D01*
X513118D01*
X518592Y180100D01*
X536893D01*
X565418Y151575D01*
X575717D01*
X580392Y146900D01*
Y98200D01*
X578542Y96350D01*
Y89238D01*
X580266Y87514D01*
G01X490991Y204288D02*
X508645Y186634D01*
X513558D01*
X519032Y181160D01*
X537333D01*
X565858Y152635D01*
X576157D01*
X581452Y147340D01*
Y97760D01*
X579602Y95910D01*
Y95290D01*
X580392Y94500D01*
X580892D01*
X581992Y93400D01*
Y91840D01*
X580266Y90114D01*
G01X495792Y421150D02*
X499972Y425330D01*
X506356D01*
X511226Y430200D01*
X532520D01*
X575866Y473546D01*
Y489803D01*
X575066Y490603D01*
X573466D01*
X572666Y489803D01*
Y488200D01*
X571866Y487400D01*
X570266D01*
X569466Y488200D01*
Y508174D01*
X570392Y509100D01*
Y511081D01*
X567292Y514181D01*
Y516750D01*
X568699Y518157D01*
G01X571345Y513114D02*
Y512764D01*
X572457Y511652D01*
Y505664D01*
X573221Y504900D01*
X576185D01*
X576795Y504290D01*
Y502900D01*
X576185Y502290D01*
X572862D01*
X572252Y501680D01*
Y499919D01*
X573008Y499163D01*
X577800D01*
X578425Y498538D01*
Y496544D01*
X577844Y495963D01*
X572756D01*
X571878Y495085D01*
Y493500D01*
X572658Y492720D01*
X577100D01*
X578366Y491454D01*
Y478001D01*
X579492Y476875D01*
Y474801D01*
X578366Y473675D01*
Y472510D01*
X575868Y470012D01*
Y468976D01*
X574123Y467231D01*
X573087D01*
X534156Y428300D01*
X511992D01*
X507137Y423445D01*
X501349D01*
X497454Y419550D01*
G01X522491Y412000D02*
X528826D01*
X532926Y416100D01*
X543639D01*
X570239Y442700D01*
X575700D01*
X601349Y468349D01*
Y495469D01*
X600778Y496040D01*
X599214D01*
X598392Y495218D01*
Y492492D01*
X597625Y491725D01*
X596025D01*
X595192Y492558D01*
Y507700D01*
X594166Y508726D01*
Y510907D01*
X591692Y513381D01*
Y517725D01*
X592124Y518157D01*
G01X522492Y409500D02*
X528992D01*
X533492Y414000D01*
X545075D01*
X571775Y440700D01*
X577236D01*
X603190Y466654D01*
Y506172D01*
X602690Y506672D01*
X601666D01*
X601021Y506027D01*
Y499238D01*
X600378Y498595D01*
X598971D01*
X598312Y499254D01*
Y507880D01*
X596766Y509426D01*
Y511870D01*
X595470Y513166D01*
Y513114D01*
G01X491992Y423500D02*
X497592Y429100D01*
X504792D01*
X510392Y434700D01*
X528291D01*
X560792Y467201D01*
Y473583D01*
X561638Y474429D01*
X567846D01*
X568636Y475219D01*
Y476819D01*
X567826Y477629D01*
X561592D01*
X560792Y478429D01*
Y480029D01*
X561592Y480829D01*
X563666D01*
X564466Y481629D01*
Y498757D01*
X563806Y499417D01*
Y511275D01*
X560766Y514315D01*
Y516917D01*
X562006Y518157D01*
G01X493692Y421950D02*
X498957Y427215D01*
X505574D01*
X510559Y432200D01*
X530827D01*
X533200Y434573D01*
Y436206D01*
X534647Y437653D01*
X536280D01*
X537726Y439099D01*
Y440732D01*
X539173Y442179D01*
X540806D01*
X542252Y443625D01*
Y445258D01*
X543699Y446705D01*
X545332D01*
X546778Y448151D01*
Y449784D01*
X548225Y451231D01*
X549858D01*
X551304Y452677D01*
Y454310D01*
X552751Y455757D01*
X554384D01*
X555830Y457203D01*
Y458836D01*
X557277Y460283D01*
X558910D01*
X560356Y461729D01*
Y463362D01*
X561803Y464809D01*
X563436D01*
X573366Y474739D01*
Y484000D01*
X572566Y484800D01*
X570966D01*
X570166Y484000D01*
Y481000D01*
X569366Y480200D01*
X567766D01*
X566966Y481000D01*
Y508727D01*
X565592Y510101D01*
Y512448D01*
X565266Y512774D01*
G01X522792Y416000D02*
X527494D01*
X531594Y420100D01*
X540491D01*
X572795Y452404D01*
X578333D01*
X596592Y470663D01*
Y478809D01*
X595836Y479565D01*
X594236D01*
X593392Y478721D01*
Y472969D01*
X592636Y472213D01*
X591036D01*
X590192Y473057D01*
Y505936D01*
X587666Y508462D01*
Y510757D01*
X584766Y513657D01*
Y517492D01*
X585431Y518157D01*
G01X522742Y414100D02*
X528260D01*
X532360Y418200D01*
X542203D01*
X570187Y446184D01*
X571049D01*
X572081Y445153D01*
X572943D01*
X574344Y446554D01*
Y447416D01*
X573312Y448447D01*
Y449309D01*
X573907Y449904D01*
X579369D01*
X599092Y469627D01*
Y481079D01*
X598136Y482035D01*
X593315D01*
X592515Y482835D01*
Y484781D01*
X593315Y485581D01*
X596557D01*
X597357Y486381D01*
Y487981D01*
X596557Y488781D01*
X593492D01*
X592692Y489581D01*
Y506800D01*
X590166Y509326D01*
Y511768D01*
X590123D01*
X588777Y513114D01*
G01X506013Y417351D02*
X510362Y421700D01*
X525542D01*
X529042Y425200D01*
X536260D01*
X582612Y471552D01*
Y503151D01*
X578346Y507417D01*
Y512120D01*
X575166Y515300D01*
G01X506642Y415130D02*
X511222Y419710D01*
X526502D01*
X529852Y423060D01*
X538320D01*
X572405Y457145D01*
X574519D01*
X575580Y456084D01*
X576806D01*
X578580Y457858D01*
Y459084D01*
X577612Y460052D01*
Y462349D01*
X579908Y464645D01*
X582019D01*
X583137Y463527D01*
X584368D01*
X586512Y465671D01*
Y484732D01*
X585892Y485352D01*
Y486352D01*
X586512Y486972D01*
Y487972D01*
X585892Y488592D01*
Y489592D01*
X586512Y490212D01*
Y491212D01*
X585892Y491832D01*
Y492832D01*
X586512Y493452D01*
Y494452D01*
X585892Y495072D01*
Y496072D01*
X586512Y496692D01*
Y497692D01*
X585892Y498312D01*
Y499312D01*
X586512Y499932D01*
Y500932D01*
X585892Y501552D01*
Y502552D01*
X586512Y503172D01*
Y504303D01*
X585058Y505757D01*
X584543D01*
X583836Y506464D01*
Y506979D01*
X582666Y508149D01*
Y511614D01*
X581366Y512914D01*
X580266D01*
G01X505262Y418100D02*
X509922Y422760D01*
X525102D01*
X528602Y426260D01*
X535820D01*
X581552Y471992D01*
Y479951D01*
X581086Y480417D01*
Y481417D01*
X581552Y481883D01*
Y483059D01*
X580932Y483679D01*
Y484679D01*
X581552Y485299D01*
Y486299D01*
X580932Y486919D01*
Y487919D01*
X581552Y488539D01*
Y489539D01*
X580932Y490159D01*
Y491159D01*
X581552Y491779D01*
Y492779D01*
X580932Y493399D01*
Y494399D01*
X581552Y495019D01*
Y496019D01*
X580932Y496639D01*
Y497639D01*
X581552Y498259D01*
Y499259D01*
X580932Y499879D01*
Y500879D01*
X581552Y501499D01*
Y502711D01*
X580191Y504072D01*
X579611D01*
X578904Y504779D01*
Y505359D01*
X577286Y506977D01*
Y511680D01*
X576266Y512700D01*
X575166D01*
G01X507512Y414500D02*
X511662Y418650D01*
X526942D01*
X530292Y422000D01*
X538760D01*
X572845Y456085D01*
X574076D01*
X575137Y455024D01*
X577249D01*
X579640Y457415D01*
Y459527D01*
X578672Y460495D01*
Y461909D01*
X580348Y463585D01*
X581579D01*
X582697Y462467D01*
X584808D01*
X587572Y465231D01*
Y504743D01*
X583726Y508589D01*
Y512054D01*
X580266Y515514D01*
G01X485037Y535100D02*
X479986Y530049D01*
Y519862D01*
X481691Y518157D01*
G01Y528899D02*
X482763D01*
X483463Y528199D01*
Y526925D01*
X482326Y525788D01*
Y524712D01*
X483338Y523700D01*
Y522500D01*
X482326Y521488D01*
Y520412D01*
X483438Y519300D01*
Y516667D01*
X483263Y516492D01*
Y514800D01*
X484949Y513114D01*
X485037D01*
G01X495077Y518157D02*
X493372Y519862D01*
Y531515D01*
X496557Y534700D01*
X497723D01*
G01Y513114D02*
X497635D01*
X495949Y514800D01*
Y516492D01*
X496856Y517399D01*
Y518992D01*
X495712Y520136D01*
Y521556D01*
X496556Y522400D01*
Y524100D01*
X495712Y524944D01*
Y526156D01*
X496656Y527100D01*
Y528300D01*
X496057Y528899D01*
X495077D01*
G01X518502Y518157D02*
X516797Y519862D01*
Y530049D01*
X521848Y535100D01*
G01Y513114D02*
X521760D01*
X520074Y514800D01*
Y516492D01*
X520249Y516667D01*
Y519300D01*
X519137Y520412D01*
Y521488D01*
X520149Y522500D01*
Y523700D01*
X519137Y524712D01*
Y525788D01*
X520274Y526925D01*
Y528199D01*
X519574Y528899D01*
X518502D01*
G01X488384Y518157D02*
X486679Y519862D01*
Y529835D01*
X487301Y530457D01*
Y531645D01*
X490356Y534700D01*
X491344D01*
G01X491430Y513114D02*
X491342D01*
X489656Y514800D01*
Y517000D01*
X490156Y517500D01*
Y519399D01*
X489019Y520536D01*
Y521864D01*
X489956Y522801D01*
Y524199D01*
X489019Y525136D01*
Y526364D01*
X490056Y527401D01*
Y528299D01*
X489456Y528899D01*
X488384D01*
G01X511809Y518157D02*
X510104Y519862D01*
Y530049D01*
X515155Y535100D01*
G01Y513114D02*
X515067D01*
X513381Y514800D01*
Y516492D01*
X513556Y516667D01*
Y519300D01*
X512444Y520412D01*
Y521488D01*
X513456Y522500D01*
Y523700D01*
X512444Y524712D01*
Y525788D01*
X513581Y526925D01*
Y528199D01*
X512881Y528899D01*
X511809D01*
G01X531888Y518157D02*
X530183Y519862D01*
Y531515D01*
X533368Y534700D01*
X534534D01*
G01Y513114D02*
X534446D01*
X532760Y514800D01*
Y516492D01*
X533667Y517399D01*
Y518992D01*
X532523Y520136D01*
Y521556D01*
X533367Y522400D01*
Y524100D01*
X532523Y524944D01*
Y526156D01*
X533467Y527100D01*
Y528300D01*
X532868Y528899D01*
X531888D01*
G01X525195Y518157D02*
X523490Y519862D01*
Y529835D01*
X524112Y530457D01*
Y531645D01*
X527167Y534700D01*
X528155D01*
G01X528241Y513114D02*
X528153D01*
X526467Y514800D01*
Y517000D01*
X526967Y517500D01*
Y519399D01*
X525830Y520536D01*
Y521864D01*
X526767Y522801D01*
Y524199D01*
X525830Y525136D01*
Y526364D01*
X526867Y527401D01*
Y528299D01*
X526267Y528899D01*
X525195D01*
G01X501544Y515300D02*
X503256Y517012D01*
Y518600D01*
X502156Y519700D01*
X501206D01*
X500616Y520290D01*
Y521660D01*
X501136Y522180D01*
X501746D01*
X502356Y522790D01*
Y524180D01*
X501746Y524790D01*
X501166D01*
X500616Y525340D01*
Y526760D01*
X501256Y527400D01*
X502536D01*
X503275Y528139D01*
Y530045D01*
X501570Y531750D01*
G01X538355Y515300D02*
X540067Y517012D01*
Y518600D01*
X538967Y519700D01*
X538017D01*
X537427Y520290D01*
Y521660D01*
X537947Y522180D01*
X538557D01*
X539167Y522790D01*
Y524180D01*
X538557Y524790D01*
X537977D01*
X537427Y525340D01*
Y526760D01*
X538067Y527400D01*
X539347D01*
X540086Y528139D01*
Y530045D01*
X538381Y531750D01*
G01X506644Y512914D02*
X506356D01*
X504939Y514331D01*
Y519300D01*
X504109Y520130D01*
Y526670D01*
X504939Y527500D01*
Y532444D01*
X506644Y534149D01*
G01X501544Y512700D02*
X501192D01*
X499556Y514336D01*
Y532411D01*
X501544Y534399D01*
G01X538355Y512700D02*
X538067D01*
X536367Y514400D01*
Y532411D01*
X538355Y534399D01*
G01X506644Y515514D02*
X508356Y517226D01*
Y518900D01*
X507356Y519900D01*
X505840D01*
X505169Y520571D01*
Y521848D01*
X505621Y522300D01*
X505956D01*
X506656Y523000D01*
Y524088D01*
X505946Y524798D01*
X505709D01*
X505169Y525338D01*
Y526229D01*
X505940Y527000D01*
X507456D01*
X508456Y528000D01*
Y529728D01*
X506644Y531540D01*
G01X555313Y92757D02*
X554192Y91636D01*
Y88700D01*
X557534Y85358D01*
Y84300D01*
X555734Y82500D01*
Y80925D01*
X556934Y79725D01*
Y78599D01*
X555734Y77399D01*
Y76026D01*
X557092Y74668D01*
Y73467D01*
X558659Y71900D01*
G01Y87714D02*
X560048Y86325D01*
Y73312D01*
X560660Y72700D01*
Y71300D01*
X558860Y69500D01*
X557860D01*
X555313Y66953D01*
Y65699D01*
G01X548620Y92757D02*
X547692Y91829D01*
Y88701D01*
X550734Y85659D01*
Y84274D01*
X549059Y82599D01*
Y81476D01*
X550559Y79976D01*
Y78624D01*
X549059Y77124D01*
Y75901D01*
X550492Y74468D01*
Y73374D01*
X551966Y71900D01*
G01Y87714D02*
X553355Y86325D01*
Y73312D01*
X553967Y72700D01*
Y71300D01*
X552167Y69500D01*
X551167D01*
X548620Y66953D01*
Y65699D01*
G01X568699Y92757D02*
X567578Y91636D01*
Y88700D01*
X570478Y85800D01*
Y83832D01*
X568945Y82299D01*
Y81100D01*
X570195Y79850D01*
Y78950D01*
X568845Y77600D01*
Y76301D01*
X570478Y74668D01*
Y72367D01*
X571345Y71500D01*
G01Y87714D02*
X572818Y86241D01*
Y73116D01*
X573434Y72500D01*
Y71156D01*
X571978Y69700D01*
X570578D01*
X568699Y67821D01*
Y65699D01*
G01X592124Y92757D02*
X591003Y91636D01*
Y88700D01*
X594345Y85358D01*
Y84300D01*
X592545Y82500D01*
Y80925D01*
X593745Y79725D01*
Y78599D01*
X592545Y77399D01*
Y76026D01*
X593903Y74668D01*
Y73467D01*
X595470Y71900D01*
G01Y87714D02*
X596859Y86325D01*
Y73312D01*
X597471Y72700D01*
Y71300D01*
X595671Y69500D01*
X594671D01*
X592124Y66953D01*
Y65699D01*
G01X562006Y92757D02*
X561078Y91829D01*
Y88701D01*
X563878Y85901D01*
Y84032D01*
X562495Y82649D01*
Y81250D01*
X563945Y79800D01*
Y78600D01*
X562445Y77100D01*
Y75901D01*
X563878Y74468D01*
Y72588D01*
X564966Y71500D01*
G01X565266Y87374D02*
X566278Y86362D01*
Y73475D01*
X567053Y72700D01*
Y71076D01*
X565477Y69500D01*
X564253D01*
X562006Y67253D01*
Y65699D01*
G01X585431Y92757D02*
X584503Y91829D01*
Y88701D01*
X587545Y85659D01*
Y84274D01*
X585870Y82599D01*
Y81476D01*
X587370Y79976D01*
Y78624D01*
X585870Y77124D01*
Y75901D01*
X587303Y74468D01*
Y73374D01*
X588777Y71900D01*
G01Y87714D02*
X590166Y86325D01*
Y73312D01*
X590778Y72700D01*
Y71300D01*
X588978Y69500D01*
X587978D01*
X585431Y66953D01*
Y65699D01*
G01X575166Y89900D02*
X578272Y86794D01*
Y70648D01*
X576944Y69320D01*
X575962D01*
X575192Y68550D01*
G01X543455Y87514D02*
Y87515D01*
X544553D01*
X545587Y86481D01*
Y83706D01*
X544881Y83000D01*
X544367D01*
X543667Y82300D01*
Y81300D01*
X544367Y80600D01*
X544867D01*
X545587Y79880D01*
Y78507D01*
X544780Y77700D01*
X544082D01*
X543481Y77099D01*
Y75901D01*
X544082Y75300D01*
X544880D01*
X545587Y74593D01*
Y71972D01*
X544564Y70949D01*
X543455D01*
G01X580266Y87514D02*
Y87515D01*
X581364D01*
X582398Y86481D01*
Y83706D01*
X581692Y83000D01*
X581178D01*
X580478Y82300D01*
Y81300D01*
X581178Y80600D01*
X581678D01*
X582398Y79880D01*
Y78507D01*
X581591Y77700D01*
X580893D01*
X580292Y77099D01*
Y75901D01*
X580893Y75300D01*
X581691D01*
X582398Y74593D01*
Y71972D01*
X581375Y70949D01*
X580266D01*
G01X575166Y87300D02*
X576265D01*
X577212Y86353D01*
Y83820D01*
X576242Y82850D01*
X575894D01*
X575278Y82234D01*
Y80902D01*
X575780Y80400D01*
X576492D01*
X577212Y79680D01*
Y78720D01*
X576392Y77900D01*
X575892D01*
X575292Y77300D01*
Y76300D01*
X577212Y74380D01*
Y71091D01*
X576501Y70380D01*
X575985D01*
X575166Y71199D01*
G01X543455Y90114D02*
X544530Y89038D01*
X546303Y87266D01*
X546647Y86922D01*
Y71532D01*
X543455Y68340D01*
G01X580266Y90114D02*
X583458Y86922D01*
Y71532D01*
X580266Y68340D01*
G01X555313Y518157D02*
X553608Y519862D01*
Y530049D01*
X558659Y535100D01*
G01Y513114D02*
X558571D01*
X556885Y514800D01*
Y516492D01*
X557060Y516667D01*
Y519300D01*
X555948Y520412D01*
Y521488D01*
X556960Y522500D01*
Y523700D01*
X555948Y524712D01*
Y525788D01*
X557085Y526925D01*
Y528199D01*
X556385Y528899D01*
X555313D01*
G01X548620Y518157D02*
X546915Y519862D01*
Y530049D01*
X551966Y535100D01*
G01Y513114D02*
X551878D01*
X550192Y514800D01*
Y516492D01*
X550367Y516667D01*
Y519300D01*
X549255Y520412D01*
Y521488D01*
X550267Y522500D01*
Y523700D01*
X549255Y524712D01*
Y525788D01*
X550392Y526925D01*
Y528199D01*
X549692Y528899D01*
X548620D01*
G01X568699Y518157D02*
X566994Y519862D01*
Y531515D01*
X570179Y534700D01*
X571345D01*
G01Y513114D02*
X571257D01*
X569571Y514800D01*
Y516492D01*
X570478Y517399D01*
Y518992D01*
X569334Y520136D01*
Y521556D01*
X570178Y522400D01*
Y524100D01*
X569334Y524944D01*
Y526156D01*
X570278Y527100D01*
Y528300D01*
X569679Y528899D01*
X568699D01*
G01X592124Y518157D02*
X590419Y519862D01*
Y530049D01*
X595470Y535100D01*
G01Y513114D02*
X595382D01*
X593696Y514800D01*
Y516492D01*
X593871Y516667D01*
Y519300D01*
X592759Y520412D01*
Y521488D01*
X593771Y522500D01*
Y523700D01*
X592759Y524712D01*
Y525788D01*
X593896Y526925D01*
Y528199D01*
X593196Y528899D01*
X592124D01*
G01X562006Y518157D02*
X560301Y519862D01*
Y529835D01*
X560923Y530457D01*
Y531645D01*
X563978Y534700D01*
X564966D01*
G01X565266Y512774D02*
X563278Y514762D01*
Y517000D01*
X563778Y517500D01*
Y519399D01*
X562641Y520536D01*
Y521864D01*
X563492Y522715D01*
Y524285D01*
X562641Y525136D01*
Y526364D01*
X563478Y527201D01*
Y528215D01*
X562794Y528899D01*
X562006D01*
G01X585431Y518157D02*
X583726Y519862D01*
Y530049D01*
X588777Y535100D01*
G01Y513114D02*
X588689D01*
X587003Y514800D01*
Y516492D01*
X587178Y516667D01*
Y519300D01*
X586066Y520412D01*
Y521488D01*
X587078Y522500D01*
Y523700D01*
X586066Y524712D01*
Y525788D01*
X587203Y526925D01*
Y528199D01*
X586503Y528899D01*
X585431D01*
G01X575166Y515300D02*
X576878Y517012D01*
Y518600D01*
X575778Y519700D01*
X574828D01*
X574238Y520290D01*
Y521660D01*
X574758Y522180D01*
X575368D01*
X575978Y522790D01*
Y524180D01*
X575368Y524790D01*
X574788D01*
X574238Y525340D01*
Y526760D01*
X574878Y527400D01*
X576158D01*
X576897Y528139D01*
Y530045D01*
X575192Y531750D01*
G01X543455Y512914D02*
X543167D01*
X541750Y514331D01*
Y519300D01*
X540920Y520130D01*
Y526670D01*
X541750Y527500D01*
Y532444D01*
X543455Y534149D01*
G01X580266Y512914D02*
X579978D01*
X578561Y514331D01*
Y519300D01*
X577731Y520130D01*
Y526670D01*
X578561Y527500D01*
Y532444D01*
X580266Y534149D01*
G01X575166Y512700D02*
X574878D01*
X573178Y514400D01*
Y532411D01*
X575166Y534399D01*
G01X543455Y515514D02*
X545167Y517226D01*
Y518900D01*
X544167Y519900D01*
X542651D01*
X541980Y520571D01*
Y521848D01*
X542432Y522300D01*
X542767D01*
X543467Y523000D01*
Y524088D01*
X542757Y524798D01*
X542520D01*
X541980Y525338D01*
Y526229D01*
X542751Y527000D01*
X544267D01*
X545267Y528000D01*
Y529728D01*
X543455Y531540D01*
G01X580266Y515514D02*
X581978Y517226D01*
Y518900D01*
X580978Y519900D01*
X579462D01*
X578791Y520571D01*
Y521848D01*
X579243Y522300D01*
X579578D01*
X580278Y523000D01*
Y524088D01*
X579568Y524798D01*
X579331D01*
X578791Y525338D01*
Y526229D01*
X579562Y527000D01*
X581078D01*
X582078Y528000D01*
Y529728D01*
X580266Y531540D01*
G01X779921Y92757D02*
X777528Y95150D01*
Y108285D01*
X778443Y109200D01*
X781020D01*
X781492Y109672D01*
Y112704D01*
X780932Y113264D01*
X779560D01*
X779000Y113824D01*
Y115264D01*
X779560Y115824D01*
X780932D01*
X781492Y116384D01*
Y117824D01*
X780932Y118384D01*
X779560D01*
X779000Y118944D01*
Y120384D01*
X779560Y120944D01*
X780932D01*
X781492Y121504D01*
Y122944D01*
X780932Y123504D01*
X779560D01*
X779000Y124064D01*
Y125504D01*
X779560Y126064D01*
X780932D01*
X781492Y126624D01*
Y144060D01*
X897795Y260363D01*
X908000D01*
G01X782567Y71500D02*
X781700Y72367D01*
Y74668D01*
X780067Y76301D01*
Y77600D01*
X781417Y78950D01*
Y79850D01*
X780167Y81100D01*
Y82299D01*
X781700Y83832D01*
Y85800D01*
X778800Y88700D01*
Y91636D01*
X779921Y92757D01*
G01X782567Y87714D02*
X784040Y86241D01*
Y73116D01*
X784656Y72500D01*
Y71156D01*
X783200Y69700D01*
X781800D01*
X779921Y67821D01*
Y65699D01*
G01X908000Y257863D02*
X898831D01*
X783992Y143024D01*
Y107373D01*
X782792Y106173D01*
X780492D01*
X779692Y105373D01*
Y104173D01*
X780492Y103373D01*
X782792D01*
X783592Y102573D01*
Y101356D01*
X781988Y99752D01*
Y92388D01*
X780692Y91092D01*
Y89589D01*
X782567Y87714D01*
G01X907500Y265363D02*
X895723D01*
X772464Y142104D01*
Y134964D01*
X773024Y134404D01*
X774740D01*
X775300Y133844D01*
Y132404D01*
X774740Y131844D01*
X773024D01*
X772464Y131284D01*
Y93521D01*
X773228Y92757D01*
G01D02*
X772300Y91829D01*
Y88701D01*
X775100Y85901D01*
Y84032D01*
X773717Y82649D01*
Y81250D01*
X775167Y79800D01*
Y78600D01*
X773667Y77100D01*
Y75901D01*
X775100Y74468D01*
Y72588D01*
X776188Y71500D01*
G01X776274Y87714D02*
X777500Y86488D01*
Y73475D01*
X778275Y72700D01*
Y71076D01*
X776699Y69500D01*
X775475D01*
X773228Y67253D01*
Y65699D01*
G01X907500Y262863D02*
X896759D01*
X778992Y145096D01*
Y129693D01*
X775028Y125729D01*
Y91692D01*
X774392Y91056D01*
Y89596D01*
X776274Y87714D01*
G01X786388Y89900D02*
X788114Y91626D01*
Y93386D01*
X787000Y94500D01*
X786314D01*
X785594Y95220D01*
Y97570D01*
X788292Y100268D01*
Y101100D01*
X787672Y101720D01*
Y102680D01*
X788292Y103300D01*
Y104300D01*
X787672Y104920D01*
Y105680D01*
X788292Y106300D01*
Y107300D01*
X787672Y107920D01*
Y108680D01*
X788292Y109300D01*
Y110300D01*
X787672Y110920D01*
Y111680D01*
X788292Y112300D01*
Y113300D01*
X787672Y113920D01*
Y114680D01*
X788292Y115300D01*
Y116300D01*
X787672Y116920D01*
Y141497D01*
X789418Y143243D01*
X790513D01*
X793580Y146310D01*
Y147405D01*
X900358Y254183D01*
X908984D01*
G01X786414Y68550D02*
X787184Y69320D01*
X788166D01*
X789494Y70648D01*
Y86794D01*
X786388Y89900D01*
G01X909104Y255243D02*
X899915D01*
X792520Y147848D01*
Y146753D01*
X790070Y144303D01*
X788975D01*
X786612Y141940D01*
Y100091D01*
X784534Y98013D01*
Y89154D01*
X786388Y87300D01*
G01D02*
X787487D01*
X788434Y86353D01*
Y83820D01*
X787464Y82850D01*
X787116D01*
X786500Y82234D01*
Y80902D01*
X787002Y80400D01*
X787714D01*
X788434Y79680D01*
Y78720D01*
X787614Y77900D01*
X787114D01*
X786514Y77300D01*
Y76300D01*
X788434Y74380D01*
Y71091D01*
X787723Y70380D01*
X787207D01*
X786388Y71199D01*
G01X908899Y334836D02*
X904090D01*
X849500Y389426D01*
Y395300D01*
X801600Y443200D01*
X797900D01*
X784149Y456951D01*
Y477751D01*
X781900Y480000D01*
Y510717D01*
X778800Y513817D01*
Y517036D01*
X779921Y518157D01*
G01X908914Y337336D02*
X904257D01*
X851500Y390093D01*
Y395999D01*
X802399Y445100D01*
X798699D01*
X786217Y457582D01*
Y480074D01*
X785490Y480801D01*
X784497D01*
X783887Y481411D01*
Y482801D01*
X784497Y483411D01*
X785967D01*
X786657Y484101D01*
Y485491D01*
X786127Y486021D01*
X784471D01*
X783914Y486578D01*
Y487968D01*
X784577Y488631D01*
X786073D01*
X786683Y489241D01*
Y490631D01*
X786073Y491241D01*
X784365D01*
X783755Y491851D01*
Y493241D01*
X784365Y493851D01*
X786312D01*
X786922Y494461D01*
Y495851D01*
X786312Y496461D01*
X784338D01*
X783728Y497071D01*
Y498461D01*
X784338Y499071D01*
X786047D01*
X786657Y499681D01*
Y501071D01*
X786047Y501681D01*
X784339D01*
X783729Y502291D01*
Y503681D01*
X784488Y504440D01*
Y511193D01*
X782567Y513114D01*
G01X908732Y330247D02*
X903347D01*
X845700Y387894D01*
Y393600D01*
X799900Y439400D01*
X795892D01*
X779324Y455968D01*
X777467Y460450D01*
Y504747D01*
X774742Y511327D01*
X772610Y513459D01*
Y517539D01*
X773228Y518157D01*
G01X908841Y332336D02*
X903924D01*
X847600Y388660D01*
Y394500D01*
X800800Y441300D01*
X796752D01*
X780958Y457094D01*
X779744Y460026D01*
Y461345D01*
X780354Y461955D01*
X781661D01*
X782311Y462605D01*
Y463995D01*
X781741Y464565D01*
X780354D01*
X779744Y465175D01*
Y466565D01*
X780354Y467175D01*
X781234D01*
X781844Y467785D01*
Y469175D01*
X781234Y469785D01*
X779988D01*
X779400Y470373D01*
Y472559D01*
X780010Y473169D01*
X781690D01*
X782280Y473759D01*
Y475149D01*
X781650Y475779D01*
X780010D01*
X779400Y476389D01*
Y506900D01*
X777788Y508512D01*
Y511600D01*
X776274Y513114D01*
G01X779921Y518157D02*
X778216Y519862D01*
Y530349D01*
X782567Y534700D01*
G01Y513114D02*
X782479D01*
X780793Y514800D01*
Y516492D01*
X781700Y517399D01*
Y518992D01*
X780556Y520136D01*
Y521556D01*
X781400Y522400D01*
Y524100D01*
X780556Y524944D01*
Y526156D01*
X781500Y527100D01*
Y528300D01*
X780901Y528899D01*
X779921D01*
G01X773228Y518157D02*
X771523Y522274D01*
Y529277D01*
X772059Y530571D01*
X776188Y534700D01*
G01X776274Y513114D02*
X776186D01*
X774500Y514800D01*
Y517000D01*
X775000Y517500D01*
Y519764D01*
X773863Y520901D01*
Y522229D01*
X774800Y523166D01*
Y524199D01*
X773863Y525136D01*
Y526364D01*
X774900Y527401D01*
Y528299D01*
X774300Y528899D01*
X773228D01*
G01X786388Y515300D02*
X788100Y517012D01*
Y518600D01*
X787000Y519700D01*
X786050D01*
X785460Y520290D01*
Y521660D01*
X785980Y522180D01*
X786590D01*
X787200Y522790D01*
Y524180D01*
X786590Y524790D01*
X786010D01*
X785460Y525340D01*
Y526760D01*
X786100Y527400D01*
X787380D01*
X788119Y528139D01*
Y530045D01*
X786414Y531750D01*
G01X908620Y341156D02*
X904603D01*
X854500Y391259D01*
Y397399D01*
X803699Y448200D01*
X799799D01*
X790680Y457319D01*
Y458183D01*
X791152Y458655D01*
X792188D01*
X792210Y458676D01*
X793480Y459947D01*
Y462823D01*
X792088Y464215D01*
X790952D01*
X790280Y464887D01*
Y466783D01*
X791152Y467655D01*
X792483D01*
X793672Y468844D01*
Y471726D01*
X792183Y473215D01*
X790652D01*
X789680Y474187D01*
Y512008D01*
X786388Y515300D01*
G01X908455Y340096D02*
X904163D01*
X853440Y390819D01*
Y396959D01*
X803259Y447140D01*
X799359D01*
X789620Y456879D01*
Y458623D01*
X790712Y459715D01*
X791748D01*
X792420Y460387D01*
Y462383D01*
X791648Y463155D01*
X790512D01*
X789220Y464447D01*
Y467223D01*
X790712Y468715D01*
X792043D01*
X792612Y469284D01*
Y471286D01*
X791743Y472155D01*
X790212D01*
X788620Y473747D01*
Y506680D01*
X788000Y507300D01*
Y508500D01*
X788620Y509120D01*
Y511568D01*
X787369Y512819D01*
X786507D01*
X786388Y512700D01*
G01D02*
X786100D01*
X784400Y514400D01*
Y532411D01*
X786388Y534399D01*
G01X840157Y92757D02*
X839036Y91636D01*
Y88700D01*
X842378Y85358D01*
Y84300D01*
X840578Y82500D01*
Y80925D01*
X841778Y79725D01*
Y78599D01*
X840578Y77399D01*
Y76026D01*
X841936Y74668D01*
Y73467D01*
X843503Y71900D01*
G01Y87714D02*
X844892Y86325D01*
Y73312D01*
X845504Y72700D01*
Y71300D01*
X843704Y69500D01*
X842704D01*
X841404Y68200D01*
Y66946D01*
X840157Y65699D01*
G01X810039Y92757D02*
X809111Y91829D01*
Y88701D01*
X811911Y85901D01*
Y84032D01*
X810528Y82649D01*
Y81250D01*
X811978Y79800D01*
Y78600D01*
X810478Y77100D01*
Y75901D01*
X811911Y74468D01*
Y72588D01*
X812999Y71500D01*
G01X813085Y87714D02*
X814311Y86488D01*
Y73475D01*
X815086Y72700D01*
Y71076D01*
X813510Y69500D01*
X812286D01*
X810039Y67253D01*
Y65699D01*
G01X833464Y92757D02*
X832536Y91829D01*
Y88701D01*
X835578Y85659D01*
Y84274D01*
X833903Y82599D01*
Y81476D01*
X835403Y79976D01*
Y78624D01*
X833903Y77124D01*
Y75901D01*
X835336Y74468D01*
Y73374D01*
X836810Y71900D01*
G01Y87714D02*
X838199Y86325D01*
Y73312D01*
X838811Y72700D01*
Y71300D01*
X837011Y69500D01*
X836011D01*
X834711Y68200D01*
Y66946D01*
X833464Y65699D01*
G01X910653Y232952D02*
X904903D01*
X845292Y173341D01*
Y94315D01*
X846850Y92757D01*
G01D02*
X845922Y91829D01*
Y88701D01*
X848722Y85901D01*
Y84032D01*
X847339Y82649D01*
Y81250D01*
X848789Y79800D01*
Y78600D01*
X847289Y77100D01*
Y75901D01*
X848722Y74468D01*
Y72588D01*
X849810Y71500D01*
G01X849896Y87714D02*
X847992Y89618D01*
Y91192D01*
X848792Y91992D01*
Y95801D01*
X848250Y96343D01*
Y172301D01*
X906351Y230402D01*
X910506D01*
G01X846850Y65699D02*
Y67253D01*
X849097Y69500D01*
X850321D01*
X851897Y71076D01*
Y72700D01*
X851122Y73475D01*
Y86488D01*
X849896Y87714D01*
G01X803346Y92757D02*
X802225Y91636D01*
Y88700D01*
X805567Y85358D01*
Y84300D01*
X803767Y82500D01*
Y80925D01*
X804967Y79725D01*
Y78599D01*
X803767Y77399D01*
Y76026D01*
X805125Y74668D01*
Y73467D01*
X806692Y71900D01*
G01X908000Y242659D02*
X905134D01*
X813192Y150717D01*
Y103200D01*
X812392Y102400D01*
X811192D01*
X810392Y103200D01*
Y124500D01*
X809592Y125300D01*
X808392D01*
X807592Y124500D01*
Y98893D01*
X805046Y96347D01*
Y94457D01*
X803346Y92757D01*
G01X806692Y87714D02*
X804800Y89606D01*
Y91300D01*
X809400Y95900D01*
X813400D01*
X816292Y98792D01*
Y148856D01*
X817092Y149656D01*
X818292D01*
X819092Y148856D01*
Y133656D01*
X819892Y132856D01*
X821092D01*
X821892Y133656D01*
Y155881D01*
X906170Y240159D01*
X907500D01*
G01X806692Y87714D02*
X808081Y86325D01*
Y73312D01*
X808693Y72700D01*
Y71300D01*
X806893Y69500D01*
X805893D01*
X804593Y68200D01*
Y66946D01*
X803346Y65699D01*
G01X796653Y92757D02*
Y131400D01*
X797453Y132200D01*
X798653D01*
X799453Y131400D01*
Y116400D01*
X800253Y115600D01*
X801453D01*
X802253Y116400D01*
Y126953D01*
X806792Y131492D01*
Y141608D01*
X804400Y144000D01*
Y145700D01*
X806792Y148092D01*
Y151389D01*
X903062Y247659D01*
X908000D01*
G01X799999Y71900D02*
X798525Y73374D01*
Y74468D01*
X797092Y75901D01*
Y77124D01*
X798592Y78624D01*
Y79976D01*
X797092Y81476D01*
Y82599D01*
X798767Y84274D01*
Y85659D01*
X795725Y88701D01*
Y91829D01*
X796653Y92757D01*
G01X799999Y87714D02*
X801388Y86325D01*
Y73312D01*
X802000Y72700D01*
Y71300D01*
X800200Y69500D01*
X799200D01*
X797900Y68200D01*
Y66946D01*
X796653Y65699D01*
G01X908000Y245159D02*
X904098D01*
X809592Y150653D01*
Y130592D01*
X805092Y126092D01*
Y101239D01*
X803953Y100100D01*
X802753D01*
X801953Y100900D01*
Y112100D01*
X801153Y112900D01*
X799953D01*
X799153Y112100D01*
Y92117D01*
X798192Y91156D01*
Y89521D01*
X799999Y87714D01*
G01X816732Y92757D02*
X815611Y91636D01*
Y88700D01*
X818511Y85800D01*
Y83832D01*
X816978Y82299D01*
Y81100D01*
X818228Y79850D01*
Y78950D01*
X816878Y77600D01*
Y76301D01*
X818511Y74668D01*
Y72367D01*
X819378Y71500D01*
G01Y87714D02*
X820851Y86241D01*
Y73116D01*
X821467Y72500D01*
Y71156D01*
X820011Y69700D01*
X818611D01*
X816732Y67821D01*
Y65699D01*
G01X909454Y251394D02*
X901459D01*
X802812Y152747D01*
Y149472D01*
X801940Y148600D01*
X800701D01*
X799012Y146911D01*
Y143904D01*
X802312Y140604D01*
Y138808D01*
X800040Y136536D01*
X792800D01*
X791212Y134948D01*
Y98983D01*
X789734Y97505D01*
Y89268D01*
X791488Y87514D01*
G01D02*
Y87515D01*
X792586D01*
X793620Y86481D01*
Y83706D01*
X792914Y83000D01*
X792400D01*
X791700Y82300D01*
Y81300D01*
X792400Y80600D01*
X792900D01*
X793620Y79880D01*
Y78507D01*
X792813Y77700D01*
X792115D01*
X791514Y77099D01*
Y75901D01*
X792115Y75300D01*
X792913D01*
X793620Y74593D01*
Y71972D01*
X792597Y70949D01*
X791488D01*
G01X823199Y89900D02*
X826305Y86794D01*
Y70648D01*
X824977Y69320D01*
X823995D01*
X823225Y68550D01*
G01X828299Y87514D02*
Y87515D01*
X829397D01*
X830431Y86481D01*
Y83706D01*
X829725Y83000D01*
X829211D01*
X828511Y82300D01*
Y81300D01*
X829211Y80600D01*
X829711D01*
X830431Y79880D01*
Y78507D01*
X829624Y77700D01*
X828926D01*
X828325Y77099D01*
Y75901D01*
X828926Y75300D01*
X829724D01*
X830431Y74593D01*
Y71972D01*
X829408Y70949D01*
X828299D01*
G01X791488Y90114D02*
X793500Y92126D01*
Y93700D01*
X792500Y94700D01*
X791600D01*
X790794Y95506D01*
Y97062D01*
X792272Y98540D01*
Y99372D01*
X792892Y99992D01*
Y100992D01*
X792272Y101612D01*
Y102372D01*
X792892Y102992D01*
Y103992D01*
X792272Y104612D01*
Y105372D01*
X792892Y105992D01*
Y106992D01*
X792272Y107612D01*
Y108372D01*
X792892Y108992D01*
Y109992D01*
X792272Y110612D01*
Y111372D01*
X792892Y111992D01*
Y112992D01*
X792272Y113612D01*
Y134505D01*
X793243Y135476D01*
X800483D01*
X803372Y138365D01*
Y141047D01*
X800072Y144347D01*
Y146468D01*
X801144Y147540D01*
X802383D01*
X803872Y149029D01*
Y152304D01*
X901902Y250334D01*
X909454D01*
G01X791488Y68340D02*
X794680Y71532D01*
Y86922D01*
X791488Y90114D01*
G01X823199Y87300D02*
X824298D01*
X825245Y86353D01*
Y83820D01*
X824275Y82850D01*
X823927D01*
X823311Y82234D01*
Y80902D01*
X823813Y80400D01*
X824525D01*
X825245Y79680D01*
Y78720D01*
X824425Y77900D01*
X823925D01*
X823325Y77300D01*
Y76300D01*
X825245Y74380D01*
Y71091D01*
X824534Y70380D01*
X824018D01*
X823199Y71199D01*
G01X828299Y90114D02*
X831491Y86922D01*
Y71532D01*
X828299Y68340D01*
G01X912107Y363076D02*
X908636D01*
X872065Y399647D01*
Y407873D01*
X847500Y432438D01*
Y497300D01*
X850700Y500500D01*
Y504200D01*
X855200Y508700D01*
Y510900D01*
X852110Y513990D01*
Y516926D01*
X853341Y518157D01*
X853543D01*
G01X912844Y357831D02*
X908549D01*
X868295Y398085D01*
Y404505D01*
X842400Y430400D01*
Y505023D01*
X846361Y514587D01*
Y516976D01*
X846850Y518157D01*
G01X912872Y360381D02*
X908665D01*
X870180Y398866D01*
Y406198D01*
X844900Y431478D01*
Y500712D01*
X845460Y501272D01*
X848240D01*
X848800Y501832D01*
Y503272D01*
X848240Y503832D01*
X845660D01*
X845100Y504392D01*
Y505832D01*
X845660Y506392D01*
X848292D01*
X849896Y507996D01*
Y513114D01*
G01X909030Y351460D02*
X906464D01*
X863400Y394524D01*
Y400900D01*
X811800Y452500D01*
Y505100D01*
X811000Y505900D01*
X809400D01*
X808600Y505100D01*
Y489894D01*
X807774Y489068D01*
X806174D01*
X805400Y489842D01*
Y510895D01*
X801988Y514307D01*
Y516799D01*
X803346Y518157D01*
G01X909088Y354000D02*
X906591D01*
X865285Y395306D01*
Y401682D01*
X820788Y446179D01*
Y470600D01*
X819988Y471400D01*
X818388D01*
X817588Y470600D01*
Y453400D01*
X816788Y452600D01*
X815188D01*
X814388Y453400D01*
Y507000D01*
X813288Y508100D01*
X808488D01*
X807988Y508600D01*
Y511870D01*
X806692Y513166D01*
Y513114D01*
G01X908942Y347560D02*
X905032D01*
X859600Y392992D01*
Y399300D01*
X806800Y452100D01*
Y468070D01*
X806000Y468870D01*
X804400D01*
X803600Y468070D01*
Y455678D01*
X802826Y454904D01*
X801226D01*
X800400Y455730D01*
Y506300D01*
X798888Y507812D01*
Y510757D01*
X795988Y513657D01*
Y517492D01*
X796653Y518157D01*
G01X908942Y349616D02*
X905642D01*
X861500Y393758D01*
Y400100D01*
X809300Y452300D01*
Y486200D01*
X808400Y487100D01*
X806800D01*
X806100Y486400D01*
Y471863D01*
X805300Y471063D01*
X803700D01*
X802900Y471863D01*
Y507400D01*
X801388Y508912D01*
Y511768D01*
X801345D01*
X799999Y513114D01*
G01X791488Y512914D02*
X792886D01*
X793520Y512280D01*
Y509520D01*
X793000Y509000D01*
Y507600D01*
X793520Y507080D01*
Y505649D01*
X796420Y502749D01*
Y501192D01*
X795180Y499952D01*
X794009D01*
X792520Y498463D01*
Y495881D01*
X794009Y494392D01*
X795548D01*
X796420Y493520D01*
Y491824D01*
X795548Y490952D01*
X794209D01*
X792720Y489463D01*
Y486881D01*
X794209Y485392D01*
X795548D01*
X796420Y484520D01*
Y482824D01*
X795548Y481952D01*
X794409D01*
X792920Y480463D01*
Y477881D01*
X794409Y476392D01*
X795548D01*
X796420Y475520D01*
Y454248D01*
X800544Y450124D01*
X804576D01*
X856640Y398060D01*
Y391786D01*
X904609Y343817D01*
X908262D01*
G01Y344877D02*
X905049D01*
X857700Y392226D01*
Y398500D01*
X805016Y451184D01*
X800984D01*
X797480Y454688D01*
Y475960D01*
X795988Y477452D01*
X794852D01*
X793980Y478324D01*
Y480020D01*
X794852Y480892D01*
X795991D01*
X797480Y482381D01*
Y484963D01*
X795991Y486452D01*
X794652D01*
X793780Y487324D01*
Y489020D01*
X794652Y489892D01*
X795991D01*
X797480Y491381D01*
Y493963D01*
X795991Y495452D01*
X794452D01*
X793580Y496324D01*
Y498020D01*
X794452Y498892D01*
X795623D01*
X797480Y500749D01*
Y503192D01*
X794580Y506092D01*
Y512720D01*
X793326Y513974D01*
X793028D01*
X791488Y515514D01*
G01X843503Y535100D02*
X838452Y530049D01*
Y519862D01*
X840157Y518157D01*
G01X843503Y513114D02*
X843415D01*
X841729Y514800D01*
Y516492D01*
X841904Y516667D01*
Y519300D01*
X840792Y520412D01*
Y521488D01*
X841804Y522500D01*
Y523700D01*
X840792Y524712D01*
Y525788D01*
X841929Y526925D01*
Y528199D01*
X841229Y528899D01*
X840157D01*
G01X812999Y534700D02*
X812011D01*
X808956Y531645D01*
Y530457D01*
X808334Y529835D01*
Y519862D01*
X810039Y518157D01*
G01Y528899D02*
X811111D01*
X811711Y528299D01*
Y527401D01*
X810674Y526364D01*
Y525136D01*
X811611Y524199D01*
Y522801D01*
X810674Y521864D01*
Y520536D01*
X811811Y519399D01*
Y517500D01*
X811311Y517000D01*
Y514800D01*
X812997Y513114D01*
X813085D01*
G01X836810Y535100D02*
X831759Y530049D01*
Y519862D01*
X833464Y518157D01*
G01Y528899D02*
X834536D01*
X835236Y528199D01*
Y526925D01*
X834099Y525788D01*
Y524712D01*
X835111Y523700D01*
Y522500D01*
X834099Y521488D01*
Y520412D01*
X835211Y519300D01*
Y516667D01*
X835036Y516492D01*
Y514800D01*
X836722Y513114D01*
X836810D01*
G01X846850Y518157D02*
Y518849D01*
X845145Y520554D01*
Y529835D01*
X845767Y530457D01*
Y531645D01*
X848822Y534700D01*
X849810D01*
G01X849896Y513114D02*
X849808D01*
X848122Y514800D01*
Y517000D01*
X848622Y517500D01*
Y519399D01*
X847485Y520536D01*
Y521864D01*
X848422Y522801D01*
Y524199D01*
X847485Y525136D01*
Y526364D01*
X848522Y527401D01*
Y528299D01*
X847922Y528899D01*
X846850D01*
G01X803346Y518157D02*
X801641Y519862D01*
Y530049D01*
X806692Y535100D01*
G01Y513114D02*
X806604D01*
X804918Y514800D01*
Y516492D01*
X805093Y516667D01*
Y519300D01*
X803981Y520412D01*
Y521488D01*
X804993Y522500D01*
Y523700D01*
X803981Y524712D01*
Y525788D01*
X805118Y526925D01*
Y528199D01*
X804418Y528899D01*
X803346D01*
G01X796653Y518157D02*
X794948Y519862D01*
Y530049D01*
X799999Y535100D01*
G01Y513114D02*
X799911D01*
X798225Y514800D01*
Y516492D01*
X798400Y516667D01*
Y519300D01*
X797288Y520412D01*
Y521488D01*
X798300Y522500D01*
Y523700D01*
X797288Y524712D01*
Y525788D01*
X798425Y526925D01*
Y528199D01*
X797725Y528899D01*
X796653D01*
G01X819378Y534700D02*
X818212D01*
X815027Y531515D01*
Y519862D01*
X816732Y518157D01*
G01X819378Y513114D02*
X818286D01*
X817604Y513796D01*
Y516492D01*
X818511Y517399D01*
Y518992D01*
X817367Y520136D01*
Y521556D01*
X818211Y522400D01*
Y524100D01*
X817367Y524944D01*
Y526156D01*
X818311Y527100D01*
Y528300D01*
X817712Y528899D01*
X816732D01*
G01X791488Y534149D02*
X789783Y532444D01*
Y527500D01*
X788953Y526670D01*
Y520130D01*
X789783Y519300D01*
Y514331D01*
X791200Y512914D01*
X791488D01*
G01X823225Y531750D02*
X824930Y530045D01*
Y528139D01*
X824191Y527400D01*
X822911D01*
X822271Y526760D01*
Y525340D01*
X822821Y524790D01*
X823401D01*
X824011Y524180D01*
Y522790D01*
X823401Y522180D01*
X822791D01*
X822271Y521660D01*
Y520290D01*
X822861Y519700D01*
X823811D01*
X824911Y518600D01*
Y517012D01*
X823199Y515300D01*
G01X828299Y534149D02*
X826594Y532444D01*
Y527500D01*
X825764Y526670D01*
Y520130D01*
X826594Y519300D01*
Y514331D01*
X828011Y512914D01*
X828299D01*
G01X791488Y515514D02*
X793200Y517226D01*
Y518900D01*
X792200Y519900D01*
X790684D01*
X790013Y520571D01*
Y521848D01*
X790465Y522300D01*
X790800D01*
X791480Y522980D01*
Y524108D01*
X790790Y524798D01*
X790553D01*
X790013Y525338D01*
Y526229D01*
X790784Y527000D01*
X792300D01*
X793300Y528000D01*
Y529728D01*
X791488Y531540D01*
G01X823199Y534399D02*
X821211Y532411D01*
Y514400D01*
X822911Y512700D01*
X823199D01*
G01X828299Y531540D02*
X830111Y529728D01*
Y528000D01*
X829111Y527000D01*
X827595D01*
X826824Y526229D01*
Y525338D01*
X827364Y524798D01*
X827601D01*
X828311Y524088D01*
Y523000D01*
X827611Y522300D01*
X827276D01*
X826824Y521848D01*
Y520571D01*
X827495Y519900D01*
X829011D01*
X830011Y518900D01*
Y517226D01*
X828299Y515514D01*
G01X853543Y92757D02*
X850900Y95400D01*
Y97100D01*
X850200Y97800D01*
Y99885D01*
X850760Y100445D01*
X851740D01*
X852300Y101005D01*
Y102445D01*
X851740Y103005D01*
X850760D01*
X850200Y103565D01*
Y105005D01*
X850760Y105565D01*
X851740D01*
X852300Y106125D01*
Y107565D01*
X851740Y108125D01*
X850760D01*
X850200Y108685D01*
Y110125D01*
X850760Y110685D01*
X851740D01*
X852300Y111245D01*
Y112685D01*
X851740Y113245D01*
X850760D01*
X850200Y113805D01*
Y115245D01*
X850760Y115805D01*
X851740D01*
X852300Y116365D01*
Y117805D01*
X851740Y118365D01*
X850760D01*
X850200Y118925D01*
Y120365D01*
X850760Y120925D01*
X851740D01*
X852300Y121485D01*
Y122925D01*
X851740Y123485D01*
X850760D01*
X850200Y124045D01*
Y171336D01*
X906716Y227852D01*
X910448D01*
G01X856189Y71500D02*
X855322Y72367D01*
Y74668D01*
X853689Y76301D01*
Y77600D01*
X855039Y78950D01*
Y79850D01*
X853789Y81100D01*
Y82299D01*
X855322Y83832D01*
Y85800D01*
X852422Y88700D01*
Y91636D01*
X853543Y92757D01*
G01X856189Y87714D02*
X854292Y89611D01*
Y90992D01*
X855474Y92174D01*
Y93774D01*
X854392Y94856D01*
Y128373D01*
X852992Y129773D01*
Y168292D01*
X906700Y222000D01*
Y224300D01*
X907702Y225302D01*
X909817D01*
G01X853543Y65699D02*
Y67821D01*
X855422Y69700D01*
X856822D01*
X858278Y71156D01*
Y72500D01*
X857662Y73116D01*
Y86241D01*
X856189Y87714D01*
G01X917056Y205756D02*
X897900Y186600D01*
X894700D01*
X877353Y169253D01*
Y112600D01*
X876553Y111800D01*
X875353D01*
X874553Y112600D01*
Y132400D01*
X873753Y133200D01*
X872553D01*
X871692Y132339D01*
Y99056D01*
X876968Y93780D01*
Y92757D01*
G01D02*
X875847Y91636D01*
Y88700D01*
X879189Y85358D01*
Y84300D01*
X877389Y82500D01*
Y80925D01*
X878589Y79725D01*
Y78599D01*
X877389Y77399D01*
Y76026D01*
X878747Y74668D01*
Y73467D01*
X880314Y71900D01*
G01Y87714D02*
X881703Y86325D01*
Y73312D01*
X882315Y72700D01*
Y71300D01*
X880515Y69500D01*
X879515D01*
X878215Y68200D01*
Y66946D01*
X876968Y65699D01*
G01X918220Y203313D02*
X897507Y182600D01*
X894400D01*
X879853Y168053D01*
Y165442D01*
X880463Y164832D01*
X881590D01*
X882200Y164222D01*
Y162832D01*
X881590Y162222D01*
X880463D01*
X879853Y161612D01*
Y160222D01*
X880463Y159612D01*
X881590D01*
X882200Y159002D01*
Y157612D01*
X881590Y157002D01*
X880463D01*
X879853Y156392D01*
Y155002D01*
X880463Y154392D01*
X881590D01*
X882200Y153782D01*
Y152392D01*
X881590Y151782D01*
X880463D01*
X879853Y151172D01*
Y149782D01*
X880463Y149172D01*
X881590D01*
X882200Y148562D01*
Y147172D01*
X881590Y146562D01*
X880463D01*
X879853Y145952D01*
Y110400D01*
X879053Y109600D01*
X875053D01*
X874253Y108800D01*
Y99639D01*
X875053Y98839D01*
X877239D01*
X878253Y99853D01*
Y106440D01*
X878813Y107000D01*
X880493D01*
X881053Y106440D01*
Y98000D01*
X879192Y96139D01*
Y92000D01*
X878410Y91218D01*
Y89618D01*
X880314Y87714D01*
G01X870275Y92761D02*
Y94325D01*
X866592Y98008D01*
Y151930D01*
X867152Y152490D01*
X872340D01*
X872900Y153050D01*
Y154490D01*
X872340Y155050D01*
X867152D01*
X866592Y155610D01*
Y157050D01*
X867152Y157610D01*
X872340D01*
X872900Y158170D01*
Y159610D01*
X872340Y160170D01*
X867152D01*
X866592Y160730D01*
Y162170D01*
X867152Y162730D01*
X872340D01*
X872900Y163290D01*
Y164730D01*
X872340Y165290D01*
X867152D01*
X866592Y165850D01*
Y168192D01*
X894438Y196038D01*
X895230D01*
X896388Y194880D01*
X897180D01*
X898199Y195899D01*
Y196691D01*
X897041Y197849D01*
Y198641D01*
X900000Y201600D01*
X902400D01*
X913180Y212380D01*
X914216D01*
G01X873621Y71900D02*
X872147Y73374D01*
Y74468D01*
X870714Y75901D01*
Y77124D01*
X872214Y78624D01*
Y79976D01*
X870714Y81476D01*
Y82599D01*
X872389Y84274D01*
Y85659D01*
X869347Y88701D01*
Y91833D01*
X870275Y92761D01*
G01X873621Y87714D02*
X871792Y89543D01*
Y91092D01*
X872592Y91892D01*
Y95008D01*
X869192Y98408D01*
Y149594D01*
X869932Y150334D01*
X871132D01*
X872053Y149413D01*
Y135900D01*
X872853Y135100D01*
X874053D01*
X874853Y135900D01*
Y171653D01*
X894200Y191000D01*
X899400D01*
X912757Y204357D01*
Y208243D01*
X914344Y209830D01*
G01X870275Y65699D02*
X871522Y66946D01*
Y68200D01*
X872822Y69500D01*
X873822D01*
X875622Y71300D01*
Y72700D01*
X875010Y73312D01*
Y86325D01*
X873621Y87714D01*
G01X924669Y197103D02*
X898266Y170700D01*
X896899D01*
X890492Y164293D01*
Y144317D01*
X892500Y142309D01*
Y140277D01*
X891940Y139717D01*
X891292D01*
X890492Y138917D01*
Y137317D01*
X891292Y136517D01*
X892874D01*
X893674Y135717D01*
Y134117D01*
X892874Y133317D01*
X891292D01*
X890492Y132517D01*
Y130917D01*
X891292Y130117D01*
X892874D01*
X893674Y129317D01*
Y127717D01*
X892874Y126917D01*
X891292D01*
X890492Y126117D01*
Y124517D01*
X891292Y123717D01*
X892874D01*
X893674Y122917D01*
Y116274D01*
X892450Y115050D01*
Y111850D01*
X891074Y110474D01*
Y106174D01*
X892174Y105074D01*
Y103538D01*
X890354Y101718D01*
Y92757D01*
G01D02*
X889233Y91636D01*
Y88700D01*
X892133Y85800D01*
Y83832D01*
X890600Y82299D01*
Y81100D01*
X891850Y79850D01*
Y78950D01*
X890500Y77600D01*
Y76301D01*
X892133Y74668D01*
Y72367D01*
X893000Y71500D01*
G01X890354Y65699D02*
Y67821D01*
X892233Y69700D01*
X893633D01*
X895089Y71156D01*
Y72500D01*
X894473Y73116D01*
Y86241D01*
X893000Y87714D01*
G01D02*
X891074Y89640D01*
Y90974D01*
X892774Y92674D01*
Y100674D01*
X894924Y102824D01*
Y114024D01*
X896174Y115274D01*
Y142171D01*
X892992Y145353D01*
Y162758D01*
X898334Y168100D01*
X899273D01*
X927974Y196801D01*
G01X883661Y92757D02*
X885674Y94770D01*
Y96562D01*
X884692Y97544D01*
Y99762D01*
X885674Y100744D01*
Y104974D01*
X884674Y105974D01*
Y110674D01*
X885474Y111474D01*
Y115767D01*
X884864Y116377D01*
X883760D01*
X883150Y116987D01*
Y118377D01*
X883760Y118987D01*
X884864D01*
X885474Y119597D01*
Y120987D01*
X884864Y121597D01*
X883760D01*
X883150Y122207D01*
Y123597D01*
X883760Y124207D01*
X884864D01*
X885474Y124817D01*
Y126207D01*
X884864Y126817D01*
X884260D01*
X883700Y127377D01*
Y128867D01*
X884260Y129427D01*
X884864D01*
X885474Y130037D01*
Y169123D01*
X894151Y177800D01*
X898152D01*
X920331Y199979D01*
G01X886621Y71500D02*
X885533Y72588D01*
Y74468D01*
X884100Y75901D01*
Y77100D01*
X885600Y78600D01*
Y79800D01*
X884150Y81250D01*
Y82649D01*
X885533Y84032D01*
Y85901D01*
X882733Y88701D01*
Y91829D01*
X883661Y92757D01*
G01Y65699D02*
Y67253D01*
X885908Y69500D01*
X887132D01*
X888708Y71076D01*
Y72700D01*
X887933Y73475D01*
Y86488D01*
X886707Y87714D01*
G01D02*
X886535D01*
X884674Y89575D01*
Y91074D01*
X888174Y94574D01*
Y106174D01*
X888574Y106574D01*
Y111074D01*
X887992Y111656D01*
Y113931D01*
X888792Y114731D01*
X889392D01*
X889900Y115239D01*
Y117223D01*
X889192Y117931D01*
X888792D01*
X887992Y118731D01*
Y119656D01*
X889292Y120956D01*
Y122181D01*
X887992Y123481D01*
Y168105D01*
X894187Y174300D01*
X898259D01*
X921363Y197404D01*
G01X940145Y193852D02*
X916150Y169857D01*
Y165352D01*
X915540Y164742D01*
X911910D01*
X911300Y164132D01*
Y162742D01*
X911910Y162132D01*
X915540D01*
X916150Y161522D01*
Y160132D01*
X915540Y159522D01*
X909810D01*
X909200Y158912D01*
Y157522D01*
X909810Y156912D01*
X912140D01*
X912700Y156352D01*
Y154310D01*
X912140Y153750D01*
X908284D01*
X907674Y153140D01*
Y136126D01*
X908492Y135308D01*
Y113838D01*
X909174Y113156D01*
Y111674D01*
X908274Y110774D01*
Y105974D01*
X909074Y105174D01*
Y103438D01*
X908042Y102406D01*
Y95242D01*
X907086Y94286D01*
Y92757D01*
G01D02*
X906158Y91829D01*
Y88701D01*
X909200Y85659D01*
Y84274D01*
X907525Y82599D01*
Y81476D01*
X909025Y79976D01*
Y78624D01*
X907525Y77124D01*
Y75901D01*
X908958Y74468D01*
Y73374D01*
X910432Y71900D01*
G01X907086Y65699D02*
X908333Y66946D01*
Y68200D01*
X909633Y69500D01*
X910633D01*
X912433Y71300D01*
Y72700D01*
X911821Y73312D01*
Y86325D01*
X910432Y87714D01*
G01D02*
X908624Y89522D01*
Y91424D01*
X910824Y93624D01*
Y101588D01*
X911574Y102338D01*
Y105474D01*
X912340Y106240D01*
Y110808D01*
X911774Y111374D01*
Y114456D01*
X910992Y115238D01*
Y136408D01*
X910174Y137226D01*
Y147440D01*
X910734Y148000D01*
X913300D01*
X918300Y153000D01*
Y168626D01*
X941672Y191998D01*
X941899D01*
G01X860010Y89900D02*
X861736Y91626D01*
Y93700D01*
X860936Y94500D01*
X859768D01*
X858172Y96096D01*
Y97024D01*
X858792Y97644D01*
Y98644D01*
X858172Y99264D01*
Y100024D01*
X858792Y100644D01*
Y101644D01*
X858172Y102264D01*
Y103024D01*
X858792Y103644D01*
Y104644D01*
X858172Y105264D01*
Y106024D01*
X858792Y106644D01*
Y107644D01*
X858172Y108264D01*
Y129800D01*
X856772Y131200D01*
Y148605D01*
X857552Y149385D01*
X859331D01*
X860750Y150804D01*
Y154256D01*
X859261Y155745D01*
X856902D01*
X856200Y156447D01*
Y159113D01*
X857072Y159985D01*
X858580D01*
X860072Y161477D01*
Y163928D01*
X857680Y166320D01*
Y167180D01*
X860072Y169572D01*
Y171121D01*
X878978Y190027D01*
X879478D01*
X880323Y190872D01*
Y191372D01*
X881053Y192102D01*
X881601D01*
X882398Y192899D01*
Y193447D01*
X883098Y194147D01*
X883806D01*
X884442Y194783D01*
Y195491D01*
X885078Y196127D01*
X885786D01*
X886423Y196764D01*
Y197472D01*
X887103Y198152D01*
X887811D01*
X888448Y198789D01*
Y199497D01*
X889103Y200152D01*
X889811D01*
X890448Y200789D01*
Y201497D01*
X891528Y202577D01*
X892236D01*
X892873Y203214D01*
Y203922D01*
X893703Y204752D01*
X894411D01*
X895048Y205389D01*
Y206097D01*
X895903Y206952D01*
X896611D01*
X897248Y207589D01*
Y208297D01*
X898018Y209067D01*
X898726D01*
X899362Y209703D01*
Y210411D01*
X899998Y211047D01*
X900706D01*
X901342Y211683D01*
Y212391D01*
X901978Y213027D01*
X902686D01*
X903323Y213664D01*
Y214372D01*
X904016Y215065D01*
X904724D01*
X905360Y215701D01*
Y216409D01*
X905996Y217045D01*
X906704D01*
X907340Y217681D01*
Y218389D01*
X907976Y219025D01*
G01X860036Y68550D02*
X860806Y69320D01*
X861788D01*
X863116Y70648D01*
Y86794D01*
X860010Y89900D01*
G01X896847Y68550D02*
X897617Y69320D01*
X898599D01*
X899927Y70648D01*
Y86794D01*
X896821Y89900D01*
G01D02*
X898547Y91626D01*
Y93452D01*
X897499Y94500D01*
X896747D01*
X896027Y95220D01*
Y96888D01*
X899854Y100715D01*
Y115630D01*
X900474Y116250D01*
Y117800D01*
X899854Y118420D01*
Y119180D01*
X900474Y119800D01*
Y120800D01*
X899854Y121420D01*
Y122180D01*
X900474Y122800D01*
Y123800D01*
X899854Y124420D01*
Y125180D01*
X900474Y125800D01*
Y126800D01*
X899854Y127420D01*
Y132622D01*
X900172Y132940D01*
Y144319D01*
X898783Y145708D01*
X897844D01*
X896972Y146580D01*
Y149076D01*
X897844Y149948D01*
X899683D01*
X901172Y151437D01*
Y154819D01*
X899683Y156308D01*
X897844D01*
X896972Y157180D01*
Y159676D01*
X897844Y160548D01*
X899683D01*
X901172Y162037D01*
Y164672D01*
X911878Y175378D01*
X912428D01*
X913222Y176172D01*
Y176722D01*
X913978Y177478D01*
X914428D01*
X915322Y178372D01*
Y178822D01*
X915998Y179498D01*
X916750D01*
X917342Y180090D01*
Y180842D01*
X917978Y181478D01*
X918730D01*
X919322Y182070D01*
Y182822D01*
X919993Y183493D01*
X920745D01*
X921337Y184085D01*
Y184837D01*
X921973Y185473D01*
X922725D01*
X923317Y186065D01*
Y186817D01*
X923953Y187453D01*
X924705D01*
X925297Y188045D01*
Y188797D01*
X926053Y189553D01*
X926805D01*
X927397Y190145D01*
Y190897D01*
X928476Y191976D01*
X929228D01*
X929820Y192568D01*
Y193320D01*
X930456Y193956D01*
X930476D01*
G01X915069Y218396D02*
X912630D01*
X862812Y168578D01*
Y147764D01*
X861940Y146892D01*
X861301D01*
X859512Y145103D01*
Y142021D01*
X861001Y140532D01*
X861940D01*
X862812Y139660D01*
Y137164D01*
X861940Y136292D01*
X861397D01*
X859812Y134707D01*
Y132324D01*
X862812Y129324D01*
Y126400D01*
X860600Y124188D01*
Y121112D01*
X862812Y118900D01*
Y115012D01*
X862044Y114244D01*
Y96721D01*
X863386Y95379D01*
Y89238D01*
X865110Y87514D01*
G01D02*
Y87515D01*
X866208D01*
X867242Y86481D01*
Y83706D01*
X866536Y83000D01*
X866022D01*
X865322Y82300D01*
Y81300D01*
X866022Y80600D01*
X866522D01*
X867242Y79880D01*
Y78507D01*
X866435Y77700D01*
X865737D01*
X865136Y77099D01*
Y75901D01*
X865737Y75300D01*
X866535D01*
X867242Y74593D01*
Y71972D01*
X866219Y70949D01*
X865110D01*
G01X935423Y194683D02*
Y193297D01*
X903994Y161868D01*
Y100158D01*
X900667Y96831D01*
Y94567D01*
X900197Y94097D01*
Y89238D01*
X901921Y87514D01*
G01D02*
Y87515D01*
X903019D01*
X904053Y86481D01*
Y83706D01*
X903347Y83000D01*
X902833D01*
X902133Y82300D01*
Y81300D01*
X902833Y80600D01*
X903333D01*
X904053Y79880D01*
Y78507D01*
X903246Y77700D01*
X902548D01*
X901947Y77099D01*
Y75901D01*
X902548Y75300D01*
X903346D01*
X904053Y74593D01*
Y71972D01*
X903030Y70949D01*
X901921D01*
G01X907226Y219775D02*
X859012Y171561D01*
Y170012D01*
X856620Y167620D01*
Y165880D01*
X859012Y163488D01*
Y161917D01*
X858140Y161045D01*
X856632D01*
X855140Y159553D01*
Y156007D01*
X856462Y154685D01*
X858821D01*
X859690Y153816D01*
Y151244D01*
X858891Y150445D01*
X857109D01*
X855712Y149048D01*
Y130757D01*
X857112Y129357D01*
Y95653D01*
X858036Y94729D01*
Y89274D01*
X860010Y87300D01*
G01D02*
X861109D01*
X862056Y86353D01*
Y83820D01*
X861086Y82850D01*
X860738D01*
X860122Y82234D01*
Y80902D01*
X860624Y80400D01*
X861336D01*
X862056Y79680D01*
Y78720D01*
X861236Y77900D01*
X860736D01*
X860136Y77300D01*
Y76300D01*
X862056Y74380D01*
Y71091D01*
X861345Y70380D01*
X860829D01*
X860010Y71199D01*
G01X929600Y194600D02*
X900112Y165112D01*
Y162477D01*
X899243Y161608D01*
X897401D01*
X895912Y160119D01*
Y156737D01*
X897401Y155248D01*
X899240D01*
X900112Y154376D01*
Y151880D01*
X899240Y151008D01*
X897401D01*
X895912Y149519D01*
Y146137D01*
X897401Y144648D01*
X898340D01*
X899112Y143876D01*
Y133383D01*
X898794Y133065D01*
Y101158D01*
X894967Y97331D01*
Y89154D01*
X896821Y87300D01*
G01D02*
X897920D01*
X898867Y86353D01*
Y83820D01*
X897897Y82850D01*
X897549D01*
X896933Y82234D01*
Y80902D01*
X897435Y80400D01*
X898147D01*
X898867Y79680D01*
Y78720D01*
X898047Y77900D01*
X897547D01*
X896947Y77300D01*
Y76300D01*
X898867Y74380D01*
Y71091D01*
X898156Y70380D01*
X897640D01*
X896821Y71199D01*
G01X865110Y90114D02*
X866936Y91940D01*
Y93332D01*
X863104Y97164D01*
Y98092D01*
X863724Y98712D01*
Y99712D01*
X863104Y100332D01*
Y101092D01*
X863724Y101712D01*
Y102712D01*
X863104Y103332D01*
Y104092D01*
X863724Y104712D01*
Y105712D01*
X863104Y106332D01*
Y107092D01*
X863724Y107712D01*
Y108712D01*
X863104Y109332D01*
Y110180D01*
X863724Y110800D01*
Y111800D01*
X863104Y112420D01*
Y113804D01*
X863872Y114572D01*
Y119340D01*
X861660Y121552D01*
Y123748D01*
X863872Y125960D01*
Y129764D01*
X860872Y132764D01*
Y134264D01*
X861840Y135232D01*
X862383D01*
X863872Y136721D01*
Y140103D01*
X862383Y141592D01*
X861444D01*
X860572Y142464D01*
Y144660D01*
X861744Y145832D01*
X862383D01*
X863872Y147321D01*
Y168138D01*
X900455Y204721D01*
X901163D01*
X901799Y205357D01*
Y206065D01*
X902435Y206701D01*
X903143D01*
X903779Y207337D01*
Y208045D01*
X904415Y208681D01*
X905123D01*
X905759Y209317D01*
Y210025D01*
X906395Y210661D01*
X907103D01*
X907739Y211297D01*
Y212005D01*
X908915Y213181D01*
X909623D01*
X910259Y213817D01*
Y214525D01*
X910895Y215161D01*
X911603D01*
X912239Y215797D01*
Y216505D01*
X913070Y217336D01*
X915069D01*
G01X865110Y68340D02*
X868302Y71532D01*
Y86922D01*
X865110Y90114D01*
G01X901921Y68340D02*
X905113Y71532D01*
Y86922D01*
X901921Y90114D01*
G01D02*
X903747Y91940D01*
Y93500D01*
X901727Y95520D01*
Y96388D01*
X902701Y97362D01*
X903577D01*
X904285Y98070D01*
Y98946D01*
X905054Y99715D01*
Y113280D01*
X905674Y113900D01*
Y114900D01*
X905054Y115520D01*
Y116280D01*
X905674Y116900D01*
Y117900D01*
X905054Y118520D01*
Y119280D01*
X905674Y119900D01*
Y120900D01*
X905054Y121520D01*
Y122280D01*
X905674Y122900D01*
Y123900D01*
X905054Y124520D01*
Y125280D01*
X905674Y125900D01*
Y126900D01*
X905054Y127520D01*
Y161428D01*
X936483Y192857D01*
Y194683D01*
G01X912107Y365627D02*
X908751D01*
X873950Y400428D01*
Y409524D01*
X850100Y433374D01*
Y485646D01*
X850660Y486206D01*
X854040D01*
X854600Y486766D01*
Y488206D01*
X854040Y488766D01*
X850660D01*
X850100Y489326D01*
Y490766D01*
X850660Y491326D01*
X854040D01*
X854600Y491886D01*
Y493326D01*
X854040Y493886D01*
X850660D01*
X850100Y494446D01*
Y496300D01*
X850900Y497100D01*
X852500D01*
X853300Y497900D01*
Y503600D01*
X857700Y508000D01*
Y511603D01*
X856189Y513114D01*
G01X904586Y391041D02*
X887962Y407665D01*
Y418875D01*
X878600Y428237D01*
Y464000D01*
X874200Y468400D01*
Y474400D01*
X873700Y474900D01*
X870000D01*
X869200Y475700D01*
Y477166D01*
X869760Y477726D01*
X872940D01*
X873500Y478286D01*
Y479726D01*
X872940Y480286D01*
X869760D01*
X869200Y480846D01*
Y482286D01*
X869760Y482846D01*
X872940D01*
X873500Y483406D01*
Y484846D01*
X872940Y485406D01*
X869760D01*
X869200Y485966D01*
Y487406D01*
X869760Y487966D01*
X872940D01*
X873500Y488526D01*
Y489966D01*
X872940Y490526D01*
X869760D01*
X869200Y491086D01*
Y492526D01*
X869760Y493086D01*
X872940D01*
X873500Y493646D01*
Y495086D01*
X872940Y495646D01*
X869760D01*
X869200Y496206D01*
Y497500D01*
X871400Y499700D01*
X877300D01*
X878000Y500400D01*
Y505600D01*
X879010Y506610D01*
Y510907D01*
X875610Y514307D01*
Y516799D01*
X876968Y518157D01*
G01X906356Y392878D02*
X890482Y408752D01*
Y419919D01*
X889805Y420596D01*
Y421458D01*
X890891Y422545D01*
Y423407D01*
X889490Y424808D01*
X888628D01*
X887542Y423721D01*
X886680D01*
X885279Y425122D01*
Y425984D01*
X886365Y427071D01*
Y427933D01*
X884964Y429334D01*
X884102D01*
X883016Y428247D01*
X882154D01*
X880500Y429901D01*
Y468017D01*
X879940Y468577D01*
X876660D01*
X876100Y469137D01*
Y470577D01*
X876660Y471137D01*
X879940D01*
X880500Y471697D01*
Y473137D01*
X879940Y473697D01*
X876660D01*
X876100Y474257D01*
Y475697D01*
X876660Y476257D01*
X879940D01*
X880500Y476817D01*
Y478257D01*
X879940Y478817D01*
X876660D01*
X876100Y479377D01*
Y480817D01*
X876660Y481377D01*
X879940D01*
X880500Y481937D01*
Y483377D01*
X879940Y483937D01*
X876660D01*
X876100Y484497D01*
Y485937D01*
X876660Y486497D01*
X879940D01*
X880500Y487057D01*
Y488497D01*
X879940Y489057D01*
X876660D01*
X876100Y489617D01*
Y491057D01*
X876660Y491617D01*
X879940D01*
X880500Y492177D01*
Y493617D01*
X879940Y494177D01*
X876660D01*
X876100Y494737D01*
Y496177D01*
X876660Y496737D01*
X879940D01*
X880500Y497297D01*
Y504100D01*
X881610Y505210D01*
Y511870D01*
X880314Y513166D01*
Y513114D01*
G01X906008Y382405D02*
X882800Y405613D01*
Y416736D01*
X870400Y429136D01*
Y434100D01*
X869200Y435300D01*
Y436600D01*
X870400Y437800D01*
Y455300D01*
X869600Y456100D01*
X868000D01*
X867200Y455300D01*
Y446700D01*
X866400Y445900D01*
X864900D01*
X864100Y446700D01*
Y499299D01*
X870401Y505600D01*
X872600D01*
X873300Y506300D01*
Y508100D01*
X872200Y509200D01*
Y511067D01*
X868800Y514467D01*
Y516686D01*
X870275Y518161D01*
G01X907712Y384308D02*
X907593D01*
X885346Y406555D01*
Y417791D01*
X876700Y426437D01*
Y435577D01*
X876140Y436137D01*
X873060D01*
X872500Y436697D01*
Y438137D01*
X873060Y438697D01*
X876140D01*
X876700Y439257D01*
Y440697D01*
X876140Y441257D01*
X873060D01*
X872500Y441817D01*
Y443257D01*
X873060Y443817D01*
X876140D01*
X876700Y444377D01*
Y445817D01*
X876140Y446377D01*
X873060D01*
X872500Y446937D01*
Y448377D01*
X873060Y448937D01*
X876140D01*
X876700Y449497D01*
Y450937D01*
X876140Y451497D01*
X873060D01*
X872500Y452057D01*
Y453497D01*
X873060Y454057D01*
X876140D01*
X876700Y454617D01*
Y456057D01*
X876140Y456617D01*
X873060D01*
X872500Y457177D01*
Y458617D01*
X873060Y459177D01*
X876140D01*
X876700Y459737D01*
Y463200D01*
X872300Y467600D01*
Y472500D01*
X871800Y473000D01*
X867100D01*
X866600Y473500D01*
Y498200D01*
X870300Y501900D01*
X873500D01*
X874350Y502750D01*
Y504650D01*
X876200Y506500D01*
Y508200D01*
X875010Y509390D01*
Y511768D01*
X874967D01*
X873621Y513114D01*
G01X905358Y403509D02*
X897550Y411317D01*
Y424687D01*
X886449Y435788D01*
Y460749D01*
X888200Y462500D01*
Y477800D01*
X885600Y480400D01*
Y488800D01*
X884774Y489626D01*
Y502075D01*
X885500Y502801D01*
Y510928D01*
X882200Y514228D01*
Y517356D01*
X883001Y518157D01*
X883661D01*
G01X886707Y513114D02*
X887587D01*
X888400Y512301D01*
Y509196D01*
X887200Y507996D01*
Y505996D01*
X888400Y504796D01*
Y502796D01*
X887200Y501596D01*
Y495200D01*
X888300Y494100D01*
Y489100D01*
X891200Y486200D01*
Y485159D01*
X890590Y484549D01*
X888510D01*
X887900Y483939D01*
Y481959D01*
X888510Y481349D01*
X890590D01*
X891200Y480739D01*
Y462301D01*
X888449Y459550D01*
Y437324D01*
X900050Y425723D01*
Y412424D01*
X907161Y405313D01*
G01X907939Y371551D02*
X876895Y402595D01*
Y412073D01*
X854180Y434788D01*
Y447848D01*
X857377Y451045D01*
Y454596D01*
X855668Y456305D01*
Y458141D01*
X857580Y460053D01*
Y502922D01*
X858506Y503848D01*
X859384D01*
X859795Y504260D01*
X860091Y504556D01*
Y505433D01*
X860798Y506140D01*
X861676D01*
X862383Y506848D01*
Y507725D01*
X863090Y508432D01*
Y512220D01*
X860010Y515300D01*
G01X865110Y512914D02*
X866210D01*
X867130Y511994D01*
Y507562D01*
X866083Y506515D01*
X865205D01*
X864498Y505808D01*
Y504930D01*
X863762Y504194D01*
X862884D01*
X862177Y503487D01*
Y502609D01*
X860420Y500852D01*
Y499652D01*
X859820Y499052D01*
Y498012D01*
X860420Y497412D01*
Y496412D01*
X859820Y495812D01*
Y494772D01*
X860420Y494172D01*
Y493172D01*
X859820Y492572D01*
Y491532D01*
X860420Y490932D01*
Y489932D01*
X859820Y489332D01*
Y488292D01*
X860420Y487692D01*
Y486692D01*
X859820Y486092D01*
Y485052D01*
X860420Y484452D01*
Y483452D01*
X859820Y482852D01*
Y481812D01*
X860420Y481212D01*
Y480053D01*
X860000Y479633D01*
Y478577D01*
X860420Y478157D01*
Y449660D01*
X857720Y446960D01*
Y443776D01*
X859376Y442120D01*
X865847D01*
X866720Y441247D01*
Y439698D01*
X865848Y438826D01*
X859397D01*
X857908Y437337D01*
Y434755D01*
X859397Y433266D01*
X865848D01*
X866720Y432394D01*
Y426162D01*
X878780Y414102D01*
Y404460D01*
X903413Y379826D01*
G01X860010Y512700D02*
X861110D01*
X862030Y511780D01*
Y508872D01*
X856520Y503362D01*
Y460493D01*
X854608Y458581D01*
Y455865D01*
X856317Y454156D01*
Y451488D01*
X853120Y448291D01*
Y444015D01*
X852720Y443615D01*
Y441785D01*
X853120Y441385D01*
Y434348D01*
X875835Y411633D01*
Y402155D01*
X907189Y370801D01*
G01X904164Y380578D02*
X879840Y404904D01*
Y414542D01*
X867780Y426602D01*
Y432834D01*
X866288Y434326D01*
X859837D01*
X858968Y435195D01*
Y436897D01*
X859837Y437766D01*
X866288D01*
X867780Y439258D01*
Y441690D01*
X866290Y443180D01*
X859816D01*
X858780Y444216D01*
Y446520D01*
X861480Y449220D01*
Y500409D01*
X868190Y507119D01*
Y512434D01*
X865110Y515514D01*
G01X909416Y406667D02*
X902550Y413533D01*
Y426759D01*
X890539Y438770D01*
Y458239D01*
X893300Y461000D01*
Y488042D01*
X890900Y490442D01*
Y505600D01*
X891900Y506600D01*
Y511228D01*
X889585Y513543D01*
Y517388D01*
X890354Y518157D01*
G01X911268Y408422D02*
X905106Y414584D01*
Y427818D01*
X896000Y436924D01*
Y439985D01*
X895390Y440595D01*
X893910D01*
X893300Y441205D01*
Y443185D01*
X893910Y443795D01*
X895390D01*
X896000Y444405D01*
Y446385D01*
X895390Y446995D01*
X893210D01*
X892600Y447605D01*
Y449585D01*
X893210Y450195D01*
X895390D01*
X896000Y450805D01*
Y452785D01*
X895390Y453395D01*
X893210D01*
X892600Y454005D01*
Y455985D01*
X893210Y456595D01*
X895390D01*
X896000Y457205D01*
Y487900D01*
X894974Y488926D01*
Y511140D01*
X893000Y513114D01*
G01X923652Y410161D02*
X916000Y417813D01*
Y431545D01*
X909800Y437745D01*
Y466700D01*
X907200Y469300D01*
Y478901D01*
X908000Y479701D01*
X909140D01*
X909800Y480361D01*
Y481761D01*
X909300Y482261D01*
X907760D01*
X907200Y482821D01*
Y484261D01*
X907760Y484821D01*
X909140D01*
X909800Y485481D01*
Y486881D01*
X909300Y487381D01*
X907760D01*
X907200Y487941D01*
Y492999D01*
X909321Y495120D01*
Y510757D01*
X906421Y513657D01*
Y517492D01*
X907086Y518157D01*
G01X919227Y405641D02*
X911408Y413459D01*
X908719Y416148D01*
Y429550D01*
X899816Y438453D01*
Y512305D01*
X896821Y515300D01*
G01X916204Y412416D02*
X912250Y416370D01*
Y430019D01*
X903782Y438487D01*
Y441851D01*
X906120Y444189D01*
Y445252D01*
X903212Y448160D01*
Y449745D01*
X906020Y452553D01*
Y454249D01*
X905148Y455121D01*
X903335D01*
X902032Y456424D01*
Y459006D01*
X903707Y460681D01*
X905327D01*
X906120Y461474D01*
Y462593D01*
X905500Y463213D01*
Y464213D01*
X906120Y464833D01*
Y465945D01*
X904241Y467824D01*
Y469246D01*
X903621Y469866D01*
Y470866D01*
X904241Y471486D01*
Y472486D01*
X903621Y473106D01*
Y474106D01*
X904241Y474726D01*
Y475726D01*
X903621Y476346D01*
Y477346D01*
X904241Y477966D01*
Y478966D01*
X903621Y479586D01*
Y480586D01*
X904241Y481206D01*
Y482206D01*
X903621Y482826D01*
Y483826D01*
X904241Y484446D01*
Y485446D01*
X903621Y486066D01*
Y487066D01*
X904241Y487686D01*
Y488686D01*
X903621Y489306D01*
Y490306D01*
X904241Y490926D01*
Y491939D01*
X903634Y492546D01*
Y493546D01*
X904241Y494153D01*
Y495312D01*
X903635Y495918D01*
Y496918D01*
X904241Y497524D01*
Y498406D01*
X903621Y499026D01*
Y500026D01*
X904241Y500646D01*
Y501646D01*
X903621Y502266D01*
Y503266D01*
X904241Y503886D01*
Y504886D01*
X903621Y505506D01*
Y506506D01*
X904241Y507126D01*
Y508126D01*
X903621Y508746D01*
Y509746D01*
X904241Y510366D01*
Y511694D01*
X903021Y512914D01*
X901921D01*
G01X918477Y404890D02*
X907659Y415708D01*
Y429110D01*
X898756Y438013D01*
Y503652D01*
X898229Y504179D01*
Y505179D01*
X898756Y505706D01*
Y506799D01*
X898136Y507419D01*
Y508419D01*
X898756Y509039D01*
Y511744D01*
X897800Y512700D01*
X896821D01*
G01X916955Y413165D02*
X913310Y416810D01*
Y430459D01*
X904842Y438927D01*
Y441411D01*
X907180Y443749D01*
Y445692D01*
X904272Y448600D01*
Y449305D01*
X907080Y452113D01*
Y454692D01*
X905591Y456181D01*
X903775D01*
X903092Y456864D01*
Y458566D01*
X904147Y459621D01*
X905767D01*
X907180Y461034D01*
Y466385D01*
X905301Y468264D01*
Y512134D01*
X901921Y515514D01*
G01X853543Y518157D02*
X851838Y519862D01*
Y531515D01*
X855023Y534700D01*
X856189D01*
G01Y513114D02*
X856101D01*
X854415Y514800D01*
Y516492D01*
X855322Y517399D01*
Y518992D01*
X854178Y520136D01*
Y521556D01*
X855022Y522400D01*
Y524100D01*
X854178Y524944D01*
Y526156D01*
X855122Y527100D01*
Y528300D01*
X854523Y528899D01*
X853543D01*
G01X876968Y518157D02*
X875263Y519862D01*
Y530049D01*
X880314Y535100D01*
G01Y513114D02*
X880226D01*
X878540Y514800D01*
Y516492D01*
X878715Y516667D01*
Y519300D01*
X877603Y520412D01*
Y521488D01*
X878615Y522500D01*
Y523700D01*
X877603Y524712D01*
Y525788D01*
X878740Y526925D01*
Y528199D01*
X878040Y528899D01*
X876968D01*
G01X870275Y518161D02*
X868570Y519866D01*
Y530049D01*
X873621Y535100D01*
G01Y513114D02*
X873533D01*
X871847Y514800D01*
Y516492D01*
X872022Y516667D01*
Y519300D01*
X870910Y520412D01*
Y521488D01*
X871922Y522500D01*
Y523700D01*
X870910Y524712D01*
Y525788D01*
X872047Y526925D01*
Y528199D01*
X871347Y528899D01*
X870275D01*
G01X890354Y518157D02*
X888649Y519862D01*
Y531515D01*
X891834Y534700D01*
X893000D01*
G01Y513114D02*
X892912D01*
X891226Y514800D01*
Y516492D01*
X892133Y517399D01*
Y518992D01*
X890989Y520136D01*
Y521556D01*
X891833Y522400D01*
Y524100D01*
X890989Y524944D01*
Y526156D01*
X891933Y527100D01*
Y528300D01*
X891334Y528899D01*
X890354D01*
G01X883661Y518157D02*
X881956Y519862D01*
Y529835D01*
X882578Y530457D01*
Y531645D01*
X885633Y534700D01*
X886621D01*
G01X883661Y528899D02*
X884733D01*
X885333Y528299D01*
Y527401D01*
X884296Y526364D01*
Y525136D01*
X885233Y524199D01*
Y522801D01*
X884296Y521864D01*
Y520536D01*
X885433Y519399D01*
Y517500D01*
X884933Y517000D01*
Y514800D01*
X886619Y513114D01*
X886707D01*
G01X907086Y518157D02*
X905381Y519862D01*
Y530049D01*
X910432Y535100D01*
G01Y513114D02*
X910344D01*
X908658Y514800D01*
Y516492D01*
X908833Y516667D01*
Y519300D01*
X907721Y520412D01*
Y521488D01*
X908733Y522500D01*
Y523700D01*
X907721Y524712D01*
Y525788D01*
X908858Y526925D01*
Y528199D01*
X908158Y528899D01*
X907086D01*
G01X860010Y515300D02*
X861722Y517012D01*
Y518600D01*
X860622Y519700D01*
X859672D01*
X859082Y520290D01*
Y521660D01*
X859602Y522180D01*
X860305D01*
X860915Y522790D01*
Y524180D01*
X860305Y524790D01*
X859632D01*
X859082Y525340D01*
Y526760D01*
X859722Y527400D01*
X860722D01*
X861741Y528419D01*
Y530045D01*
X860036Y531750D01*
G01X896821Y515300D02*
X898533Y517012D01*
Y518600D01*
X897433Y519700D01*
X896483D01*
X895893Y520290D01*
Y521660D01*
X896413Y522180D01*
X897023D01*
X897633Y522790D01*
Y524180D01*
X897023Y524790D01*
X896443D01*
X895893Y525340D01*
Y526760D01*
X896533Y527400D01*
X897813D01*
X898552Y528139D01*
Y530045D01*
X896847Y531750D01*
G01X865110Y534149D02*
X863405Y532444D01*
Y527500D01*
X862575Y526670D01*
Y520130D01*
X863405Y519300D01*
Y514331D01*
X864822Y512914D01*
X865110D01*
G01X901921D02*
X901633D01*
X900216Y514331D01*
Y519300D01*
X899386Y520130D01*
Y526670D01*
X900216Y527500D01*
Y532444D01*
X901921Y534149D01*
G01X860010Y534399D02*
X858022Y532411D01*
Y514400D01*
X859722Y512700D01*
X860010D01*
G01X896821D02*
X896533D01*
X894833Y514400D01*
Y532411D01*
X896821Y534399D01*
G01X865110Y515514D02*
X866822Y517226D01*
Y518900D01*
X865822Y519900D01*
X864306D01*
X863635Y520571D01*
Y521848D01*
X864087Y522300D01*
X864422D01*
X865122Y523000D01*
Y524088D01*
X864412Y524798D01*
X864175D01*
X863635Y525338D01*
Y526229D01*
X864406Y527000D01*
X865922D01*
X866922Y528000D01*
Y529728D01*
X865110Y531540D01*
G01X901921Y515514D02*
X903633Y517226D01*
Y518900D01*
X902633Y519900D01*
X901117D01*
X900446Y520571D01*
Y521848D01*
X900898Y522300D01*
X901233D01*
X901933Y523000D01*
Y524088D01*
X901223Y524798D01*
X900986D01*
X900446Y525338D01*
Y526229D01*
X901217Y527000D01*
X902733D01*
X903733Y528000D01*
Y529728D01*
X901921Y531540D01*
G01X970669Y-7108D02*
Y-4669D01*
X968964Y-2964D01*
Y1448D01*
X969574Y2058D01*
X970625D01*
X971235Y2668D01*
Y4568D01*
X970625Y5178D01*
X969574D01*
X968964Y5788D01*
Y14464D01*
X970669Y16169D01*
Y17057D01*
G01X994906Y200336D02*
Y125303D01*
X979200Y109597D01*
Y102500D01*
X972500Y95800D01*
Y91714D01*
X972215Y91429D01*
Y89069D01*
X972469Y88815D01*
Y85883D01*
X972060Y85474D01*
Y75859D01*
X972396Y75523D01*
Y72695D01*
X972700Y72391D01*
Y67199D01*
X972380Y66879D01*
Y51820D01*
X973060Y51140D01*
Y48674D01*
X972400Y48014D01*
Y34899D01*
X973060Y34239D01*
Y29759D01*
X972300Y28999D01*
Y26100D01*
X970669Y24469D01*
Y17057D01*
G01X963976Y-7108D02*
Y-4724D01*
X965713Y-2987D01*
Y10940D01*
X965600Y11053D01*
Y17799D01*
X968008Y20207D01*
Y25393D01*
X969054Y26439D01*
Y29379D01*
X968474Y29959D01*
Y34207D01*
X968950Y34683D01*
Y52910D01*
X969064Y53024D01*
Y67169D01*
X968700Y67533D01*
Y69385D01*
X968939Y69624D01*
Y83439D01*
X969274Y83774D01*
Y85574D01*
X968674Y86174D01*
Y88374D01*
X969274Y88974D01*
Y90974D01*
X968100Y92148D01*
Y97100D01*
X972200Y101200D01*
Y106331D01*
X992881Y127012D01*
Y200681D01*
G01X986881Y190678D02*
Y129942D01*
X966200Y109261D01*
Y104200D01*
X959674Y97674D01*
Y92274D01*
X958674Y91274D01*
Y89224D01*
X959674Y88224D01*
Y86474D01*
X958674Y85474D01*
Y76627D01*
X959000Y76301D01*
Y72843D01*
X959674Y72169D01*
Y67559D01*
X958924Y66809D01*
Y52207D01*
X959600Y51531D01*
Y49572D01*
X958988Y48960D01*
Y33413D01*
X959674Y32727D01*
Y29759D01*
X958900Y28985D01*
Y15000D01*
X959600Y14300D01*
Y11074D01*
X959000Y10474D01*
Y3700D01*
X960629Y2071D01*
Y-4536D01*
G01X990881Y200481D02*
Y127950D01*
X970500Y107569D01*
Y102500D01*
X965974Y97974D01*
Y91674D01*
X965274Y90974D01*
Y88874D01*
X965974Y88174D01*
Y86274D01*
X965374Y85674D01*
Y75359D01*
X965699Y75034D01*
Y72684D01*
X965374Y72359D01*
Y70059D01*
X965974Y69459D01*
Y67459D01*
X965600Y67085D01*
Y48960D01*
X965700Y48860D01*
Y34885D01*
X965374Y34559D01*
Y32259D01*
X965974Y31659D01*
Y29659D01*
X965617Y29302D01*
Y20117D01*
X963981Y18481D01*
Y17062D01*
X963976Y17057D01*
G01X988881Y191212D02*
Y128579D01*
X968500Y108198D01*
Y103500D01*
X962043Y97043D01*
Y91805D01*
X962774Y91074D01*
Y88974D01*
X962074Y88274D01*
Y86374D01*
X962574Y85874D01*
Y76395D01*
X962296Y76117D01*
Y72737D01*
X962574Y72459D01*
Y69959D01*
X961974Y69359D01*
Y67359D01*
X962371Y66962D01*
Y48710D01*
X962250Y48589D01*
Y30000D01*
X962334Y29916D01*
Y10819D01*
X960629Y9114D01*
G01X943449Y189941D02*
X920200Y166692D01*
Y146535D01*
X919590Y145925D01*
X914560D01*
X913950Y145315D01*
Y143925D01*
X914560Y143315D01*
X919590D01*
X920200Y142705D01*
Y141315D01*
X919590Y140705D01*
X914560D01*
X913950Y140095D01*
Y138705D01*
X914560Y138095D01*
X916440D01*
X917000Y137535D01*
Y135216D01*
X916440Y134656D01*
X914592D01*
X913492Y133556D01*
Y116438D01*
X915774Y114156D01*
Y111474D01*
X915174Y110874D01*
Y105974D01*
X915874Y105274D01*
Y103832D01*
X913779Y101737D01*
Y92757D01*
G01D02*
X912658Y91636D01*
Y88700D01*
X916000Y85358D01*
Y84300D01*
X914200Y82500D01*
Y80925D01*
X915400Y79725D01*
Y78599D01*
X914200Y77399D01*
Y76026D01*
X915558Y74668D01*
Y73467D01*
X917125Y71900D01*
G01X913779Y65699D02*
X915026Y66946D01*
Y68200D01*
X916326Y69500D01*
X917326D01*
X919126Y71300D01*
Y72700D01*
X918514Y73312D01*
Y86325D01*
X917125Y87714D01*
G01D02*
X915292Y89547D01*
Y91392D01*
X918374Y94474D01*
Y95365D01*
X916192Y97547D01*
Y100555D01*
X918374Y102737D01*
Y105524D01*
X919074Y106224D01*
Y110924D01*
X918592Y111406D01*
Y114874D01*
X915992Y117474D01*
Y125090D01*
X916602Y125700D01*
X920840D01*
X921400Y126260D01*
Y128166D01*
X920840Y128726D01*
X917210D01*
X916600Y129336D01*
Y130726D01*
X917210Y131336D01*
X921782D01*
X922392Y131946D01*
Y165277D01*
X945356Y188241D01*
G01X933658Y68550D02*
X934428Y69320D01*
X935410D01*
X936738Y70648D01*
Y86794D01*
X933632Y89900D01*
G01D02*
X935358Y91626D01*
Y94000D01*
X934858Y94500D01*
X933338D01*
X932838Y95000D01*
Y97588D01*
X936654Y101404D01*
Y102236D01*
X937274Y102856D01*
Y103856D01*
X936654Y104476D01*
Y113483D01*
X937572Y114401D01*
Y115401D01*
X938072Y115901D01*
Y116901D01*
X937572Y117401D01*
Y118401D01*
X938072Y118901D01*
Y119901D01*
X937572Y120401D01*
Y121401D01*
X938072Y121901D01*
Y122901D01*
X937572Y123401D01*
Y128404D01*
X937972Y128804D01*
Y130634D01*
X937572Y131034D01*
Y132864D01*
X938484Y133776D01*
X940344D01*
X941772Y135204D01*
Y138429D01*
X940283Y139918D01*
X938444D01*
X937300Y141062D01*
Y143014D01*
X938444Y144158D01*
X940283D01*
X941772Y145647D01*
Y149029D01*
X940283Y150518D01*
X939614D01*
X938960Y151172D01*
Y153834D01*
X939360Y154234D01*
Y156064D01*
X938960Y156464D01*
Y159494D01*
X943122Y163656D01*
X943687D01*
X944982Y164951D01*
Y165516D01*
X946276Y166810D01*
X946841D01*
X948136Y168105D01*
Y168670D01*
X949430Y169964D01*
X949995D01*
X951290Y171259D01*
Y171824D01*
X952584Y173118D01*
X953149D01*
X954444Y174413D01*
Y174978D01*
X955738Y176272D01*
X956303D01*
X957598Y177567D01*
Y178132D01*
X958892Y179426D01*
X959457D01*
X960752Y180721D01*
Y181286D01*
X962046Y182580D01*
X962611D01*
X963906Y183875D01*
Y184440D01*
X965200Y185734D01*
Y188900D01*
G01X969740Y192943D02*
Y190774D01*
X967099Y184399D01*
X944512Y161812D01*
Y133908D01*
X941112Y130508D01*
Y113747D01*
X940752Y113387D01*
Y101085D01*
X938043Y98376D01*
Y98373D01*
X936978Y97308D01*
Y89268D01*
X938732Y87514D01*
G01D02*
Y87515D01*
X939830D01*
X940864Y86481D01*
Y83706D01*
X940158Y83000D01*
X939644D01*
X938944Y82300D01*
Y81300D01*
X939644Y80600D01*
X940144D01*
X940864Y79880D01*
Y78507D01*
X940057Y77700D01*
X939359D01*
X938758Y77099D01*
Y75901D01*
X939359Y75300D01*
X940157D01*
X940864Y74593D01*
Y71972D01*
X939841Y70949D01*
X938732D01*
G01X964140Y188900D02*
Y186174D01*
X937900Y159934D01*
Y150732D01*
X939174Y149458D01*
X939840D01*
X940712Y148586D01*
Y146087D01*
X939843Y145218D01*
X938004D01*
X936240Y143454D01*
Y140622D01*
X938004Y138858D01*
X939840D01*
X940712Y137986D01*
Y135647D01*
X939901Y134836D01*
X938041D01*
X936512Y133307D01*
Y114844D01*
X935594Y113926D01*
Y101847D01*
X931778Y98031D01*
Y89154D01*
X933632Y87300D01*
G01D02*
X934731D01*
X935678Y86353D01*
Y83820D01*
X934708Y82850D01*
X934360D01*
X933744Y82234D01*
Y80902D01*
X934246Y80400D01*
X934958D01*
X935678Y79680D01*
Y78720D01*
X934858Y77900D01*
X934358D01*
X933758Y77300D01*
Y76300D01*
X935678Y74380D01*
Y71091D01*
X934967Y70380D01*
X934451D01*
X933632Y71199D01*
G01X938732Y90114D02*
X940558Y91940D01*
Y93942D01*
X939900Y94600D01*
X938800D01*
X938038Y95362D01*
Y96868D01*
X938793Y97623D01*
X939669D01*
X940377Y98331D01*
Y99207D01*
X941812Y100642D01*
Y103480D01*
X942432Y104100D01*
Y105100D01*
X941812Y105720D01*
Y112944D01*
X942172Y113304D01*
Y130065D01*
X945572Y133465D01*
Y161372D01*
X953154Y168954D01*
X953719D01*
X955014Y170249D01*
Y170814D01*
X956308Y172108D01*
X956873D01*
X958168Y173403D01*
Y173968D01*
X959462Y175262D01*
X960027D01*
X961322Y176557D01*
Y177122D01*
X967998Y183798D01*
X970800Y190563D01*
Y192965D01*
G01X938732Y68340D02*
X941924Y71532D01*
Y86922D01*
X938732Y90114D01*
G01X927165Y92757D02*
X927474Y93066D01*
Y102196D01*
X929292Y104014D01*
Y104856D01*
X927874Y106274D01*
Y110374D01*
X929074Y111574D01*
Y114873D01*
X929800Y115599D01*
Y157284D01*
X933552Y161036D01*
Y161898D01*
X932656Y162794D01*
Y163656D01*
X934057Y165057D01*
X934919D01*
X935815Y164161D01*
X936677D01*
X938078Y165562D01*
Y166424D01*
X937182Y167320D01*
Y168182D01*
X938583Y169583D01*
X939445D01*
X940341Y168687D01*
X941203D01*
X942604Y170088D01*
Y170950D01*
X941708Y171846D01*
Y172708D01*
X943109Y174109D01*
X943971D01*
X944867Y173213D01*
X945729D01*
X947130Y174614D01*
Y175476D01*
X946234Y176372D01*
Y177234D01*
X947635Y178635D01*
X948497D01*
X949393Y177739D01*
X950255D01*
X951656Y179140D01*
Y180002D01*
X950760Y180898D01*
Y181760D01*
X952161Y183161D01*
X953023D01*
X953919Y182265D01*
X954781D01*
X959200Y186684D01*
Y194265D01*
G01X929811Y71500D02*
X928944Y72367D01*
Y85800D01*
X926044Y88700D01*
Y91636D01*
X927165Y92757D01*
G01X929811Y87714D02*
X927774Y89751D01*
Y90874D01*
X929574Y92674D01*
Y101338D01*
X931724Y103488D01*
Y113823D01*
X933892Y115991D01*
Y158710D01*
X961476Y186294D01*
Y193991D01*
G01X927165Y65699D02*
Y67821D01*
X929044Y69700D01*
X930444D01*
X931900Y71156D01*
Y72500D01*
X931284Y73116D01*
Y86241D01*
X929811Y87714D01*
G01X950590Y92757D02*
Y100290D01*
X951300Y101000D01*
X952901D01*
X953600Y101699D01*
Y102500D01*
X951874Y104226D01*
Y108374D01*
X952500Y109000D01*
Y111500D01*
X953756Y112756D01*
X955592D01*
X956492Y113656D01*
Y115612D01*
X955692Y116412D01*
X951660D01*
X951100Y116972D01*
Y119240D01*
X951660Y119800D01*
X955692D01*
X956492Y120600D01*
Y162958D01*
X957838Y164304D01*
X958630D01*
X960271Y162663D01*
X961063D01*
X962082Y163682D01*
Y164474D01*
X960441Y166115D01*
Y166907D01*
X969219Y175685D01*
X973085D01*
X978828Y181428D01*
Y194186D01*
G01X953936Y71900D02*
X952337Y73499D01*
Y86306D01*
X949344Y89299D01*
Y91511D01*
X950590Y92757D01*
G01X953936Y87714D02*
X955874Y89652D01*
Y91274D01*
X953392Y93756D01*
Y97092D01*
X957400Y101100D01*
Y105762D01*
X956192Y106970D01*
Y108570D01*
X956992Y109370D01*
X958026D01*
X958992Y110336D01*
Y155856D01*
X964400Y161264D01*
Y168199D01*
X970001Y173800D01*
X974600D01*
X981397Y180597D01*
Y194186D01*
G01X950590Y65699D02*
X951837Y66946D01*
Y68200D01*
X953137Y69500D01*
X954137D01*
X955937Y71300D01*
Y72364D01*
X955325Y72976D01*
Y86325D01*
X953936Y87714D01*
G01X920472Y92757D02*
X923192Y95477D01*
Y96764D01*
X922292Y97664D01*
X920692D01*
X919992Y98364D01*
Y99964D01*
X920792Y100764D01*
X922392D01*
X923192Y101564D01*
Y104856D01*
X921474Y106574D01*
Y110774D01*
X922592Y111892D01*
Y115593D01*
X925276Y118277D01*
Y118811D01*
X924694Y119393D01*
X920660D01*
X920100Y119953D01*
Y122033D01*
X920660Y122593D01*
X925014D01*
X925574Y123153D01*
Y162192D01*
X953826Y190444D01*
Y193611D01*
G01X923432Y71500D02*
X922344Y72588D01*
Y85901D01*
X919544Y88701D01*
Y91829D01*
X920472Y92757D01*
G01X923518Y87714D02*
X923334D01*
X921482Y89566D01*
Y91032D01*
X925074Y94624D01*
Y105974D01*
X925374Y106274D01*
Y110974D01*
X925174Y111174D01*
Y114574D01*
X927800Y117200D01*
Y161751D01*
X956376Y190327D01*
Y193511D01*
G01X920472Y65699D02*
Y67253D01*
X922719Y69500D01*
X923943D01*
X925519Y71076D01*
Y72700D01*
X924744Y73475D01*
Y86488D01*
X923518Y87714D01*
G01X973636Y192131D02*
Y182736D01*
X970355Y179455D01*
X967656D01*
X951492Y163291D01*
Y159681D01*
X950556Y158745D01*
X948844D01*
X948192Y158093D01*
Y155293D01*
X948992Y154493D01*
X951200D01*
X952000Y153693D01*
Y152093D01*
X951200Y151293D01*
X948992D01*
X948192Y150493D01*
Y148893D01*
X948992Y148093D01*
X951100D01*
X951900Y147293D01*
Y145693D01*
X951100Y144893D01*
X948992D01*
X948192Y144093D01*
Y142493D01*
X948992Y141693D01*
X950700D01*
X951500Y140893D01*
Y139293D01*
X950700Y138493D01*
X948992D01*
X948192Y137693D01*
Y136093D01*
X948500Y135785D01*
Y132565D01*
X944792Y128857D01*
Y114256D01*
X946374Y112674D01*
Y109674D01*
X945274Y108574D01*
Y104026D01*
X945792Y103508D01*
Y94656D01*
X943897Y92761D01*
Y92757D01*
G01D02*
X942644Y91504D01*
Y89750D01*
X945644Y86750D01*
Y73499D01*
X947243Y71900D01*
G01Y87714D02*
X945400Y89557D01*
Y91300D01*
X948192Y94092D01*
Y103192D01*
X949174Y104174D01*
Y108426D01*
X948692Y108908D01*
Y114056D01*
X947292Y115456D01*
Y123640D01*
X947852Y124200D01*
X953432D01*
X953992Y124760D01*
Y163124D01*
X968438Y177570D01*
X971570D01*
X976186Y182186D01*
Y192141D01*
G01X943897Y65699D02*
X945144Y66946D01*
Y68200D01*
X946444Y69500D01*
X947444D01*
X949244Y71300D01*
Y72700D01*
X948632Y73312D01*
Y86325D01*
X947243Y87714D01*
G01X928671Y412356D02*
X921200Y419827D01*
Y454700D01*
X920600Y455300D01*
X919400D01*
X918800Y454700D01*
Y451600D01*
X918100Y450900D01*
X916500D01*
X915900Y451500D01*
Y488000D01*
X915500Y488400D01*
Y494999D01*
X915821Y495320D01*
Y510907D01*
X912421Y514307D01*
Y516799D01*
X913779Y518157D01*
G01X930449Y414135D02*
X923800Y420784D01*
Y435580D01*
X924360Y436140D01*
X925740D01*
X926300Y436700D01*
Y438140D01*
X925740Y438700D01*
X924360D01*
X923800Y439260D01*
Y440700D01*
X924360Y441260D01*
X925740D01*
X926300Y441820D01*
Y443260D01*
X925740Y443820D01*
X924360D01*
X923800Y444380D01*
Y445820D01*
X924360Y446380D01*
X925740D01*
X926300Y446940D01*
Y448380D01*
X925740Y448940D01*
X924360D01*
X923800Y449500D01*
Y459300D01*
X923100Y460000D01*
X921700D01*
X921100Y459400D01*
Y457800D01*
X920600Y457300D01*
X918921D01*
X918421Y457800D01*
Y482621D01*
X919000Y483200D01*
Y497173D01*
X918421Y497752D01*
Y511870D01*
X917125Y513166D01*
Y513114D01*
G01X925330Y412090D02*
X918100Y419320D01*
Y432400D01*
X912300Y438200D01*
Y440541D01*
X912860Y441101D01*
X916740D01*
X917300Y441661D01*
Y443101D01*
X916740Y443661D01*
X912860D01*
X912300Y444221D01*
Y445661D01*
X912860Y446221D01*
X918340D01*
X918900Y446781D01*
Y448221D01*
X918340Y448781D01*
X912860D01*
X912300Y449341D01*
Y494301D01*
X911821Y494780D01*
Y502788D01*
X912621Y503588D01*
X912900D01*
X913700Y504388D01*
Y505988D01*
X912900Y506788D01*
X912621D01*
X911821Y507588D01*
Y511768D01*
X911778D01*
X910432Y513114D01*
G01X968931Y404437D02*
Y411439D01*
X942980Y437390D01*
Y480152D01*
X936712Y486420D01*
Y512249D01*
X933661Y515300D01*
X933632D01*
G01X938732Y512914D02*
X939832D01*
X941052Y511694D01*
Y509967D01*
X940432Y509347D01*
Y508347D01*
X941052Y507727D01*
Y506727D01*
X940432Y506107D01*
Y505107D01*
X941052Y504487D01*
Y503487D01*
X940432Y502867D01*
Y501867D01*
X941052Y501247D01*
Y500154D01*
X940525Y499627D01*
Y498627D01*
X941052Y498100D01*
Y496915D01*
X940537Y496400D01*
Y495400D01*
X941052Y494885D01*
Y493715D01*
X940511Y493174D01*
Y492174D01*
X941052Y491633D01*
Y490527D01*
X940432Y489907D01*
Y488907D01*
X941052Y488287D01*
Y486677D01*
X941759Y485970D01*
Y485093D01*
X942466Y484385D01*
X943344D01*
X944051Y483678D01*
Y482801D01*
X944758Y482093D01*
X945636D01*
X946532Y481197D01*
Y480197D01*
X945912Y479577D01*
Y478577D01*
X946532Y477957D01*
Y476957D01*
X945912Y476337D01*
Y475337D01*
X946532Y474717D01*
Y473717D01*
X945912Y473097D01*
Y472097D01*
X946532Y471477D01*
Y470477D01*
X945912Y469857D01*
Y468857D01*
X946532Y468237D01*
Y446000D01*
X947812Y444720D01*
X951178D01*
X952020Y443878D01*
Y442165D01*
X951148Y441293D01*
X949363D01*
X947871Y439801D01*
Y437222D01*
X949360Y435733D01*
X951979D01*
X952848Y434864D01*
Y431419D01*
X952850D01*
X971834Y412435D01*
Y407587D01*
G01X933632Y512700D02*
X934760D01*
X935652Y511808D01*
Y508824D01*
X934982Y508154D01*
Y507154D01*
X935652Y506484D01*
Y505484D01*
X934982Y504814D01*
Y503814D01*
X935652Y503144D01*
Y485977D01*
X941920Y479709D01*
Y436947D01*
X967871Y410996D01*
Y404437D01*
G01X962707Y401938D02*
Y408803D01*
X936200Y435310D01*
Y466600D01*
X930316Y472484D01*
Y486784D01*
X927974Y489126D01*
Y493874D01*
X929082Y494982D01*
Y502598D01*
X928282Y503398D01*
X928000D01*
X927200Y504198D01*
Y505798D01*
X928000Y506598D01*
X928282D01*
X929082Y507398D01*
Y510857D01*
X925732Y514207D01*
Y516724D01*
X927165Y518157D01*
G01X965276Y401814D02*
Y409841D01*
X938800Y436317D01*
Y477195D01*
X938100Y477895D01*
X936600D01*
X935800Y477095D01*
Y473359D01*
X934820Y472379D01*
X933220D01*
X932400Y473199D01*
Y480100D01*
X933020Y480720D01*
X934890D01*
X935500Y481330D01*
Y482500D01*
X934670Y483330D01*
X932970D01*
X932400Y483900D01*
Y488400D01*
X931732Y489068D01*
Y511193D01*
X929811Y513114D01*
G01X957579Y399557D02*
Y406859D01*
X931100Y433338D01*
Y465400D01*
X928700Y467800D01*
X926900D01*
X926200Y467100D01*
Y465700D01*
X925600Y465100D01*
X924200D01*
X923600Y465700D01*
Y488700D01*
X921574Y490726D01*
Y494374D01*
X922400Y495200D01*
Y502400D01*
X921300Y503500D01*
Y507900D01*
X922382Y508982D01*
Y510857D01*
X919232Y514007D01*
Y516917D01*
X920472Y518157D01*
G01X960157Y400397D02*
Y407817D01*
X933700Y434274D01*
Y465700D01*
X925596Y473804D01*
Y474614D01*
X926132Y475150D01*
X927821D01*
X928378Y475707D01*
Y477097D01*
X927715Y477760D01*
X926106D01*
X925523Y478343D01*
Y479733D01*
X926160Y480370D01*
X927741D01*
X928351Y480980D01*
Y482370D01*
X927741Y482980D01*
X926700D01*
X926100Y483580D01*
Y494500D01*
X925400Y495200D01*
Y502300D01*
X924590Y503110D01*
X924000D01*
X923200Y503910D01*
Y505510D01*
X924000Y506310D01*
X924610D01*
X925032Y506732D01*
Y511600D01*
X923518Y513114D01*
G01X972894Y407587D02*
Y412875D01*
X953908Y431861D01*
Y435304D01*
X952419Y436793D01*
X949800D01*
X948931Y437662D01*
Y439361D01*
X949803Y440233D01*
X951588D01*
X953080Y441725D01*
Y444318D01*
X951618Y445780D01*
X948252D01*
X947592Y446440D01*
Y481637D01*
X942112Y487117D01*
Y512134D01*
X938732Y515514D01*
G01X980758Y406691D02*
Y415842D01*
X961653Y434947D01*
Y466131D01*
X955798Y471986D01*
Y473644D01*
X956598Y474444D01*
X957866D01*
X958489Y475067D01*
Y477067D01*
X957912Y477644D01*
X956320D01*
X955400Y478564D01*
Y486300D01*
X953900Y487800D01*
Y492400D01*
X952300Y494000D01*
Y499368D01*
X952632Y499700D01*
Y510907D01*
X949232Y514307D01*
Y516799D01*
X950590Y518157D01*
G01X983308Y406691D02*
Y416592D01*
X964307Y435593D01*
Y478038D01*
X962245Y480100D01*
X958707D01*
X957907Y480900D01*
Y483017D01*
X958517Y483627D01*
X962473D01*
X963057Y484211D01*
Y485601D01*
X962421Y486237D01*
X958517D01*
X957907Y486847D01*
Y488237D01*
X958517Y488847D01*
X961749D01*
X962318Y489416D01*
Y490806D01*
X961667Y491457D01*
X957327D01*
X956300Y492484D01*
Y499474D01*
X955774Y500000D01*
Y511328D01*
X953936Y513166D01*
Y513114D01*
G01X975658Y406691D02*
Y413934D01*
X956596Y432996D01*
Y447601D01*
X955696Y448501D01*
X951200D01*
X950400Y449301D01*
Y450901D01*
X951200Y451701D01*
X952248D01*
X953048Y452501D01*
Y454004D01*
X952052Y455000D01*
X950900D01*
X950100Y455800D01*
Y483200D01*
X946600Y486700D01*
Y493400D01*
X945600Y494400D01*
Y499500D01*
X946132Y500032D01*
Y510757D01*
X943232Y513657D01*
Y517492D01*
X943897Y518157D01*
G01X978208Y406691D02*
Y414993D01*
X959100Y434101D01*
Y456171D01*
X957704Y457567D01*
X953300D01*
X952500Y458367D01*
Y459467D01*
X953300Y460267D01*
X958698D01*
X959356Y460925D01*
Y462226D01*
X958582Y463000D01*
X953200D01*
X952700Y463500D01*
Y465466D01*
X953310Y466076D01*
X956270D01*
X956827Y466633D01*
Y468123D01*
X956164Y468786D01*
X953310D01*
X952700Y469396D01*
Y484300D01*
X948632Y488368D01*
Y493732D01*
X949800Y494900D01*
Y498200D01*
X948632Y499368D01*
Y511768D01*
X948589D01*
X947243Y513114D01*
G01X913779Y518157D02*
X912074Y519862D01*
Y530049D01*
X917125Y535100D01*
G01Y513114D02*
X917037D01*
X915351Y514800D01*
Y516492D01*
X915526Y516667D01*
Y519300D01*
X914414Y520412D01*
Y521488D01*
X915426Y522500D01*
Y523700D01*
X914414Y524712D01*
Y525788D01*
X915551Y526925D01*
Y528199D01*
X914851Y528899D01*
X913779D01*
G01X933632Y515300D02*
X935344Y517012D01*
Y518600D01*
X934244Y519700D01*
X933294D01*
X932704Y520290D01*
Y521660D01*
X933224Y522180D01*
X933834D01*
X934444Y522790D01*
Y524180D01*
X933834Y524790D01*
X933254D01*
X932704Y525340D01*
Y526760D01*
X933344Y527400D01*
X934624D01*
X935363Y528139D01*
Y530045D01*
X933658Y531750D01*
G01X938732Y534149D02*
X937027Y532444D01*
Y527500D01*
X936197Y526670D01*
Y520130D01*
X937027Y519300D01*
Y514331D01*
X938444Y512914D01*
X938732D01*
G01X933632Y534399D02*
X931644Y532411D01*
Y514400D01*
X933344Y512700D01*
X933632D01*
G01X938732Y515514D02*
X940444Y517226D01*
Y518900D01*
X939444Y519900D01*
X937928D01*
X937257Y520571D01*
Y521848D01*
X937709Y522300D01*
X938044D01*
X938744Y523000D01*
Y524088D01*
X938034Y524798D01*
X937797D01*
X937257Y525338D01*
Y526229D01*
X938028Y527000D01*
X939544D01*
X940544Y528000D01*
Y529728D01*
X938732Y531540D01*
G01X927165Y518157D02*
X925460Y519862D01*
Y531515D01*
X928645Y534700D01*
X929811D01*
G01Y513114D02*
X929723D01*
X928037Y514800D01*
Y516492D01*
X928944Y517399D01*
Y518992D01*
X927800Y520136D01*
Y521556D01*
X928644Y522400D01*
Y524100D01*
X927800Y524944D01*
Y526156D01*
X928744Y527100D01*
Y528300D01*
X928145Y528899D01*
X927165D01*
G01X950590Y518157D02*
X948885Y519862D01*
Y530049D01*
X953936Y535100D01*
G01Y513114D02*
X953848D01*
X952162Y514800D01*
Y516492D01*
X952337Y516667D01*
Y519300D01*
X951225Y520412D01*
Y521488D01*
X952237Y522500D01*
Y523700D01*
X951225Y524712D01*
Y525788D01*
X952362Y526925D01*
Y528199D01*
X951662Y528899D01*
X950590D01*
G01X920472Y518157D02*
X918767Y519862D01*
Y529835D01*
X919389Y530457D01*
Y531645D01*
X922444Y534700D01*
X923432D01*
G01X923518Y513114D02*
X923430D01*
X921744Y514800D01*
Y517000D01*
X922244Y517500D01*
Y519399D01*
X921107Y520536D01*
Y521864D01*
X922044Y522801D01*
Y524199D01*
X921107Y525136D01*
Y526364D01*
X922144Y527401D01*
Y528299D01*
X921544Y528899D01*
X920472D01*
G01X943897Y518157D02*
X942192Y519862D01*
Y530049D01*
X947243Y535100D01*
G01Y513114D02*
X947155D01*
X945469Y514800D01*
Y516492D01*
X945644Y516667D01*
Y519300D01*
X944532Y520412D01*
Y521488D01*
X945544Y522500D01*
Y523700D01*
X944532Y524712D01*
Y525788D01*
X945669Y526925D01*
Y528199D01*
X944969Y528899D01*
X943897D01*
G01X987400Y399687D02*
Y476800D01*
X962500Y501700D01*
Y511400D01*
X961900Y512000D01*
Y513500D01*
X962700Y514300D01*
Y516400D01*
X962000Y517100D01*
Y519500D01*
X962360Y519860D01*
Y533060D01*
X962700Y533400D01*
Y534900D01*
X962257Y535343D01*
Y552057D01*
X962346Y552146D01*
Y568254D01*
X962242Y568358D01*
Y577158D01*
X959010Y580390D01*
Y586810D01*
X959600Y587400D01*
Y591392D01*
X958893Y592099D01*
Y596807D01*
X958500Y597200D01*
Y605300D01*
X960629Y607429D01*
Y609864D01*
G01X991400Y399889D02*
Y478800D01*
X969200Y501000D01*
Y511500D01*
X968800Y511900D01*
Y513900D01*
X969300Y514400D01*
Y516300D01*
X968700Y516900D01*
Y519500D01*
X969030Y519830D01*
Y530570D01*
X968927Y530673D01*
Y549273D01*
X968700Y549500D01*
Y553804D01*
X969031Y554135D01*
Y568169D01*
X968800Y568400D01*
Y573600D01*
X968927Y573727D01*
Y577073D01*
X962257Y583743D01*
Y590070D01*
X963976Y591789D01*
Y593657D01*
G01X989400Y399607D02*
Y477900D01*
X965500Y501800D01*
Y511200D01*
X965800Y511500D01*
Y513800D01*
X965200Y514400D01*
Y516200D01*
X966000Y517000D01*
Y519100D01*
X965607Y519493D01*
Y530307D01*
X966000Y530700D01*
Y532800D01*
X965695Y533105D01*
Y552005D01*
X965607Y552093D01*
Y568307D01*
X965695Y568395D01*
Y576922D01*
X960629Y581988D01*
Y585714D01*
G01X970669Y593657D02*
Y592753D01*
X968928Y591012D01*
Y583572D01*
X975657Y576843D01*
Y570957D01*
X975642Y570942D01*
Y546844D01*
X974422Y545624D01*
Y544444D01*
X975060Y543806D01*
X976087D01*
X976753Y543140D01*
Y541605D01*
X976199Y541051D01*
X974990D01*
X974380Y540441D01*
Y538969D01*
X975642Y537707D01*
Y516658D01*
X975805Y516495D01*
Y514205D01*
X975581Y513981D01*
Y512019D01*
X976000Y511600D01*
Y509299D01*
X980700Y504599D01*
Y495158D01*
X995400Y480458D01*
Y398948D01*
G01X993400Y399647D02*
Y479629D01*
X978700Y494329D01*
Y502600D01*
X972100Y509200D01*
Y511000D01*
X972600Y511500D01*
Y513800D01*
X972100Y514300D01*
Y516400D01*
X972700Y517000D01*
Y526100D01*
X972351Y526449D01*
Y530351D01*
X972894Y530894D01*
Y533845D01*
X972410Y534329D01*
Y545390D01*
X972395Y545405D01*
Y549395D01*
X972439Y549439D01*
Y553753D01*
X972306Y553886D01*
Y564816D01*
X972395Y564905D01*
Y568195D01*
X972700Y568500D01*
Y571784D01*
X972395Y572089D01*
Y576605D01*
X965695Y583305D01*
Y589805D01*
X965607Y589893D01*
Y597975D01*
X963976Y599606D01*
Y607292D01*
G01X970669Y593657D02*
X969539Y594787D01*
Y606162D01*
X970669Y607292D01*
G01X974015Y593657D02*
Y595196D01*
X973405Y595806D01*
X972480D01*
X971870Y596416D01*
Y597406D01*
X972480Y598016D01*
X973405D01*
X974015Y598626D01*
Y599616D01*
X973405Y600226D01*
X972062D01*
X971452Y600836D01*
Y601826D01*
X972062Y602436D01*
X973405D01*
X974015Y603046D01*
Y604499D01*
G01X977362Y9114D02*
X976800Y8552D01*
Y800D01*
X977362Y238D01*
Y-1743D01*
G01X996906Y201105D02*
Y122550D01*
X981400Y107044D01*
Y102100D01*
X975429Y96129D01*
Y91805D01*
X976160Y91074D01*
Y88974D01*
X975460Y88274D01*
Y86374D01*
X975960Y85874D01*
Y81630D01*
X975714Y81384D01*
Y72705D01*
X975960Y72459D01*
Y69959D01*
X975360Y69359D01*
Y67359D01*
X975630Y67089D01*
Y53804D01*
X975710Y53724D01*
Y32709D01*
X975200Y32199D01*
Y29719D01*
X975657Y29262D01*
Y22186D01*
X972300Y18829D01*
Y14176D01*
X977362Y9114D01*
G01X974015Y-9901D02*
Y-7785D01*
X979594Y-2206D01*
Y4114D01*
X979000Y4708D01*
Y12072D01*
X974015Y17057D01*
G01D02*
X979360Y22402D01*
Y26259D01*
X979100Y26519D01*
Y28725D01*
X979860Y29485D01*
Y31159D01*
X978441Y32578D01*
Y34240D01*
X978980Y34779D01*
Y48094D01*
X979595Y48709D01*
Y50139D01*
X978382Y51352D01*
Y52896D01*
X979100Y53614D01*
Y66617D01*
X979703Y67220D01*
Y69116D01*
X978429Y70390D01*
Y72388D01*
X978990Y72949D01*
Y75129D01*
X978760Y75359D01*
Y85674D01*
X979643Y86557D01*
Y88247D01*
X978660Y89230D01*
Y90974D01*
X979360Y91674D01*
Y97560D01*
X983200Y101400D01*
Y106015D01*
X998906Y121721D01*
Y200994D01*
G01X1028036Y189302D02*
Y108744D01*
X1032180Y104600D01*
Y80720D01*
X1033400Y79500D01*
Y46500D01*
X1034660Y45240D01*
Y40020D01*
X1033460Y38820D01*
Y7101D01*
X1029799Y3440D01*
X1025840D01*
X1023960Y1560D01*
Y-2847D01*
X1020142Y-6665D01*
X1013853D01*
X1012954Y-7564D01*
Y-8567D01*
X1014173Y-9786D01*
G01X1021386Y188688D02*
Y84177D01*
X1020156Y82947D01*
X1017010D01*
X1016429Y82366D01*
Y80976D01*
X1017068Y80337D01*
X1020156D01*
X1021386Y79107D01*
Y62214D01*
X1024480Y59120D01*
Y54570D01*
X1026700Y52350D01*
Y43300D01*
X1024480Y41080D01*
Y23896D01*
X1020404Y19820D01*
X1014658D01*
X1014158Y19320D01*
Y17803D01*
X1014919Y17042D01*
G01X1014173Y-1858D02*
X1012954Y-639D01*
Y1671D01*
X1011638Y2987D01*
X1008244D01*
X1007654Y3577D01*
Y5476D01*
X1008307Y6129D01*
X1015357D01*
X1016133Y5353D01*
Y1225D01*
X1017366Y-8D01*
X1019690D01*
X1020922Y1224D01*
Y4837D01*
X1024934Y8849D01*
X1026402D01*
X1028454Y10901D01*
Y40954D01*
X1029500Y42000D01*
Y54600D01*
X1028454Y55646D01*
Y102623D01*
X1024736Y106341D01*
Y189209D01*
G01X1018086Y196219D02*
Y102615D01*
X1010338Y94867D01*
Y86133D01*
X1012000Y84471D01*
Y72100D01*
X1014660Y69440D01*
Y62840D01*
X1020980Y56520D01*
Y53770D01*
X1023600Y51150D01*
Y45500D01*
X1020980Y42880D01*
Y26367D01*
X1018933Y24320D01*
X1013782D01*
X1010565Y21103D01*
Y15523D01*
X1012954Y13134D01*
Y10333D01*
X1014173Y9114D01*
G01X1026976Y189302D02*
Y108304D01*
X1031120Y104160D01*
Y80280D01*
X1032340Y79060D01*
Y46060D01*
X1033600Y44800D01*
Y40460D01*
X1032400Y39260D01*
Y7541D01*
X1029359Y4500D01*
X1025400D01*
X1022900Y2000D01*
Y-2407D01*
X1019702Y-5605D01*
X1013413D01*
X1011894Y-7124D01*
Y-8718D01*
X1010826Y-9786D01*
G01X1020326Y188688D02*
Y84617D01*
X1019716Y84007D01*
X1016570D01*
X1015369Y82806D01*
Y80536D01*
X1016628Y79277D01*
X1019716D01*
X1020326Y78667D01*
Y61774D01*
X1023420Y58680D01*
Y54130D01*
X1025640Y51910D01*
Y43740D01*
X1023420Y41520D01*
Y24336D01*
X1019964Y20880D01*
X1014218D01*
X1013098Y19760D01*
Y17842D01*
X1012270Y17014D01*
G01X1010826Y-1858D02*
X1011894Y-790D01*
Y1231D01*
X1011198Y1927D01*
X1007804D01*
X1006594Y3137D01*
Y5916D01*
X1007867Y7189D01*
X1015797D01*
X1017193Y5793D01*
Y1665D01*
X1017806Y1052D01*
X1019250D01*
X1019862Y1664D01*
Y5277D01*
X1024494Y9909D01*
X1025962D01*
X1027394Y11341D01*
Y41394D01*
X1028440Y42440D01*
Y54160D01*
X1027394Y55206D01*
Y102183D01*
X1023676Y105901D01*
Y189367D01*
G01X1017026Y196219D02*
Y103055D01*
X1009278Y95307D01*
Y85693D01*
X1010940Y84031D01*
Y71660D01*
X1013600Y69000D01*
Y62400D01*
X1019920Y56080D01*
Y53330D01*
X1022540Y50710D01*
Y45940D01*
X1019920Y43320D01*
Y26807D01*
X1018493Y25380D01*
X1013342D01*
X1009505Y21543D01*
Y15083D01*
X1011894Y12694D01*
Y10182D01*
X1010826Y9114D01*
G01X1004134Y-7108D02*
Y-4734D01*
X1002300Y-2900D01*
Y3200D01*
X1002528Y3428D01*
Y15451D01*
X1004134Y17057D01*
G01X1012906Y196375D02*
Y106436D01*
X1002201Y95731D01*
Y91805D01*
X1002932Y91074D01*
Y88974D01*
X1002232Y88274D01*
Y86374D01*
X1002519Y86087D01*
Y69746D01*
X1002430Y69657D01*
Y48376D01*
X1002500Y48306D01*
Y26800D01*
X1004134Y25166D01*
Y17057D01*
G01X1004133Y9122D02*
X1004287Y8968D01*
Y-1588D01*
X1004133Y-1742D01*
G01X1014906Y196325D02*
Y105607D01*
X1005728Y96429D01*
Y85870D01*
X1005532Y85674D01*
Y75359D01*
X1005814Y75077D01*
Y73085D01*
X1005268Y72539D01*
Y67123D01*
X1005761Y66630D01*
Y54129D01*
X1005532Y53900D01*
Y48275D01*
X1005775Y48032D01*
Y45525D01*
X1006200Y45100D01*
Y35500D01*
X1004900Y34200D01*
Y29600D01*
X1005744Y28756D01*
Y16145D01*
X1004500Y14901D01*
Y9489D01*
X1004133Y9122D01*
G01X1000787Y17057D02*
Y11888D01*
X999072Y10173D01*
Y7328D01*
X1000000Y6400D01*
Y-1280D01*
X999059Y-3552D01*
Y-5759D01*
X1000772Y-9895D01*
X1000787Y-9901D01*
G01Y17057D02*
X1001300Y17570D01*
Y22800D01*
X999182Y24918D01*
Y30067D01*
X999905Y30790D01*
Y34130D01*
X999060Y34975D01*
Y41424D01*
X1000105Y42469D01*
Y44619D01*
X999060Y45664D01*
Y47902D01*
X999681Y48523D01*
Y50575D01*
X998709Y51547D01*
Y53351D01*
X999150Y53792D01*
Y59776D01*
X1000255Y60881D01*
Y63528D01*
X999150Y64633D01*
Y66877D01*
X999832Y67559D01*
Y69259D01*
X998832Y70259D01*
Y72359D01*
X999051Y72578D01*
Y75640D01*
X998832Y75859D01*
Y79256D01*
X999849Y80273D01*
Y82376D01*
X998832Y83393D01*
Y85474D01*
X999832Y86474D01*
Y88224D01*
X998832Y89224D01*
Y91274D01*
X999374Y91816D01*
Y95733D01*
X1001336Y97695D01*
Y98827D01*
X1000448Y99715D01*
Y100847D01*
X1001579Y101978D01*
X1002711D01*
X1003599Y101090D01*
X1004731D01*
X1005862Y102221D01*
Y103353D01*
X1005424Y103791D01*
Y104923D01*
X1006555Y106054D01*
X1007687D01*
X1008125Y105616D01*
X1009257D01*
X1010906Y107265D01*
Y191275D01*
G01X997441Y-1743D02*
Y9122D01*
G01X1008906Y191225D02*
Y110299D01*
X1007199Y108592D01*
X1005238D01*
X997751Y101105D01*
Y100082D01*
X998924Y98909D01*
Y98047D01*
X997579Y96702D01*
X995870D01*
X995260Y96092D01*
Y91760D01*
X996046Y90974D01*
Y88974D01*
X995446Y88374D01*
Y86174D01*
X996046Y85574D01*
Y83774D01*
X995798Y83526D01*
Y72407D01*
X996046Y72159D01*
Y69959D01*
X995246Y69159D01*
Y67759D01*
X995710Y67295D01*
Y63749D01*
X996701Y62758D01*
Y60629D01*
X995710Y59638D01*
Y48110D01*
X995780Y48040D01*
Y34625D01*
X995700Y34545D01*
Y24400D01*
X999146Y20954D01*
Y13505D01*
X997441Y11800D01*
Y9122D01*
G01X994094D02*
X994940D01*
X995441Y8621D01*
Y7329D01*
X994831Y6719D01*
X993997D01*
X993360Y6082D01*
Y5092D01*
X993943Y4509D01*
X995068D01*
X995678Y3899D01*
Y2909D01*
X995068Y2299D01*
X993930D01*
X993359Y1728D01*
Y738D01*
X994008Y89D01*
X994995D01*
X995716Y-632D01*
Y-2682D01*
X996857Y-3823D01*
Y-4818D01*
X996033Y-5642D01*
X995200D01*
X994094Y-4536D01*
G01X1006906Y191175D02*
Y114195D01*
X1005752Y113041D01*
X1002810D01*
X1001886Y112117D01*
Y108069D01*
X992746Y98929D01*
Y91674D01*
X992046Y90974D01*
Y88874D01*
X992746Y88174D01*
Y86274D01*
X992146Y85674D01*
Y75359D01*
X992470Y75035D01*
Y72683D01*
X992430Y72643D01*
Y50690D01*
X992489Y50631D01*
Y24411D01*
X995729Y21171D01*
Y13617D01*
X994094Y11982D01*
Y9122D01*
G01Y17057D02*
X992471Y13138D01*
Y8231D01*
X991731Y7491D01*
Y-211D01*
X992600Y-1080D01*
Y-3100D01*
X992274Y-3426D01*
Y-5392D01*
X994094Y-9786D01*
G01X1004906Y190725D02*
Y119234D01*
X999315Y113643D01*
Y108327D01*
X988815Y97827D01*
Y91805D01*
X989546Y91074D01*
Y88974D01*
X988846Y88274D01*
Y86374D01*
X989346Y85874D01*
Y81630D01*
X989013Y81297D01*
Y69959D01*
X989120Y69852D01*
Y50748D01*
X989010Y50638D01*
Y43553D01*
X989006Y43549D01*
Y31819D01*
X989143Y31682D01*
Y24757D01*
X994094Y19806D01*
Y17057D01*
G01X987401Y-4536D02*
X986637Y-5300D01*
X985700D01*
X985100Y-4700D01*
Y-3244D01*
X986700Y-1644D01*
Y-385D01*
X987401Y316D01*
Y2518D01*
X986791Y3128D01*
X983119D01*
X982509Y3738D01*
Y5638D01*
X983119Y6248D01*
X986791D01*
X987401Y6858D01*
Y9114D01*
G01D02*
X985660Y10855D01*
Y18640D01*
X982400Y21900D01*
Y29419D01*
X982054Y29765D01*
Y33461D01*
X982450Y33857D01*
Y37949D01*
X982060Y38339D01*
Y45374D01*
X982420Y45734D01*
Y49100D01*
X981918Y49602D01*
Y52298D01*
X982420Y52800D01*
Y67199D01*
X982093Y67526D01*
Y72084D01*
X982414Y72405D01*
Y83528D01*
X982660Y83774D01*
Y85574D01*
X982060Y86174D01*
Y88374D01*
X982660Y88974D01*
Y90974D01*
X982060Y91574D01*
Y97461D01*
X985400Y100801D01*
Y105386D01*
X1000906Y120892D01*
Y200173D01*
G01X990748Y17057D02*
X989043Y15352D01*
Y6557D01*
X989500Y6100D01*
Y-400D01*
X988948Y-952D01*
Y-3148D01*
X989550Y-3750D01*
Y-5910D01*
X990748Y-7108D01*
G01X1002906Y200493D02*
Y120063D01*
X997315Y114472D01*
Y109156D01*
X996312Y108153D01*
X995210D01*
X993531Y109832D01*
X992353D01*
X991177Y108656D01*
Y107659D01*
X992919Y105917D01*
Y104760D01*
X991786Y103627D01*
X990657D01*
X989506Y104778D01*
X988207D01*
X987176Y103747D01*
Y102581D01*
X988393Y101364D01*
Y100234D01*
X985974Y97815D01*
Y91802D01*
X985446Y91274D01*
Y89256D01*
X986171Y88531D01*
Y85881D01*
X985446Y85156D01*
Y75859D01*
X985738Y75567D01*
Y66851D01*
X985680Y66793D01*
Y48220D01*
X985700Y48200D01*
Y32205D01*
X986446Y31459D01*
Y29759D01*
X985696Y29009D01*
Y25205D01*
X990748Y20153D01*
Y17057D01*
G01X1032240Y190375D02*
Y115700D01*
X1042600Y105340D01*
Y100462D01*
X1046223Y96839D01*
Y91805D01*
X1045492Y91074D01*
Y88974D01*
X1046192Y88274D01*
Y86374D01*
X1045692Y85874D01*
Y69957D01*
X1046292Y69357D01*
Y67359D01*
X1045692Y66759D01*
Y63408D01*
X1045853Y63247D01*
Y50813D01*
X1046192Y50474D01*
Y48574D01*
X1045692Y48074D01*
Y43889D01*
X1046258Y43323D01*
Y38151D01*
X1045911Y37804D01*
Y29178D01*
X1045692Y28959D01*
Y27208D01*
X1047000Y25900D01*
Y17679D01*
X1047637Y17042D01*
G01X1030238Y190273D02*
X1030240Y190271D01*
Y114870D01*
X1040600Y104510D01*
Y99632D01*
X1042300Y97932D01*
Y15400D01*
X1044290Y13410D01*
Y11792D01*
G01X1034240Y190071D02*
Y116530D01*
X1035169Y115601D01*
X1036301D01*
X1036984Y116284D01*
X1038116D01*
X1039247Y115153D01*
Y114021D01*
X1038564Y113338D01*
Y112206D01*
X1044600Y106170D01*
Y101292D01*
X1048985Y96907D01*
Y91674D01*
X1049459Y91200D01*
Y88648D01*
X1049095Y88284D01*
Y86164D01*
X1050041Y85218D01*
Y82049D01*
X1049237Y81245D01*
X1048407D01*
X1047821Y80659D01*
Y78759D01*
X1048455Y78125D01*
X1049249D01*
X1049749Y77625D01*
Y75523D01*
X1049347Y75121D01*
Y72597D01*
X1049585Y72359D01*
Y70059D01*
X1048985Y69459D01*
Y67459D01*
X1049370Y67074D01*
Y57462D01*
X1049266Y57358D01*
Y53593D01*
X1049346Y53513D01*
Y22042D01*
X1054331Y17057D01*
G01X1038240Y190084D02*
Y121992D01*
X1048600Y111632D01*
Y102952D01*
X1055285Y96267D01*
Y92274D01*
X1056590Y90969D01*
Y89529D01*
X1055285Y88224D01*
Y86474D01*
X1056285Y85474D01*
Y75859D01*
X1055940Y75514D01*
Y69914D01*
X1055285Y69259D01*
Y67559D01*
X1055941Y66903D01*
Y53818D01*
X1055285Y53162D01*
Y48674D01*
X1055952Y48007D01*
Y43486D01*
X1056689Y42749D01*
Y38463D01*
X1055960Y37734D01*
Y32134D01*
X1055285Y31459D01*
Y29759D01*
X1055939Y29105D01*
Y21961D01*
X1059295Y18605D01*
Y15146D01*
X1060375Y14066D01*
Y11090D01*
X1059409Y10124D01*
Y6427D01*
X1060019Y5817D01*
X1061362D01*
X1062176Y5003D01*
Y3403D01*
X1061390Y2617D01*
X1060276D01*
X1059476Y1817D01*
Y-3024D01*
X1059100Y-3400D01*
Y-5702D01*
X1060506Y-7108D01*
X1064369D01*
G01X1036240Y190168D02*
Y121162D01*
X1042365Y115037D01*
Y113905D01*
X1041596Y113136D01*
Y112004D01*
X1042727Y110873D01*
X1043859D01*
X1044628Y111642D01*
X1045760D01*
X1046600Y110802D01*
Y102122D01*
X1052916Y95806D01*
Y91805D01*
X1052079Y90968D01*
Y89080D01*
X1052885Y88274D01*
Y86374D01*
X1052385Y85874D01*
Y77115D01*
X1052622Y76878D01*
Y72696D01*
X1052101Y72175D01*
Y70243D01*
X1052985Y69359D01*
Y67359D01*
X1052717Y67091D01*
Y53806D01*
X1051956Y53045D01*
Y51403D01*
X1052885Y50474D01*
Y48574D01*
X1052706Y48395D01*
Y34980D01*
X1051883Y34157D01*
Y32661D01*
X1052985Y31559D01*
Y29559D01*
X1052664Y29238D01*
Y22055D01*
X1057677Y17042D01*
G01X1040240Y190240D02*
Y122822D01*
X1053900Y109162D01*
Y101042D01*
X1059774Y95168D01*
Y91677D01*
X1059071Y90974D01*
Y88974D01*
X1059671Y88374D01*
Y86174D01*
X1059071Y85574D01*
Y83774D01*
X1059399Y83446D01*
Y72259D01*
X1059871Y71787D01*
Y67759D01*
X1059383Y67271D01*
Y62420D01*
X1059315Y62352D01*
Y53102D01*
X1059671Y52746D01*
Y48374D01*
X1059384Y48087D01*
Y33700D01*
X1059871Y33213D01*
Y29959D01*
X1059406Y29494D01*
Y22022D01*
X1064371Y17057D01*
G01X1032800Y402828D02*
Y491912D01*
X1033800Y492912D01*
X1034932D01*
X1036055Y491789D01*
X1037187D01*
X1038318Y492920D01*
Y494052D01*
X1037195Y495175D01*
Y496307D01*
X1049466Y508578D01*
Y511134D01*
X1049010Y511590D01*
Y513702D01*
X1049494Y514186D01*
Y516706D01*
X1049100Y517100D01*
Y526700D01*
X1049352Y526952D01*
Y533052D01*
X1049355Y533055D01*
Y554345D01*
X1049264Y554436D01*
Y556964D01*
X1049949Y557649D01*
Y562811D01*
X1049352Y563408D01*
Y579824D01*
X1052607Y583079D01*
Y587207D01*
X1054331Y588931D01*
Y593657D01*
G01X997400Y395781D02*
Y481400D01*
X982700Y496100D01*
Y505700D01*
X978908Y509492D01*
Y511208D01*
X979400Y511700D01*
Y513800D01*
X978800Y514400D01*
Y516500D01*
X979080Y516780D01*
Y531596D01*
X978977Y531699D01*
Y538415D01*
X978992Y538430D01*
Y554592D01*
X979094Y554694D01*
Y570906D01*
X978991Y571009D01*
Y577309D01*
X972395Y583905D01*
Y588948D01*
X974015Y590568D01*
Y593657D01*
G01Y585714D02*
X982429Y577300D01*
Y573371D01*
X981800Y572742D01*
Y568700D01*
X982342Y568158D01*
Y564942D01*
X981800Y564400D01*
Y558600D01*
X982385Y558015D01*
Y553107D01*
X981900Y552622D01*
Y549700D01*
X982415Y549185D01*
Y534712D01*
X982100Y534397D01*
Y530600D01*
X982400Y530300D01*
Y526200D01*
X982000Y525800D01*
Y516900D01*
X982600Y516300D01*
Y514400D01*
X982200Y514000D01*
Y511700D01*
X982700Y511200D01*
Y509324D01*
X984700Y507324D01*
Y500699D01*
X989930Y495469D01*
Y494337D01*
X989294Y493701D01*
Y492556D01*
X990425Y491425D01*
X991544D01*
X992193Y492074D01*
X993325D01*
X994456Y490943D01*
Y489811D01*
X993703Y489058D01*
Y487926D01*
X994834Y486795D01*
X995966D01*
X996719Y487548D01*
X997851D01*
X999400Y485999D01*
Y405706D01*
G01X1021020Y401381D02*
Y405391D01*
X1022120Y406491D01*
Y496248D01*
X1026308Y500436D01*
Y510884D01*
X1028207Y512783D01*
Y520701D01*
X1027759Y521149D01*
Y522979D01*
X1028207Y523427D01*
Y525257D01*
X1027759Y525705D01*
Y527535D01*
X1028207Y527983D01*
Y529813D01*
X1027759Y530261D01*
Y532091D01*
X1028207Y532539D01*
Y534369D01*
X1027759Y534817D01*
Y536647D01*
X1028207Y537095D01*
Y572588D01*
X1027759Y573036D01*
Y574866D01*
X1028207Y575314D01*
Y586351D01*
X1027759Y586799D01*
Y588629D01*
X1028207Y589077D01*
Y590907D01*
X1027759Y591355D01*
Y593185D01*
X1028207Y593633D01*
Y595463D01*
X1026937Y596733D01*
X1021160D01*
X1020819Y596392D01*
X1018989D01*
X1018648Y596733D01*
X1016693D01*
X1015461Y597965D01*
Y600837D01*
X1016693Y602069D01*
X1018631D01*
X1018971Y602409D01*
X1020801D01*
X1021141Y602069D01*
X1023772D01*
X1024834Y603131D01*
Y606677D01*
X1023642Y607869D01*
X1019562D01*
X1019150Y607457D01*
X1017320D01*
X1016908Y607869D01*
X1013911D01*
X1012986Y606944D01*
Y605801D01*
X1014173Y604614D01*
G01X1014324Y401277D02*
Y408095D01*
X1015520Y409291D01*
Y499488D01*
X1018340Y502308D01*
Y525360D01*
X1019620Y526640D01*
Y548900D01*
X1021540Y550820D01*
Y557860D01*
X1019620Y559780D01*
Y574613D01*
X1014121Y580112D01*
X1010630D01*
X1008361Y582381D01*
Y597098D01*
X1009481Y598218D01*
X1011660D01*
X1013765Y596113D01*
Y594796D01*
X1014919Y593642D01*
G01X1024420Y401699D02*
Y404091D01*
X1025620Y405291D01*
Y494888D01*
X1030213Y499481D01*
Y509093D01*
X1031681Y510561D01*
Y533775D01*
X1031233Y534223D01*
Y536053D01*
X1031681Y536501D01*
Y538331D01*
X1031233Y538779D01*
Y540609D01*
X1031681Y541057D01*
Y542887D01*
X1031233Y543335D01*
Y545165D01*
X1031681Y545613D01*
Y547443D01*
X1031233Y547891D01*
Y549721D01*
X1031681Y550169D01*
Y553099D01*
X1031240Y553540D01*
Y560040D01*
X1031573Y560373D01*
Y597677D01*
X1031125Y598125D01*
Y599955D01*
X1031573Y600403D01*
Y602233D01*
X1031125Y602681D01*
Y604511D01*
X1031573Y604959D01*
Y606789D01*
X1028824Y609538D01*
X1028191D01*
X1026896Y610833D01*
Y611466D01*
X1025602Y612760D01*
X1024969D01*
X1023674Y614055D01*
Y614688D01*
X1022380Y615982D01*
X1019461D01*
X1019085Y615606D01*
X1017255D01*
X1016879Y615982D01*
X1013968D01*
X1012880Y614894D01*
Y613535D01*
X1014173Y612242D01*
G01X1017695Y401923D02*
Y406766D01*
X1018820Y407891D01*
Y497991D01*
X1021940Y501111D01*
Y502941D01*
X1021492Y503389D01*
Y505219D01*
X1021940Y505667D01*
Y507497D01*
X1021492Y507945D01*
Y509775D01*
X1021940Y510223D01*
Y523560D01*
X1023393Y525013D01*
Y526843D01*
X1022945Y527291D01*
Y529121D01*
X1023393Y529569D01*
Y547692D01*
X1025340Y549639D01*
Y553991D01*
X1024892Y554439D01*
Y556269D01*
X1025340Y556717D01*
Y558547D01*
X1024892Y558995D01*
Y560825D01*
X1025340Y561273D01*
Y566104D01*
X1024892Y566552D01*
Y568382D01*
X1025340Y568830D01*
Y570660D01*
X1023640Y572360D01*
Y577847D01*
X1023192Y578295D01*
Y580125D01*
X1023640Y580573D01*
Y582403D01*
X1023192Y582851D01*
Y584681D01*
X1023640Y585129D01*
Y587429D01*
X1021669Y589400D01*
X1018990D01*
X1018542Y588952D01*
X1016712D01*
X1016264Y589400D01*
X1014200D01*
X1012978Y588178D01*
Y586609D01*
X1013873Y585714D01*
G01X1022080Y401501D02*
Y404948D01*
X1023180Y406048D01*
Y495808D01*
X1027368Y499996D01*
Y510444D01*
X1029267Y512343D01*
Y595903D01*
X1027377Y597793D01*
X1017133D01*
X1016521Y598405D01*
Y600397D01*
X1017133Y601009D01*
X1024212D01*
X1025894Y602691D01*
Y607117D01*
X1024082Y608929D01*
X1013471D01*
X1011926Y607384D01*
Y605714D01*
X1010826Y604614D01*
G01X1015384Y401397D02*
Y407652D01*
X1016580Y408848D01*
Y499048D01*
X1019400Y501868D01*
Y511377D01*
X1019741Y511718D01*
Y513548D01*
X1019400Y513889D01*
Y515808D01*
X1019848Y516256D01*
Y518086D01*
X1019400Y518534D01*
Y520364D01*
X1019848Y520812D01*
Y522642D01*
X1019400Y523090D01*
Y524920D01*
X1020680Y526200D01*
Y530236D01*
X1021128Y530684D01*
Y532514D01*
X1020680Y532962D01*
Y534792D01*
X1021128Y535240D01*
Y537070D01*
X1020680Y537518D01*
Y539348D01*
X1021128Y539796D01*
Y541626D01*
X1020680Y542074D01*
Y543904D01*
X1021128Y544352D01*
Y546182D01*
X1020680Y546630D01*
Y548460D01*
X1022600Y550380D01*
Y558300D01*
X1020680Y560220D01*
Y564199D01*
X1021128Y564647D01*
Y566477D01*
X1020680Y566925D01*
Y568809D01*
X1021074Y569203D01*
Y571033D01*
X1020680Y571427D01*
Y575053D01*
X1018276Y577457D01*
Y577894D01*
X1016981Y579189D01*
X1016544D01*
X1014561Y581172D01*
X1011070D01*
X1009421Y582821D01*
Y596658D01*
X1009921Y597158D01*
X1011220D01*
X1012705Y595673D01*
Y594775D01*
X1011572Y593642D01*
G01X1025480Y401579D02*
Y403648D01*
X1026680Y404848D01*
Y494448D01*
X1031273Y499041D01*
Y508653D01*
X1032741Y510121D01*
Y553539D01*
X1032300Y553980D01*
Y559600D01*
X1032633Y559933D01*
Y607229D01*
X1022820Y617042D01*
X1013528D01*
X1011820Y615334D01*
Y613236D01*
X1010826Y612242D01*
G01X1018755Y401923D02*
Y406326D01*
X1019877Y407448D01*
X1019879D01*
X1019880Y407449D01*
Y497551D01*
X1023000Y500671D01*
Y523120D01*
X1024453Y524573D01*
Y547252D01*
X1026400Y549199D01*
Y571100D01*
X1024700Y572800D01*
Y587869D01*
X1022109Y590460D01*
X1013760D01*
X1011918Y588618D01*
Y586506D01*
X1011126Y585714D01*
G01X1036800Y405200D02*
Y485434D01*
X1043113Y491747D01*
Y492879D01*
X1041988Y494004D01*
Y495148D01*
X1043218Y496378D01*
X1044140D01*
X1045377Y495141D01*
X1046481D01*
X1047300Y495960D01*
Y500400D01*
X1056122Y509222D01*
Y511778D01*
X1055761Y512139D01*
Y513861D01*
X1056095Y514195D01*
Y516705D01*
X1055400Y517400D01*
Y525800D01*
X1055949Y526349D01*
Y533049D01*
X1055963Y533063D01*
Y551863D01*
X1055979Y551879D01*
Y558079D01*
X1055953Y558105D01*
Y570653D01*
X1055964Y570664D01*
Y579540D01*
X1059401Y582977D01*
Y588867D01*
X1062751Y592217D01*
Y595417D01*
X1063500Y596166D01*
Y606423D01*
X1064369Y607292D01*
G01X1038800Y405821D02*
Y484605D01*
X1049300Y495105D01*
Y499571D01*
X1058900Y509171D01*
Y511000D01*
X1059900Y512000D01*
Y513600D01*
X1059100Y514400D01*
Y516200D01*
X1059416Y516516D01*
Y530616D01*
X1059600Y530800D01*
Y534176D01*
X1059401Y534375D01*
Y538959D01*
X1059800Y539358D01*
Y545300D01*
X1059401Y545699D01*
Y549301D01*
X1059500Y549400D01*
Y553199D01*
X1059314Y553385D01*
Y563882D01*
X1059416Y563984D01*
Y568516D01*
X1059653Y568753D01*
Y573727D01*
X1059388Y573992D01*
Y579690D01*
X1062707Y583009D01*
Y588857D01*
X1064371Y590521D01*
Y593657D01*
G01X1030800Y405204D02*
Y492741D01*
X1045700Y507641D01*
Y510912D01*
X1046151Y511363D01*
Y513949D01*
X1045748Y514352D01*
Y516348D01*
X1045915Y516515D01*
Y529791D01*
X1045929Y529805D01*
Y546071D01*
X1045800Y546200D01*
Y549300D01*
X1046017Y549517D01*
Y563763D01*
X1045802Y563978D01*
Y568002D01*
X1046105Y568305D01*
Y570895D01*
X1045914Y571086D01*
Y587014D01*
X1047637Y588737D01*
Y593642D01*
G01X984054Y585714D02*
Y577546D01*
X985765Y575835D01*
Y572383D01*
X986100Y572048D01*
Y568600D01*
X985676Y568176D01*
Y552800D01*
X986100Y552376D01*
Y549700D01*
X985692Y549292D01*
Y525408D01*
X986300Y524800D01*
Y517200D01*
X985400Y516300D01*
Y514400D01*
X985900Y513900D01*
Y511500D01*
X985500Y511100D01*
Y509354D01*
X986700Y508154D01*
Y501528D01*
X1001400Y486828D01*
Y406100D01*
G01X1034800Y405100D02*
Y486263D01*
X1040368Y491831D01*
Y496651D01*
X1052400Y508683D01*
Y511100D01*
X1053200Y511900D01*
Y513700D01*
X1052400Y514500D01*
Y516600D01*
X1052800Y517000D01*
Y520400D01*
X1052658Y520542D01*
Y530158D01*
X1052800Y530300D01*
Y532700D01*
X1052629Y532871D01*
Y549229D01*
X1052717Y549317D01*
Y557765D01*
X1053000Y558048D01*
Y563500D01*
X1052687Y563813D01*
Y570613D01*
X1052643Y570657D01*
Y579575D01*
X1055949Y582881D01*
Y591914D01*
X1057677Y593642D01*
G01X1004134Y593657D02*
X1002200Y591723D01*
Y587500D01*
X1002499Y587201D01*
Y580601D01*
X1005764Y577336D01*
Y574016D01*
X1005365Y573617D01*
Y568357D01*
X1005761Y567961D01*
Y560365D01*
X1009223Y556903D01*
Y527647D01*
X1006400Y524824D01*
Y509438D01*
X1013400Y502438D01*
Y410168D01*
X1012140Y408908D01*
Y401713D01*
G01X1010140Y404760D02*
Y409737D01*
X1011400Y410997D01*
Y495758D01*
X1010011Y497147D01*
Y498279D01*
X1011276Y499544D01*
Y500635D01*
X1010145Y501766D01*
X1008972D01*
X1007913Y500707D01*
X1006946D01*
X1005815Y501838D01*
Y503135D01*
X1007309Y504629D01*
Y505584D01*
X1006041Y506852D01*
X1005006D01*
X1003772Y505618D01*
X1002723D01*
X1001433Y506908D01*
Y508099D01*
X1002664Y509330D01*
Y511036D01*
X1002100Y511600D01*
Y513800D01*
X1002800Y514500D01*
Y516600D01*
X1002000Y517400D01*
Y519900D01*
X1002500Y520400D01*
Y577000D01*
X999061Y580439D01*
Y591931D01*
X1000787Y593657D01*
G01X994094Y585722D02*
Y582106D01*
X999047Y577153D01*
Y573447D01*
X999150Y573344D01*
Y554650D01*
X999076Y554576D01*
Y532924D01*
X999163Y532837D01*
Y524937D01*
X999900Y524200D01*
Y517300D01*
X998900Y516300D01*
Y514600D01*
X999306Y514194D01*
Y511706D01*
X998206Y510606D01*
Y506122D01*
X1009400Y494928D01*
Y411826D01*
X1008109Y410535D01*
Y405305D01*
G01X994094Y593657D02*
X992479Y592042D01*
Y580221D01*
X995799Y576901D01*
Y570999D01*
X995725Y570925D01*
Y551925D01*
X995815Y551835D01*
Y535685D01*
X996100Y535400D01*
Y533400D01*
X995727Y533027D01*
Y521227D01*
X995300Y520800D01*
Y517200D01*
X995900Y516600D01*
Y514100D01*
X995668Y513868D01*
Y511732D01*
X996000Y511400D01*
Y509400D01*
X995347Y508747D01*
Y506151D01*
X998672Y502826D01*
Y501526D01*
X1000555Y499643D01*
X1001403D01*
X1003198Y497848D01*
Y496880D01*
X1007400Y492678D01*
Y413816D01*
G01X1003400Y405714D02*
Y491628D01*
X1002445Y492583D01*
X1001329D01*
X1000479Y491733D01*
X999505D01*
X998195Y493043D01*
Y493975D01*
X998873Y494653D01*
Y495771D01*
X997742Y496902D01*
X996596D01*
X995942Y496248D01*
X994810D01*
X994000Y497058D01*
Y498978D01*
X992204Y500774D01*
X990828D01*
X989300Y502302D01*
Y511200D01*
X988800Y511700D01*
Y513700D01*
X989400Y514300D01*
Y516500D01*
X988200Y517700D01*
Y520800D01*
X989114Y521714D01*
Y535686D01*
X989019Y535781D01*
Y551043D01*
X989136Y551160D01*
Y568064D01*
X989012Y568188D01*
Y576288D01*
X987401Y577899D01*
Y585714D01*
G01X1005400Y413600D02*
Y492292D01*
X991900Y505792D01*
Y510900D01*
X992700Y511700D01*
Y513800D01*
X992100Y514400D01*
Y516500D01*
X992600Y517000D01*
Y521800D01*
X992376Y522024D01*
Y535676D01*
X992479Y535779D01*
Y577021D01*
X989027Y580473D01*
Y589527D01*
X990748Y591248D01*
Y593657D01*
G01X1028800Y405271D02*
Y493570D01*
X1042400Y507170D01*
Y586502D01*
X1044290Y588392D01*
G01X974015Y585714D02*
Y587677D01*
X976159Y589821D01*
Y592241D01*
X975657Y592743D01*
Y594801D01*
X976147Y595291D01*
Y605553D01*
X974015Y607685D01*
Y609864D01*
G01X984054Y585714D02*
X981915Y587853D01*
Y591761D01*
X982326Y592172D01*
Y599326D01*
X982700Y599700D01*
Y605600D01*
X982200Y606100D01*
Y608500D01*
X984055Y610355D01*
Y612457D01*
G01X994094Y585722D02*
Y587894D01*
X996100Y589900D01*
Y592300D01*
X995725Y592675D01*
Y594559D01*
X997763Y596597D01*
Y604181D01*
X995519Y606425D01*
X994094Y609864D01*
G01X987401Y585714D02*
X986600Y586515D01*
Y591572D01*
X985676Y592496D01*
Y594604D01*
X985601Y594679D01*
Y605599D01*
X985855Y605853D01*
Y608318D01*
X987401Y609864D01*
G01X1004134Y593657D02*
Y607292D01*
G01X1000787Y593657D02*
X1002361Y595231D01*
Y596832D01*
X1001751Y597442D01*
X1000126D01*
X999516Y598052D01*
Y599442D01*
X1000126Y600052D01*
X1001751D01*
X1002361Y600662D01*
Y602925D01*
X1000787Y604499D01*
G01X994094Y593657D02*
Y595615D01*
X993362Y596347D01*
X989757D01*
X989239Y596865D01*
Y598502D01*
X989836Y599099D01*
X995494D01*
X996008Y599613D01*
Y601155D01*
X995454Y601709D01*
X991592D01*
X990985Y602316D01*
Y604797D01*
X991988Y605800D01*
X992908D01*
X994094Y604614D01*
G01X990748Y593657D02*
X989938D01*
X987601Y595994D01*
Y602153D01*
X989201Y603753D01*
Y605245D01*
X988031Y606415D01*
Y607971D01*
X989300Y609240D01*
Y610062D01*
X989800Y610562D01*
X991100D01*
X991600Y610062D01*
Y608144D01*
X990748Y607292D01*
G01X1054331Y17057D02*
X1053200Y15926D01*
Y10900D01*
X1052673Y10373D01*
Y927D01*
X1053000Y600D01*
Y-2800D01*
X1052400Y-3400D01*
Y-5500D01*
X1054330Y-7430D01*
Y-9901D01*
G01X1048240Y191296D02*
Y126141D01*
X1067000Y107381D01*
Y99399D01*
X1073057Y93342D01*
Y91574D01*
X1072457Y90974D01*
Y88974D01*
X1073057Y88374D01*
Y86174D01*
X1072457Y85574D01*
Y75242D01*
X1072684Y75015D01*
Y71608D01*
X1073257Y71035D01*
Y67759D01*
X1072683Y67185D01*
Y57451D01*
X1072776Y57358D01*
Y48093D01*
X1072673Y47990D01*
Y34183D01*
X1073399Y33457D01*
Y30101D01*
X1072678Y29380D01*
Y22663D01*
X1076016Y19325D01*
Y15784D01*
X1079365Y12435D01*
Y235D01*
X1079700Y-100D01*
Y-3000D01*
X1079300Y-3400D01*
Y-5400D01*
X1081102Y-7202D01*
Y-9901D01*
G01X1094488Y-9786D02*
Y-8032D01*
X1089200Y-2744D01*
Y-600D01*
X1089427Y-373D01*
Y18672D01*
X1086192Y21907D01*
Y29508D01*
X1086643Y29959D01*
Y31359D01*
X1086109Y31893D01*
Y38176D01*
X1086443Y38983D01*
Y45374D01*
X1086173Y45644D01*
Y48104D01*
X1086443Y48374D01*
Y50574D01*
X1085843Y51174D01*
Y53174D01*
X1086190Y53521D01*
Y67306D01*
X1086643Y67759D01*
Y69159D01*
X1085843Y69959D01*
Y72159D01*
X1086157Y72473D01*
Y83460D01*
X1085843Y83774D01*
Y85574D01*
X1086443Y86174D01*
Y88374D01*
X1085843Y88974D01*
Y90974D01*
X1086443Y91574D01*
Y95656D01*
X1079800Y102299D01*
Y105901D01*
X1056240Y129461D01*
Y189743D01*
G01X1058240Y189343D02*
Y130290D01*
X1081900Y106630D01*
Y103199D01*
X1089143Y95956D01*
Y91674D01*
X1089843Y90974D01*
Y88874D01*
X1089143Y88174D01*
Y86274D01*
X1089743Y85674D01*
Y75359D01*
X1089411Y75027D01*
Y72691D01*
X1089743Y72359D01*
Y70059D01*
X1089143Y69459D01*
Y67459D01*
X1089422Y67180D01*
Y53595D01*
X1089843Y53174D01*
Y50840D01*
X1089421Y50418D01*
Y43966D01*
X1089743Y43644D01*
Y37559D01*
X1089433Y37249D01*
Y34869D01*
X1089743Y34559D01*
Y32259D01*
X1089143Y31659D01*
Y29659D01*
X1089427Y29375D01*
Y22073D01*
X1092864Y18636D01*
Y7236D01*
X1094488Y5612D01*
Y-4536D01*
G01X1050240Y190799D02*
Y126971D01*
X1069206Y108005D01*
Y100630D01*
X1071324Y98512D01*
X1073088D01*
X1075900Y95700D01*
Y91531D01*
X1076457Y90974D01*
Y88874D01*
X1075757Y88174D01*
Y86274D01*
X1076928Y85103D01*
Y82398D01*
X1076318Y81788D01*
X1075113D01*
X1074466Y81141D01*
Y79751D01*
X1075039Y79178D01*
X1076318D01*
X1076928Y78568D01*
Y75434D01*
X1076119Y74625D01*
Y72597D01*
X1076357Y72359D01*
Y70059D01*
X1075757Y69459D01*
Y67459D01*
X1076129Y67087D01*
Y57449D01*
X1076037Y57357D01*
Y53594D01*
X1076457Y53174D01*
Y51074D01*
X1075757Y50374D01*
Y48474D01*
X1076149Y48082D01*
Y46001D01*
X1077074Y45076D01*
Y43402D01*
X1076464Y42792D01*
X1075245D01*
X1074635Y42182D01*
Y40792D01*
X1075245Y40182D01*
X1076464D01*
X1077074Y39572D01*
Y37796D01*
X1076124Y36846D01*
Y22046D01*
X1080000Y18170D01*
Y18144D01*
X1081102Y17042D01*
G01X1060240Y188943D02*
Y131119D01*
X1085658Y105701D01*
Y104571D01*
X1085109Y104023D01*
Y102893D01*
X1086242Y101760D01*
X1087373D01*
X1087921Y102308D01*
X1089051D01*
X1090184Y101175D01*
Y100045D01*
X1089635Y99497D01*
Y98367D01*
X1090768Y97234D01*
X1091899D01*
X1092447Y97782D01*
X1093577D01*
X1094531Y96828D01*
Y93262D01*
X1092343Y91074D01*
Y88974D01*
X1093043Y88274D01*
Y86374D01*
X1092543Y85874D01*
Y75757D01*
X1092857Y75443D01*
Y72119D01*
X1091965Y71227D01*
Y68752D01*
X1092857Y67860D01*
Y64916D01*
X1091837Y63896D01*
Y62460D01*
X1092536Y61761D01*
X1094023D01*
X1094633Y61151D01*
Y59761D01*
X1094023Y59151D01*
X1092438D01*
X1091722Y58435D01*
Y56957D01*
X1092857Y55822D01*
Y53256D01*
X1092343Y52742D01*
Y50936D01*
X1092846Y50433D01*
Y43586D01*
X1093109Y43323D01*
Y38735D01*
X1092865Y38491D01*
Y31837D01*
X1092852Y31824D01*
Y22648D01*
X1094488Y21012D01*
Y17059D01*
G01X1062348Y188712D02*
Y131840D01*
X1096443Y97745D01*
Y52240D01*
X1096097Y51894D01*
Y26761D01*
X1096600Y26258D01*
Y16084D01*
X1095427Y14911D01*
Y10061D01*
X1094488Y9122D01*
G01X1047637Y17042D02*
Y11763D01*
X1049349Y10051D01*
Y649D01*
X1049033Y333D01*
Y-2733D01*
X1049665Y-3365D01*
Y-5555D01*
X1047637Y-7583D01*
Y-9901D01*
G01X1064369Y-1743D02*
Y4249D01*
X1064979Y4859D01*
X1065969D01*
X1066579Y4249D01*
Y59D01*
X1067161Y-523D01*
X1068151D01*
X1068789Y115D01*
Y6579D01*
X1068179Y7189D01*
X1064979D01*
X1064369Y7799D01*
Y9120D01*
X1064371Y9122D01*
G01X1042240Y190218D02*
Y123652D01*
X1055900Y109992D01*
Y101872D01*
X1061874Y95898D01*
Y92171D01*
X1063071Y90974D01*
Y88874D01*
X1062371Y88174D01*
Y86274D01*
X1062971Y85674D01*
Y75359D01*
X1062695Y75083D01*
Y72635D01*
X1062971Y72359D01*
Y67341D01*
X1062730Y67100D01*
Y53515D01*
X1063071Y53174D01*
Y51074D01*
X1062371Y50374D01*
Y48474D01*
X1062766Y48079D01*
Y34764D01*
X1062971Y34559D01*
Y32259D01*
X1062371Y31659D01*
Y29659D01*
X1062746Y29284D01*
Y24106D01*
X1065994Y20858D01*
Y15794D01*
X1064369Y14169D01*
Y9124D01*
X1064371Y9122D01*
G01X1057677Y17042D02*
X1055800Y15165D01*
Y10200D01*
X1055971Y10029D01*
Y-901D01*
X1055800Y-1072D01*
Y-3000D01*
X1056450Y-3650D01*
Y-5882D01*
X1057676Y-7108D01*
G01X1044240Y190266D02*
Y124481D01*
X1045360Y123360D01*
X1060627Y108094D01*
Y99974D01*
X1066302Y94299D01*
Y91805D01*
X1065853Y91356D01*
Y88692D01*
X1066271Y88274D01*
Y86374D01*
X1065771Y85874D01*
Y75929D01*
X1065989Y75711D01*
Y31941D01*
X1065978Y31930D01*
Y23704D01*
X1069423Y20259D01*
Y14944D01*
X1068910Y14431D01*
Y12468D01*
X1070428Y10950D01*
X1071650D01*
X1072682Y9918D01*
Y1711D01*
X1073099Y1294D01*
Y-2921D01*
X1072682Y-3338D01*
Y-5984D01*
X1074409Y-7711D01*
Y-9786D01*
G01X1052240Y190520D02*
Y127801D01*
X1073100Y106941D01*
Y101600D01*
X1079688Y95012D01*
Y91805D01*
X1078957Y91074D01*
Y88974D01*
X1079657Y88274D01*
Y86374D01*
X1079157Y85874D01*
Y83942D01*
X1079372Y83727D01*
Y72674D01*
X1079157Y72459D01*
Y69959D01*
X1079384Y69732D01*
Y57381D01*
X1079489Y57276D01*
Y53806D01*
X1079372Y53689D01*
Y21628D01*
X1082715Y18285D01*
Y16285D01*
X1081241Y14811D01*
Y11652D01*
X1082841Y10052D01*
Y541D01*
X1082616Y316D01*
Y-2516D01*
X1087795Y-7695D01*
Y-9786D01*
G01X1046240Y191585D02*
Y125311D01*
X1062627Y108924D01*
Y100873D01*
X1068671Y94829D01*
Y92274D01*
X1069671Y91274D01*
Y89224D01*
X1068671Y88224D01*
Y86474D01*
X1070474Y84671D01*
Y82933D01*
X1069864Y82323D01*
X1068608D01*
X1067998Y81713D01*
Y80323D01*
X1068608Y79713D01*
X1069864D01*
X1070474Y79103D01*
Y76662D01*
X1069439Y75627D01*
Y71727D01*
X1068671Y70959D01*
Y67559D01*
X1069428Y66802D01*
Y64733D01*
X1069987Y64174D01*
Y61892D01*
X1069429Y61334D01*
Y59550D01*
X1070255Y58724D01*
Y57163D01*
X1069428Y56336D01*
Y53717D01*
X1068410Y52699D01*
Y48935D01*
X1069446Y47899D01*
Y44906D01*
X1068604Y44064D01*
Y42296D01*
X1069446Y41454D01*
Y34604D01*
X1068362Y33520D01*
Y30068D01*
X1069424Y29006D01*
Y23087D01*
X1073628Y18883D01*
Y17823D01*
X1074409Y17042D01*
G01X1054240Y190277D02*
Y128631D01*
X1075200Y107671D01*
Y102499D01*
X1082100Y95599D01*
Y92231D01*
X1083057Y91274D01*
Y89224D01*
X1082057Y88224D01*
Y86474D01*
X1082818Y85713D01*
Y72472D01*
X1081331Y70985D01*
Y68285D01*
X1082830Y66786D01*
Y57850D01*
X1082711Y57731D01*
Y53820D01*
X1081356Y52465D01*
Y49375D01*
X1082836Y47895D01*
Y34780D01*
X1081381Y33325D01*
Y30435D01*
X1082843Y28973D01*
Y22011D01*
X1087795Y17059D01*
G01X1044290Y11792D02*
Y-1140D01*
X1044291Y-1141D01*
Y-2200D01*
G01X1074300Y185300D02*
Y131800D01*
X1079813Y126287D01*
X1080675D01*
X1082113Y127725D01*
X1082975D01*
X1083959Y126741D01*
Y125879D01*
X1082521Y124441D01*
Y123579D01*
X1083505Y122595D01*
X1084367D01*
X1085805Y124033D01*
X1086667D01*
X1087651Y123049D01*
Y122187D01*
X1086213Y120749D01*
Y119887D01*
X1087197Y118903D01*
X1088059D01*
X1089497Y120341D01*
X1090359D01*
X1091343Y119357D01*
Y118495D01*
X1089905Y117057D01*
Y116195D01*
X1104400Y101700D01*
X1129136D01*
X1132679Y98157D01*
X1133670D01*
X1135353Y96474D01*
X1143726D01*
X1144685Y95515D01*
Y92757D01*
G01X1076200Y184999D02*
Y140800D01*
X1100664Y116336D01*
Y115136D01*
X1102172Y113628D01*
X1103372D01*
X1108048Y108952D01*
Y108090D01*
X1106660Y106702D01*
Y105840D01*
X1107644Y104856D01*
X1108506D01*
X1109894Y106244D01*
X1110756D01*
X1112100Y104900D01*
X1129473D01*
X1136073Y98300D01*
X1145400D01*
X1146674Y97026D01*
Y92174D01*
X1145424Y90924D01*
Y89621D01*
X1147331Y87714D01*
G01X1089700Y186600D02*
Y157500D01*
X1124000Y123200D01*
X1156937D01*
X1166125Y114012D01*
Y111423D01*
X1166900Y110648D01*
Y107584D01*
X1168284Y106200D01*
X1168900D01*
X1169974Y105126D01*
Y96874D01*
X1169300Y96200D01*
X1167500D01*
X1166900Y95600D01*
Y93967D01*
X1168110Y92757D01*
G01X1069200Y185535D02*
Y177506D01*
X1068590Y176896D01*
X1067410D01*
X1066800Y176286D01*
Y174896D01*
X1067410Y174286D01*
X1068590D01*
X1069200Y173676D01*
Y172286D01*
X1068590Y171676D01*
X1067410D01*
X1066800Y171066D01*
Y169676D01*
X1067410Y169066D01*
X1068590D01*
X1069200Y168456D01*
Y167066D01*
X1068590Y166456D01*
X1067410D01*
X1066800Y165846D01*
Y164456D01*
X1067410Y163846D01*
X1068590D01*
X1069200Y163236D01*
Y161846D01*
X1068590Y161236D01*
X1067410D01*
X1066800Y160626D01*
Y159236D01*
X1067410Y158626D01*
X1068590D01*
X1069200Y158016D01*
Y156626D01*
X1068590Y156016D01*
X1067410D01*
X1066800Y155406D01*
Y133299D01*
X1104299Y95800D01*
X1127964D01*
X1129207Y94557D01*
X1132178D01*
X1133961Y92774D01*
X1137975D01*
X1137992Y92757D01*
G01X1071300Y184700D02*
Y131700D01*
X1104900Y98100D01*
X1108899D01*
X1109799Y99000D01*
X1112209D01*
X1113109Y98100D01*
X1114799D01*
X1116399Y99700D01*
X1117801D01*
X1119401Y98100D01*
X1120799D01*
X1122399Y99700D01*
X1124201D01*
X1125801Y98100D01*
X1129200D01*
X1130943Y96357D01*
X1132924D01*
X1134607Y94674D01*
X1140774D01*
X1141274Y94174D01*
Y93324D01*
X1139188Y91238D01*
Y89564D01*
X1141038Y87714D01*
G01X1085900Y185900D02*
Y149399D01*
X1087389Y147910D01*
X1089190D01*
X1092100Y145000D01*
Y143199D01*
X1116999Y118300D01*
X1154764D01*
X1159500Y113564D01*
Y112500D01*
X1158200Y111200D01*
Y110047D01*
X1158900Y109347D01*
X1159500D01*
X1160300Y108547D01*
Y106947D01*
X1159500Y106147D01*
X1158900D01*
X1158200Y105447D01*
Y103400D01*
X1158700Y102900D01*
X1160500D01*
X1162000Y101400D01*
Y100500D01*
X1161356Y99856D01*
X1159308D01*
X1158408Y98956D01*
Y97356D01*
X1159208Y96556D01*
X1161545D01*
X1162100Y96001D01*
Y93444D01*
X1161417Y92761D01*
Y92757D01*
G01X1087800Y186200D02*
Y155300D01*
X1122400Y120700D01*
X1155900D01*
X1163462Y113138D01*
Y111262D01*
X1162392Y110192D01*
Y106454D01*
X1164300Y104546D01*
Y92700D01*
X1162900Y91300D01*
Y89577D01*
X1164763Y87714D01*
G01X1080065Y185287D02*
Y183900D01*
X1079300Y183135D01*
Y182050D01*
X1079750Y181600D01*
Y180600D01*
X1079300Y180150D01*
Y179150D01*
X1079750Y178700D01*
Y177700D01*
X1079300Y177250D01*
Y176250D01*
X1079750Y175800D01*
Y174800D01*
X1079300Y174350D01*
Y173350D01*
X1079750Y172900D01*
Y171900D01*
X1079300Y171450D01*
Y170450D01*
X1079750Y170000D01*
Y169000D01*
X1079300Y168550D01*
Y167550D01*
X1079750Y167100D01*
Y166100D01*
X1079300Y165650D01*
Y164650D01*
X1079750Y164200D01*
Y163200D01*
X1079300Y162750D01*
Y161752D01*
X1079750Y161302D01*
Y160300D01*
X1079300Y159850D01*
Y158850D01*
X1079750Y158400D01*
Y157400D01*
X1079300Y156950D01*
Y155550D01*
X1079750Y155100D01*
Y154100D01*
X1079300Y153650D01*
Y152550D01*
X1079750Y152100D01*
Y151100D01*
X1079300Y150650D01*
Y142400D01*
X1081218Y140482D01*
X1082080D01*
X1083029Y141431D01*
X1084769D01*
X1086377Y139823D01*
Y138083D01*
X1085428Y137134D01*
Y136272D01*
X1086412Y135288D01*
X1087274D01*
X1088223Y136237D01*
X1089963D01*
X1091571Y134629D01*
Y132889D01*
X1090622Y131940D01*
Y131078D01*
X1092970Y128730D01*
X1093832D01*
X1094531Y129429D01*
X1096271D01*
X1097879Y127821D01*
Y126081D01*
X1097180Y125382D01*
Y124520D01*
X1098164Y123536D01*
X1099026D01*
X1099725Y124235D01*
X1101465D01*
X1103073Y122627D01*
Y120887D01*
X1102374Y120188D01*
Y119326D01*
X1112040Y109660D01*
X1115700D01*
X1116740Y110700D01*
X1123760D01*
X1124800Y109660D01*
X1129741D01*
X1131378Y108023D01*
X1132015D01*
X1132723Y107315D01*
Y106678D01*
X1137041Y102360D01*
X1139550D01*
X1140000Y102810D01*
X1141000D01*
X1141450Y102360D01*
X1147508D01*
X1150238Y99630D01*
Y97800D01*
X1150688Y97350D01*
Y96350D01*
X1150238Y95900D01*
Y94900D01*
X1150638Y94500D01*
X1151540D01*
X1152878Y93162D01*
Y91626D01*
X1151152Y89900D01*
G01X1082163Y185287D02*
Y147936D01*
X1114899Y115200D01*
X1151829D01*
X1153120Y113909D01*
Y98612D01*
X1154498Y97234D01*
Y89268D01*
X1156252Y87514D01*
G01X1079005Y185287D02*
Y184340D01*
X1078240Y183575D01*
Y141960D01*
X1080778Y139422D01*
X1082520D01*
X1083469Y140371D01*
X1084329D01*
X1085317Y139383D01*
Y138523D01*
X1084368Y137574D01*
Y135832D01*
X1085972Y134228D01*
X1087714D01*
X1088663Y135177D01*
X1089523D01*
X1090511Y134189D01*
Y133329D01*
X1089562Y132380D01*
Y130638D01*
X1092530Y127670D01*
X1094272D01*
X1094971Y128369D01*
X1095831D01*
X1096819Y127381D01*
Y126521D01*
X1096120Y125822D01*
Y124080D01*
X1097724Y122476D01*
X1099466D01*
X1100165Y123175D01*
X1101025D01*
X1102013Y122187D01*
Y121327D01*
X1101314Y120628D01*
Y118886D01*
X1111600Y108600D01*
X1116140D01*
X1117180Y109640D01*
X1123320D01*
X1124360Y108600D01*
X1129301D01*
X1136601Y101300D01*
X1147068D01*
X1149178Y99190D01*
Y89274D01*
X1151152Y87300D01*
G01X1083223Y185287D02*
Y148376D01*
X1115339Y116260D01*
X1152269D01*
X1154180Y114349D01*
Y102220D01*
X1154800Y101600D01*
Y100600D01*
X1154180Y99980D01*
Y99052D01*
X1155558Y97674D01*
Y95542D01*
X1156400Y94700D01*
X1157601D01*
X1158300Y94001D01*
Y92162D01*
X1156252Y90114D01*
G01X1091600Y187097D02*
Y159800D01*
X1125400Y126000D01*
X1157674D01*
X1172600Y111074D01*
Y105300D01*
X1172474Y105174D01*
Y94374D01*
X1169374Y91274D01*
Y89796D01*
X1171456Y87714D01*
G01X1096826Y193436D02*
X1094700Y191310D01*
Y187911D01*
X1095310Y187301D01*
X1096590D01*
X1097200Y186691D01*
Y185301D01*
X1096590Y184691D01*
X1095310D01*
X1094700Y184081D01*
Y182691D01*
X1095310Y182081D01*
X1096590D01*
X1097200Y181471D01*
Y180081D01*
X1096590Y179471D01*
X1095310D01*
X1094700Y178861D01*
Y177471D01*
X1095310Y176861D01*
X1096590D01*
X1097200Y176251D01*
Y173646D01*
X1096640Y173086D01*
X1095160D01*
X1094600Y172526D01*
Y171086D01*
X1095160Y170526D01*
X1096640D01*
X1097200Y169966D01*
Y162301D01*
X1130401Y129100D01*
X1161000D01*
X1177174Y112926D01*
Y111974D01*
X1175974Y110774D01*
Y106274D01*
X1176874Y105374D01*
Y103238D01*
X1175392Y101756D01*
Y94656D01*
X1174803Y94067D01*
Y92757D01*
G01X1076106Y417287D02*
Y457106D01*
X1093993Y474993D01*
Y476125D01*
X1092825Y477293D01*
Y478425D01*
X1093956Y479556D01*
X1095088D01*
X1096256Y478388D01*
X1097388D01*
X1098519Y479519D01*
Y480651D01*
X1097451Y481719D01*
Y482851D01*
X1098582Y483982D01*
X1099714D01*
X1100732Y482964D01*
X1101864D01*
X1102995Y484095D01*
Y485227D01*
X1102027Y486195D01*
Y487327D01*
X1115300Y500600D01*
X1126199D01*
X1132113Y506514D01*
X1141114D01*
X1142400Y507800D01*
Y511175D01*
X1143200Y511975D01*
Y517356D01*
X1144001Y518157D01*
X1144685D01*
G01X1078656Y417287D02*
Y456056D01*
X1107059Y484459D01*
Y485591D01*
X1105751Y486899D01*
Y488031D01*
X1106882Y489162D01*
X1108014D01*
X1109634Y487542D01*
X1110766D01*
X1111897Y488673D01*
Y489805D01*
X1110343Y491359D01*
Y492491D01*
X1111474Y493622D01*
X1112606D01*
X1114292Y491936D01*
X1115424D01*
X1116555Y493067D01*
Y494199D01*
X1114891Y495863D01*
Y497017D01*
X1115974Y498100D01*
X1127499D01*
X1134113Y504714D01*
X1150114D01*
X1150680Y505280D01*
Y506820D01*
X1150100Y507400D01*
X1146900D01*
X1146100Y508200D01*
Y509332D01*
X1146800Y510032D01*
X1148000D01*
X1148800Y510832D01*
Y511964D01*
X1147650Y513114D01*
X1147331D01*
G01X1070657Y417187D02*
Y463457D01*
X1099522Y492322D01*
Y497328D01*
X1107294Y505100D01*
X1112044D01*
X1112654Y505710D01*
Y506970D01*
X1113264Y507580D01*
X1114654D01*
X1115264Y506970D01*
Y505710D01*
X1115874Y505100D01*
X1117264D01*
X1117874Y505710D01*
Y507763D01*
X1118506Y508395D01*
X1119896D01*
X1120484Y507807D01*
Y505710D01*
X1121094Y505100D01*
X1123522D01*
X1130374Y511952D01*
X1132274D01*
X1133174Y511052D01*
X1135452D01*
X1137200Y512800D01*
Y517365D01*
X1137992Y518157D01*
G01X1073556Y417187D02*
Y458156D01*
X1081216Y465816D01*
Y466948D01*
X1079600Y468564D01*
Y469674D01*
X1080731Y470805D01*
X1081885D01*
X1083479Y469211D01*
X1084611D01*
X1085749Y470349D01*
Y471481D01*
X1084494Y472736D01*
Y473694D01*
X1103854Y493054D01*
Y494186D01*
X1102093Y495947D01*
Y497079D01*
X1103224Y498210D01*
X1104356D01*
X1106117Y496449D01*
X1107249D01*
X1108380Y497580D01*
Y498712D01*
X1106861Y500231D01*
Y501363D01*
X1107992Y502494D01*
X1109124D01*
X1110643Y500975D01*
X1111775D01*
X1114000Y503200D01*
X1125100D01*
X1130214Y508314D01*
X1139600D01*
X1140400Y509114D01*
Y512476D01*
X1141038Y513114D01*
G01X1082311Y418187D02*
Y454479D01*
X1119464Y491632D01*
X1130103D01*
X1134380Y495909D01*
Y498801D01*
X1136168Y500589D01*
X1151060D01*
X1154232Y503761D01*
Y512220D01*
X1151152Y515300D01*
G01X1088451Y418487D02*
Y444152D01*
X1087841Y444762D01*
X1086669D01*
X1085461Y445970D01*
Y448240D01*
X1086713Y449492D01*
X1087841D01*
X1088451Y450102D01*
Y456375D01*
X1120600Y488524D01*
X1128115D01*
X1128735Y489144D01*
X1129735D01*
X1130355Y488524D01*
X1131355D01*
X1131975Y489144D01*
X1132975D01*
X1133595Y488524D01*
X1134595D01*
X1135215Y489144D01*
X1136215D01*
X1136835Y488524D01*
X1137835D01*
X1138455Y489144D01*
X1139455D01*
X1140075Y488524D01*
X1141075D01*
X1141695Y489144D01*
X1142695D01*
X1143315Y488524D01*
X1147555D01*
X1148175Y489144D01*
X1149175D01*
X1149795Y488524D01*
X1150795D01*
X1151415Y489144D01*
X1152415D01*
X1153035Y488524D01*
X1154035D01*
X1154655Y489144D01*
X1155655D01*
X1156275Y488524D01*
X1157533D01*
X1158572Y489563D01*
Y492740D01*
X1158084Y493228D01*
Y494228D01*
X1158572Y494716D01*
Y496275D01*
X1158118Y496729D01*
Y497729D01*
X1158572Y498183D01*
Y500443D01*
X1157952Y501063D01*
Y502063D01*
X1158572Y502683D01*
Y503683D01*
X1157952Y504303D01*
Y505303D01*
X1158572Y505923D01*
Y506923D01*
X1157952Y507543D01*
Y508543D01*
X1158572Y509163D01*
Y511694D01*
X1157352Y512914D01*
X1156252D01*
G01X1081251Y418187D02*
Y454919D01*
X1119024Y492692D01*
X1129663D01*
X1130951Y493980D01*
Y494736D01*
X1131658Y495443D01*
X1132414D01*
X1133320Y496349D01*
Y499241D01*
X1135728Y501649D01*
X1137560D01*
X1138180Y502269D01*
X1139180D01*
X1139800Y501649D01*
X1140800D01*
X1141420Y502269D01*
X1142420D01*
X1143040Y501649D01*
X1144040D01*
X1144660Y502269D01*
X1145660D01*
X1146280Y501649D01*
X1147280D01*
X1147900Y502269D01*
X1148900D01*
X1149520Y501649D01*
X1150620D01*
X1153172Y504201D01*
Y506922D01*
X1152552Y507542D01*
Y508542D01*
X1153172Y509162D01*
Y511780D01*
X1152252Y512700D01*
X1151152D01*
G01X1046900Y406829D02*
Y481389D01*
X1072400Y506889D01*
Y511100D01*
X1072925Y511625D01*
Y514075D01*
X1072642Y514358D01*
Y516942D01*
X1073300Y517600D01*
Y525900D01*
X1072669Y526531D01*
Y530469D01*
X1072698Y530498D01*
Y549098D01*
X1072757Y549157D01*
Y564943D01*
X1072669Y565031D01*
Y568269D01*
X1072684Y568284D01*
Y577384D01*
X1076136Y580836D01*
Y589536D01*
X1079486Y592886D01*
Y602883D01*
X1081102Y604499D01*
G01X1049284Y367060D02*
X1050800Y368576D01*
Y369700D01*
X1051400Y370300D01*
Y371600D01*
X1050800Y372200D01*
Y373600D01*
X1051300Y374100D01*
Y375600D01*
X1050800Y376100D01*
Y377600D01*
X1051200Y378000D01*
Y379600D01*
X1050800Y380000D01*
Y381400D01*
X1054600Y385200D01*
Y401000D01*
X1054000Y401600D01*
Y403000D01*
X1055000Y404000D01*
Y474087D01*
X1069389Y488476D01*
Y492489D01*
X1085900Y509000D01*
Y511500D01*
X1086258Y511858D01*
Y513842D01*
X1086017Y514083D01*
Y516917D01*
X1086499Y517399D01*
Y526301D01*
X1086082Y526718D01*
Y529782D01*
X1086156Y529856D01*
Y558944D01*
X1086070Y559030D01*
Y573570D01*
X1086127Y573627D01*
Y576527D01*
X1089433Y579833D01*
Y587067D01*
X1091283Y588917D01*
Y591283D01*
X1092857Y592857D01*
Y602983D01*
X1094488Y604614D01*
G01X1049284Y363160D02*
X1050450Y364326D01*
Y365550D01*
X1052000Y367100D01*
X1053800D01*
X1058500Y371800D01*
Y379200D01*
X1059900Y380600D01*
X1061400D01*
X1062493Y381693D01*
Y405453D01*
X1061000Y406946D01*
Y471600D01*
X1096351Y506951D01*
Y511049D01*
X1095574Y511826D01*
Y513774D01*
X1096500Y514700D01*
Y517200D01*
X1096093Y517607D01*
Y533293D01*
X1096300Y533500D01*
Y548700D01*
X1096110Y548890D01*
Y568090D01*
X1095815Y568385D01*
Y570815D01*
X1096118Y571118D01*
Y576318D01*
X1096353Y576553D01*
Y586547D01*
X1095400Y587500D01*
Y589000D01*
X1096400Y590000D01*
Y602600D01*
X1096700Y602900D01*
Y605100D01*
X1094488Y607312D01*
Y609864D01*
G01X1048900Y407111D02*
Y476474D01*
X1048901Y476475D01*
Y480541D01*
X1050044Y481684D01*
X1051196D01*
X1052139Y480741D01*
X1053195D01*
X1054384Y481930D01*
Y483022D01*
X1053069Y484337D01*
Y485247D01*
X1054349Y486527D01*
X1055405D01*
X1056669Y485263D01*
X1057663D01*
X1058863Y486463D01*
Y487595D01*
X1057632Y488826D01*
Y489707D01*
X1059020Y491095D01*
X1059889D01*
X1061243Y489741D01*
X1062141D01*
X1063389Y490989D01*
Y492121D01*
X1062418Y493092D01*
Y494078D01*
X1076300Y507960D01*
Y511300D01*
X1075600Y512000D01*
Y513800D01*
X1076300Y514500D01*
Y516600D01*
X1075700Y517200D01*
Y521100D01*
X1076152Y521552D01*
Y530248D01*
X1076122Y530278D01*
Y551974D01*
X1076048Y552048D01*
Y558548D01*
X1076136Y558636D01*
Y577136D01*
X1079385Y580385D01*
Y586985D01*
X1080400Y588000D01*
Y590262D01*
X1081102Y590964D01*
Y593642D01*
G01X1052664Y372909D02*
X1054600Y374845D01*
Y382300D01*
X1056600Y384300D01*
Y395600D01*
X1058100Y397100D01*
Y404200D01*
X1057000Y405300D01*
Y473258D01*
X1071389Y487647D01*
Y491660D01*
X1088063Y508334D01*
X1088562D01*
X1089595Y509367D01*
Y511205D01*
X1088800Y512000D01*
Y513800D01*
X1089600Y514600D01*
Y516600D01*
X1089200Y517000D01*
Y527700D01*
X1089418Y527918D01*
Y552118D01*
X1089427Y552127D01*
Y557427D01*
X1089418Y557436D01*
Y576618D01*
X1092856Y580056D01*
Y586956D01*
X1093400Y587500D01*
Y589876D01*
X1094488Y590964D01*
Y593659D01*
G01X1052664Y369010D02*
X1056500Y372846D01*
Y381100D01*
X1058700Y383300D01*
Y394910D01*
X1060100Y396310D01*
Y405016D01*
X1059000Y406116D01*
Y472429D01*
X1073389Y486818D01*
Y490831D01*
X1076718Y494160D01*
X1077580D01*
X1078513Y493227D01*
X1079375D01*
X1080359Y494211D01*
Y495073D01*
X1079426Y496006D01*
Y496868D01*
X1088925Y506367D01*
X1089813D01*
X1092600Y509154D01*
Y511300D01*
X1093300Y512000D01*
Y513900D01*
X1092400Y514800D01*
Y516200D01*
X1093300Y517100D01*
Y526100D01*
X1092856Y526544D01*
Y576656D01*
X1094488Y578288D01*
Y585722D01*
G01X1040866Y405606D02*
Y483842D01*
X1052546Y495522D01*
Y496654D01*
X1051693Y497507D01*
Y498665D01*
X1052824Y499796D01*
X1053930D01*
X1054782Y498944D01*
X1055927D01*
X1056700Y499717D01*
Y503244D01*
X1062761Y509305D01*
Y511339D01*
X1062522Y511578D01*
Y513922D01*
X1062881Y514281D01*
Y516319D01*
X1062585Y516615D01*
Y519385D01*
X1063734Y520534D01*
Y526266D01*
X1062649Y527351D01*
Y539449D01*
X1062737Y539537D01*
Y551637D01*
X1062751Y551651D01*
Y557704D01*
X1063557Y558510D01*
X1064491D01*
X1065125Y559144D01*
Y561058D01*
X1064473Y561710D01*
X1063469D01*
X1062708Y562471D01*
Y570448D01*
X1062678Y570478D01*
Y579466D01*
X1064108Y580896D01*
X1066305D01*
X1066889Y581480D01*
Y582870D01*
X1066253Y583506D01*
X1064981D01*
X1064371Y584116D01*
Y585722D01*
G01X1074409Y604614D02*
Y597512D01*
X1072690Y595793D01*
Y589638D01*
X1069400Y586348D01*
Y581400D01*
X1065999Y577999D01*
Y564801D01*
X1067100Y563700D01*
Y557714D01*
X1065984Y556598D01*
Y549214D01*
X1065999Y549199D01*
Y527201D01*
X1067000Y526200D01*
Y517600D01*
X1065700Y516300D01*
Y514400D01*
X1066259Y513841D01*
Y511995D01*
X1064950Y510686D01*
Y508665D01*
X1058700Y502415D01*
Y498847D01*
X1042900Y483047D01*
Y405741D01*
G01X1050900Y407111D02*
Y475645D01*
X1065389Y490134D01*
Y494219D01*
X1079000Y507830D01*
Y511000D01*
X1079886Y511886D01*
Y513514D01*
X1078917Y514483D01*
Y516217D01*
X1079800Y517100D01*
Y527300D01*
X1079369Y527731D01*
Y554469D01*
X1079471Y554571D01*
Y559335D01*
X1079377Y559429D01*
Y576677D01*
X1082836Y580136D01*
Y586900D01*
X1086185Y590249D01*
Y603004D01*
X1087795Y604614D01*
G01X1044900Y406265D02*
Y482218D01*
X1061541Y498859D01*
Y499991D01*
X1061082Y500450D01*
Y501582D01*
X1062213Y502713D01*
X1063345D01*
X1063804Y502254D01*
X1064936D01*
X1066067Y503385D01*
Y504517D01*
X1065608Y504976D01*
Y506108D01*
X1066739Y507239D01*
X1067871D01*
X1068330Y506780D01*
X1069462D01*
X1070579Y507897D01*
Y510121D01*
X1069000Y511700D01*
Y513332D01*
X1069989Y514321D01*
Y516011D01*
X1069100Y516900D01*
Y520200D01*
X1069436Y520536D01*
Y530064D01*
X1068908Y530592D01*
Y535164D01*
X1069422Y535678D01*
Y549478D01*
X1068908Y549992D01*
Y554276D01*
X1069451Y554819D01*
Y567949D01*
X1068900Y568500D01*
Y573026D01*
X1069437Y573563D01*
Y577637D01*
X1072683Y580883D01*
Y586883D01*
X1074409Y588609D01*
Y593642D01*
G01X1045904Y361209D02*
Y362504D01*
X1047800Y364400D01*
Y366000D01*
X1047266Y366534D01*
Y367666D01*
X1047800Y368200D01*
Y369800D01*
X1047400Y370200D01*
Y371700D01*
X1047800Y372100D01*
Y373700D01*
X1047400Y374100D01*
Y375700D01*
X1047800Y376100D01*
Y377600D01*
X1047300Y378100D01*
Y379500D01*
X1047800Y380000D01*
Y381400D01*
X1047300Y381900D01*
Y383300D01*
X1048500Y384500D01*
X1049900D01*
X1051200Y385800D01*
Y387400D01*
X1050634Y387966D01*
Y389034D01*
X1051300Y389700D01*
Y391200D01*
X1050700Y391800D01*
Y401200D01*
X1051800Y402300D01*
Y404200D01*
X1052900Y405300D01*
Y474816D01*
X1067389Y489305D01*
Y493389D01*
X1082900Y508900D01*
Y511300D01*
X1082500Y511700D01*
Y514200D01*
X1083000Y514700D01*
Y516600D01*
X1082600Y517000D01*
Y520400D01*
X1082821Y520621D01*
Y530555D01*
X1081278Y532098D01*
Y534134D01*
X1082822Y535678D01*
Y548978D01*
X1081381Y550419D01*
Y553115D01*
X1082733Y554467D01*
Y562233D01*
X1082823Y562323D01*
Y567549D01*
X1081350Y569022D01*
Y572058D01*
X1082822Y573530D01*
Y576922D01*
X1086127Y580227D01*
Y586827D01*
X1087795Y588495D01*
Y593659D01*
G01X1092106Y417467D02*
Y455006D01*
X1121944Y484844D01*
X1159144D01*
X1161600Y487300D01*
Y493600D01*
X1163100Y495100D01*
Y504500D01*
X1163300Y504700D01*
Y511109D01*
X1160752Y513657D01*
Y517492D01*
X1161417Y518157D01*
G01X1095036Y417407D02*
Y451925D01*
X1103557Y460446D01*
Y461318D01*
X1102969Y461906D01*
Y462768D01*
X1104370Y464169D01*
X1105232D01*
X1105820Y463581D01*
X1106682D01*
X1108083Y464982D01*
Y465844D01*
X1107495Y466432D01*
Y467294D01*
X1108896Y468695D01*
X1109758D01*
X1110346Y468107D01*
X1111208D01*
X1112609Y469508D01*
Y470370D01*
X1112021Y470958D01*
Y471820D01*
X1113422Y473221D01*
X1114284D01*
X1114872Y472633D01*
X1115734D01*
X1117135Y474034D01*
Y474896D01*
X1116547Y475484D01*
Y476346D01*
X1117948Y477747D01*
X1118810D01*
X1119398Y477159D01*
X1120260D01*
X1121661Y478560D01*
Y479422D01*
X1121073Y480010D01*
Y480872D01*
X1122545Y482344D01*
X1160243D01*
X1166100Y488201D01*
Y494400D01*
X1165200Y495300D01*
Y503342D01*
X1166600Y504742D01*
X1167400D01*
X1168200Y505542D01*
Y507142D01*
X1167400Y507942D01*
X1166400D01*
X1165600Y508742D01*
Y512314D01*
X1164800Y513114D01*
X1164763D01*
G01X1089511Y418487D02*
Y444592D01*
X1088281Y445822D01*
X1087109D01*
X1086521Y446410D01*
Y447800D01*
X1087153Y448432D01*
X1088281D01*
X1089511Y449662D01*
Y455935D01*
X1121040Y487464D01*
X1157973D01*
X1159632Y489123D01*
Y512134D01*
X1156252Y515514D01*
G01X1064371Y585722D02*
X1066006Y587357D01*
Y597094D01*
X1065916Y597184D01*
Y605516D01*
X1066169Y605769D01*
Y608261D01*
X1064369Y610061D01*
Y612657D01*
G01X1054331Y593657D02*
X1053751Y594237D01*
Y603920D01*
X1054330Y604499D01*
G01X1047637Y593642D02*
X1048139Y594144D01*
Y603997D01*
X1047637Y604499D01*
G01X1057677Y593642D02*
Y595848D01*
X1057177Y596348D01*
X1056143D01*
X1055426Y597065D01*
Y598971D01*
X1056162Y599707D01*
X1060969D01*
X1061724Y600462D01*
Y601950D01*
X1061079Y602595D01*
X1057274D01*
X1056382Y603487D01*
Y605998D01*
X1057676Y607292D01*
G01X1044290Y588392D02*
Y595722D01*
X1045665Y597097D01*
Y606065D01*
X1046017Y606417D01*
Y608283D01*
X1044290Y610010D01*
Y612657D01*
X1044291Y612658D01*
G01X1107874Y92757D02*
X1106753Y91636D01*
Y88700D01*
X1109653Y85800D01*
Y83832D01*
X1108120Y82299D01*
Y81100D01*
X1109370Y79850D01*
Y78950D01*
X1108020Y77600D01*
Y76301D01*
X1109653Y74668D01*
Y72367D01*
X1110520Y71500D01*
G01Y87714D02*
X1111993Y86241D01*
Y73116D01*
X1112609Y72500D01*
Y71156D01*
X1111153Y69700D01*
X1109753D01*
X1107874Y67821D01*
Y65699D01*
G01X1131299Y92757D02*
X1130178Y91636D01*
Y88700D01*
X1133520Y85358D01*
Y84300D01*
X1131720Y82500D01*
Y80925D01*
X1132920Y79725D01*
Y78599D01*
X1131720Y77399D01*
Y76026D01*
X1133078Y74668D01*
Y73467D01*
X1134645Y71900D01*
G01Y87714D02*
X1136034Y86325D01*
Y73312D01*
X1136646Y72700D01*
Y71300D01*
X1134846Y69500D01*
X1133846D01*
X1131299Y66953D01*
Y65699D01*
G01X1101181Y92757D02*
X1100253Y91829D01*
Y88701D01*
X1103053Y85901D01*
Y84032D01*
X1101670Y82649D01*
Y81250D01*
X1103120Y79800D01*
Y78600D01*
X1101620Y77100D01*
Y75901D01*
X1103053Y74468D01*
Y72588D01*
X1104141Y71500D01*
G01X1104227Y87714D02*
X1105453Y86488D01*
Y73475D01*
X1106228Y72700D01*
Y71076D01*
X1104652Y69500D01*
X1103428D01*
X1101181Y67253D01*
Y65699D01*
G01X1124606Y92757D02*
X1123678Y91829D01*
Y88701D01*
X1126720Y85659D01*
Y84274D01*
X1125045Y82599D01*
Y81476D01*
X1126545Y79976D01*
Y78624D01*
X1125045Y77124D01*
Y75901D01*
X1126478Y74468D01*
Y73374D01*
X1127952Y71900D01*
G01Y87714D02*
X1129341Y86325D01*
Y73312D01*
X1129953Y72700D01*
Y71300D01*
X1128153Y69500D01*
X1127153D01*
X1124606Y66953D01*
Y65699D01*
G01X1144685Y92757D02*
X1143564Y91636D01*
Y88700D01*
X1146464Y85800D01*
Y83832D01*
X1144931Y82299D01*
Y81100D01*
X1146181Y79850D01*
Y78950D01*
X1144831Y77600D01*
Y76301D01*
X1146464Y74668D01*
Y72367D01*
X1147331Y71500D01*
G01Y87714D02*
X1148804Y86241D01*
Y73116D01*
X1149420Y72500D01*
Y71156D01*
X1147964Y69700D01*
X1146564D01*
X1144685Y67821D01*
Y65699D01*
G01X1137992Y92757D02*
X1137064Y91829D01*
Y88701D01*
X1139864Y85901D01*
Y84032D01*
X1138481Y82649D01*
Y81250D01*
X1139931Y79800D01*
Y78600D01*
X1138431Y77100D01*
Y75901D01*
X1139864Y74468D01*
Y72588D01*
X1140952Y71500D01*
G01X1141038Y87714D02*
X1142264Y86488D01*
Y73475D01*
X1143039Y72700D01*
Y71076D01*
X1141463Y69500D01*
X1140239D01*
X1137992Y67253D01*
Y65699D01*
G01X1114340Y89900D02*
X1117446Y86794D01*
Y70648D01*
X1116118Y69320D01*
X1115136D01*
X1114366Y68550D01*
G01X1151152Y89900D02*
X1154258Y86794D01*
Y70648D01*
X1152930Y69320D01*
X1151948D01*
X1151178Y68550D01*
G01X1119440Y87514D02*
Y87515D01*
X1120538D01*
X1121572Y86481D01*
Y83706D01*
X1120866Y83000D01*
X1120352D01*
X1119652Y82300D01*
Y81300D01*
X1120352Y80600D01*
X1120852D01*
X1121572Y79880D01*
Y78507D01*
X1120765Y77700D01*
X1120067D01*
X1119466Y77099D01*
Y75901D01*
X1120067Y75300D01*
X1120865D01*
X1121572Y74593D01*
Y71972D01*
X1120549Y70949D01*
X1119440D01*
G01X1156252Y87514D02*
Y87515D01*
X1157350D01*
X1158384Y86481D01*
Y83706D01*
X1157678Y83000D01*
X1157164D01*
X1156464Y82300D01*
Y81300D01*
X1157164Y80600D01*
X1157664D01*
X1158384Y79880D01*
Y78507D01*
X1157577Y77700D01*
X1156879D01*
X1156278Y77099D01*
Y75901D01*
X1156879Y75300D01*
X1157677D01*
X1158384Y74593D01*
Y71972D01*
X1157361Y70949D01*
X1156252D01*
G01X1114340Y87300D02*
X1115439D01*
X1116386Y86353D01*
Y83820D01*
X1115416Y82850D01*
X1115068D01*
X1114452Y82234D01*
Y80902D01*
X1114954Y80400D01*
X1115666D01*
X1116386Y79680D01*
Y78720D01*
X1115566Y77900D01*
X1115066D01*
X1114466Y77300D01*
Y76300D01*
X1116386Y74380D01*
Y71091D01*
X1115675Y70380D01*
X1115159D01*
X1114340Y71199D01*
G01X1151152Y87300D02*
X1152249D01*
X1153198Y86351D01*
Y83820D01*
X1152228Y82850D01*
X1151880D01*
X1151264Y82234D01*
Y80902D01*
X1151766Y80400D01*
X1152478D01*
X1153198Y79680D01*
Y78720D01*
X1152378Y77900D01*
X1151878D01*
X1151278Y77300D01*
Y76300D01*
X1153198Y74380D01*
Y71091D01*
X1152487Y70380D01*
X1151971D01*
X1151152Y71199D01*
G01X1119440Y90114D02*
X1122632Y86922D01*
Y71532D01*
X1119440Y68340D01*
G01X1156252Y90114D02*
X1159444Y86922D01*
Y71532D01*
X1156252Y68340D01*
G01X1101926Y188936D02*
Y163575D01*
X1103386Y162115D01*
X1104248D01*
X1105184Y163052D01*
X1106046D01*
X1107030Y162068D01*
Y161206D01*
X1106094Y160269D01*
Y159407D01*
X1107078Y158423D01*
X1107940D01*
X1108876Y159360D01*
X1109738D01*
X1110722Y158376D01*
Y157514D01*
X1109786Y156577D01*
Y155715D01*
X1110770Y154731D01*
X1111632D01*
X1112568Y155668D01*
X1113430D01*
X1114414Y154684D01*
Y153822D01*
X1113478Y152885D01*
Y152023D01*
X1114462Y151039D01*
X1115324D01*
X1116260Y151976D01*
X1117122D01*
X1118106Y150992D01*
Y150130D01*
X1117185Y149209D01*
Y148416D01*
X1118238Y147363D01*
X1119031D01*
X1119952Y148284D01*
X1120814D01*
X1134498Y134600D01*
X1163100D01*
X1183400Y114300D01*
Y111700D01*
X1182174Y110474D01*
Y106074D01*
X1183174Y105074D01*
Y103238D01*
X1181496Y101560D01*
Y92757D01*
G01X1104476Y188936D02*
Y168824D01*
X1135400Y137900D01*
X1153300D01*
X1154500Y136700D01*
X1160000D01*
X1161200Y137900D01*
X1163200D01*
X1186074Y115026D01*
Y102738D01*
X1183674Y100338D01*
Y92474D01*
X1182174Y90974D01*
Y89682D01*
X1184142Y87714D01*
G01X1120716Y193596D02*
Y174283D01*
X1142999Y152000D01*
X1182056D01*
X1199172Y134884D01*
Y133527D01*
X1200340Y132359D01*
X1201132D01*
X1201255Y132482D01*
X1202116D01*
X1203100Y131498D01*
Y130636D01*
X1202063Y129598D01*
Y128736D01*
X1204274Y126525D01*
Y116274D01*
X1206774Y113774D01*
Y111374D01*
X1206274Y110874D01*
Y106174D01*
X1207892Y104556D01*
Y102556D01*
X1207192Y101856D01*
X1205892D01*
X1205092Y101056D01*
Y99856D01*
X1205692Y99256D01*
X1207092D01*
X1207892Y98456D01*
Y97556D01*
X1206792Y96456D01*
X1205356D01*
X1204921Y96021D01*
Y92757D01*
G01X1123266Y193596D02*
Y175133D01*
X1144199Y154200D01*
X1184100D01*
X1206992Y131308D01*
Y117218D01*
X1210174Y114036D01*
Y95339D01*
X1206500Y91665D01*
Y89481D01*
X1208267Y87714D01*
G01X1099376Y193436D02*
X1099200Y193260D01*
Y163301D01*
X1118950Y143551D01*
X1122550D01*
X1133601Y132500D01*
X1160699D01*
X1179674Y113525D01*
Y105674D01*
X1179474Y105474D01*
Y100468D01*
X1178674Y99668D01*
X1178292D01*
X1177492Y98868D01*
Y97268D01*
X1178292Y96468D01*
X1178674D01*
X1179474Y95668D01*
Y94724D01*
X1178706Y93956D01*
X1177692D01*
X1177099Y93363D01*
Y92199D01*
X1175874Y90974D01*
Y89689D01*
X1177849Y87714D01*
G01X1115616Y190596D02*
Y173484D01*
X1141200Y147900D01*
X1172499D01*
X1174911Y145488D01*
X1175773D01*
X1176760Y146476D01*
X1177622D01*
X1178606Y145492D01*
Y144630D01*
X1177619Y143642D01*
Y142780D01*
X1178603Y141796D01*
X1179465D01*
X1180452Y142784D01*
X1181314D01*
X1182298Y141800D01*
Y140938D01*
X1181311Y139950D01*
Y139088D01*
X1182295Y138104D01*
X1183157D01*
X1184130Y139077D01*
X1184923D01*
X1185976Y138024D01*
Y137231D01*
X1185003Y136258D01*
Y135396D01*
X1185987Y134412D01*
X1189088D01*
X1190800Y132700D01*
Y129599D01*
X1199274Y121125D01*
Y114366D01*
X1200340Y113300D01*
Y111840D01*
X1199774Y111274D01*
Y105774D01*
X1200028Y105520D01*
Y99529D01*
X1196308Y95809D01*
Y94677D01*
X1198042Y92942D01*
X1198228Y92757D01*
G01X1118166Y190596D02*
Y173634D01*
X1141900Y149900D01*
X1177400D01*
X1201774Y125526D01*
Y114826D01*
X1202974Y113626D01*
Y111574D01*
X1203374Y111174D01*
Y105474D01*
X1202874Y104974D01*
Y97438D01*
X1202074Y96638D01*
X1201000D01*
X1200200Y95838D01*
Y92100D01*
X1199700Y91600D01*
Y89588D01*
X1201574Y87714D01*
G01X1108110Y189726D02*
Y188726D01*
X1108560Y188276D01*
Y187276D01*
X1108110Y186826D01*
Y185650D01*
X1108560Y185200D01*
Y184200D01*
X1108110Y183750D01*
Y182750D01*
X1108560Y182300D01*
Y181300D01*
X1108110Y180850D01*
Y179850D01*
X1108560Y179400D01*
Y178400D01*
X1108110Y177950D01*
Y176650D01*
X1108560Y176200D01*
Y175200D01*
X1108110Y174750D01*
Y171390D01*
X1108817Y170683D01*
X1109453D01*
X1110161Y169975D01*
Y169339D01*
X1110978Y168522D01*
X1111614D01*
X1112322Y167814D01*
Y167178D01*
X1113128Y166372D01*
X1113764D01*
X1114472Y165664D01*
Y165028D01*
X1115179Y164321D01*
X1115815D01*
X1116523Y163613D01*
Y162977D01*
X1117528Y161972D01*
X1118164D01*
X1118872Y161264D01*
Y160628D01*
X1119928Y159572D01*
X1120564D01*
X1121272Y158864D01*
Y158228D01*
X1137640Y141860D01*
X1170441D01*
X1173311Y138990D01*
Y137248D01*
X1172534Y136471D01*
Y135767D01*
X1173678Y134623D01*
X1174382D01*
X1175159Y135400D01*
X1176901D01*
X1178505Y133796D01*
Y132054D01*
X1177678Y131227D01*
Y130523D01*
X1178822Y129379D01*
X1179526D01*
X1180353Y130206D01*
X1182095D01*
X1183699Y128602D01*
Y126860D01*
X1182722Y125883D01*
Y125179D01*
X1183866Y124035D01*
X1188266D01*
X1191054Y121247D01*
Y118420D01*
X1191674Y117800D01*
Y116800D01*
X1191054Y116180D01*
Y104093D01*
X1191674Y103473D01*
Y102473D01*
X1191054Y101853D01*
Y101021D01*
X1187169Y97136D01*
Y95220D01*
X1187889Y94500D01*
X1188889D01*
X1189689Y93700D01*
Y91626D01*
X1187963Y89900D01*
G01X1111981Y190613D02*
Y171820D01*
X1139201Y144600D01*
X1171300D01*
X1195094Y120806D01*
Y100761D01*
X1191309Y96976D01*
Y89268D01*
X1192838Y87738D01*
X1193063Y87514D01*
G01X1107050Y189726D02*
Y170950D01*
X1137200Y140800D01*
X1170001D01*
X1172251Y138550D01*
Y137688D01*
X1171474Y136911D01*
Y135327D01*
X1173238Y133563D01*
X1174822D01*
X1175599Y134340D01*
X1176461D01*
X1177445Y133356D01*
Y132494D01*
X1176618Y131667D01*
Y130083D01*
X1178382Y128319D01*
X1179966D01*
X1180793Y129146D01*
X1181655D01*
X1182639Y128162D01*
Y127300D01*
X1181662Y126323D01*
Y124739D01*
X1183426Y122975D01*
X1187826D01*
X1189994Y120807D01*
Y101464D01*
X1186109Y97579D01*
Y89154D01*
X1187782Y87482D01*
X1187963Y87300D01*
G01X1113041Y190613D02*
Y189550D01*
X1113491Y189100D01*
Y188100D01*
X1113041Y187650D01*
Y186150D01*
X1113491Y185700D01*
Y184700D01*
X1113041Y184250D01*
Y182950D01*
X1113491Y182500D01*
Y181500D01*
X1113041Y181050D01*
Y180050D01*
X1113491Y179600D01*
Y178600D01*
X1113041Y178150D01*
Y176750D01*
X1113491Y176300D01*
Y175300D01*
X1113041Y174850D01*
Y172260D01*
X1113748Y171553D01*
X1114384D01*
X1115092Y170845D01*
Y170209D01*
X1139641Y145660D01*
X1171740D01*
X1196154Y121246D01*
Y100321D01*
X1192369Y96536D01*
Y95281D01*
X1193050Y94600D01*
X1193789D01*
X1194344Y94044D01*
X1194630Y93759D01*
X1194889Y93500D01*
Y91940D01*
X1193063Y90114D01*
G01X1133000Y197701D02*
X1137900Y192801D01*
Y190484D01*
X1138510Y189874D01*
X1140090D01*
X1140700Y189264D01*
Y187874D01*
X1140090Y187264D01*
X1138510D01*
X1137900Y186654D01*
Y184881D01*
X1138460Y184321D01*
X1140540D01*
X1141100Y183761D01*
Y182321D01*
X1140540Y181761D01*
X1138460D01*
X1137900Y181201D01*
Y180200D01*
X1139241Y178859D01*
X1155242D01*
X1169801Y164300D01*
X1186501D01*
X1212329Y138472D01*
X1219174D01*
X1220700Y136946D01*
Y135672D01*
X1219174Y134146D01*
Y132872D01*
X1220700Y131346D01*
Y130072D01*
X1219174Y128546D01*
Y127272D01*
X1220700Y125746D01*
Y124472D01*
X1219174Y122946D01*
Y121672D01*
X1220700Y120146D01*
Y118872D01*
X1219174Y117346D01*
Y116072D01*
X1220700Y114546D01*
Y113272D01*
X1219174Y111746D01*
Y110472D01*
X1220700Y108946D01*
Y107672D01*
X1219174Y106146D01*
Y104872D01*
X1220700Y103346D01*
Y102072D01*
X1219174Y100546D01*
Y99673D01*
X1217392Y97891D01*
Y93672D01*
X1218307Y92757D01*
G01X1134600Y198962D02*
Y198900D01*
X1152756Y180744D01*
X1156857D01*
X1168201Y169400D01*
X1171663D01*
X1172273Y168790D01*
Y167510D01*
X1172883Y166900D01*
X1174273D01*
X1174883Y167510D01*
Y168790D01*
X1175493Y169400D01*
X1176883D01*
X1177493Y168790D01*
Y167510D01*
X1178103Y166900D01*
X1179493D01*
X1180103Y167510D01*
Y168790D01*
X1180713Y169400D01*
X1186200D01*
X1214300Y141300D01*
X1220201D01*
X1223200Y138301D01*
Y100265D01*
X1220374Y97439D01*
Y92274D01*
X1218974Y90874D01*
Y89693D01*
X1220953Y87714D01*
G01X1150705Y205294D02*
X1161344Y194655D01*
X1166944D01*
X1173299Y188300D01*
X1175905D01*
X1176465Y188860D01*
Y191740D01*
X1177025Y192300D01*
X1178465D01*
X1179025Y191740D01*
Y188860D01*
X1179585Y188300D01*
X1190600D01*
X1216026Y162874D01*
X1226674D01*
X1241732Y147816D01*
Y92757D01*
G01X1245078Y87714D02*
X1243300Y89492D01*
Y91200D01*
X1244300Y92200D01*
Y148848D01*
X1225824Y167324D01*
X1215876D01*
X1189700Y193500D01*
X1155484Y203316D01*
X1151900Y206900D01*
G01X1129300Y194501D02*
Y191157D01*
X1129910Y190547D01*
X1132890D01*
X1133500Y189937D01*
Y188547D01*
X1132890Y187937D01*
X1127510D01*
X1126900Y187327D01*
Y185937D01*
X1127510Y185327D01*
X1132690D01*
X1133300Y184717D01*
Y183327D01*
X1132690Y182717D01*
X1129910D01*
X1129300Y182107D01*
Y178101D01*
X1132601Y174800D01*
X1152601D01*
X1168901Y158500D01*
X1185000D01*
X1210500Y133000D01*
Y118400D01*
X1214174Y114726D01*
Y101173D01*
X1212774Y99773D01*
Y93917D01*
X1211614Y92757D01*
G01X1130800Y196301D02*
X1135500Y191601D01*
Y178401D01*
X1136927Y176974D01*
X1153726D01*
X1169000Y161700D01*
X1185600D01*
X1216674Y130626D01*
Y128546D01*
X1216064Y127936D01*
X1214200D01*
X1213700Y127436D01*
Y125826D01*
X1214200Y125326D01*
X1216064D01*
X1216674Y124716D01*
Y123326D01*
X1216064Y122716D01*
X1214110D01*
X1213500Y122106D01*
Y120716D01*
X1214110Y120106D01*
X1216064D01*
X1216674Y119496D01*
Y100275D01*
X1215274Y98875D01*
Y93260D01*
X1214660Y92646D01*
Y87588D01*
X1214874Y87374D01*
G01X1145200Y202900D02*
X1159500Y188600D01*
X1164100D01*
X1169100Y183600D01*
X1188100D01*
X1216126Y155574D01*
X1226126D01*
X1233400Y148300D01*
Y120067D01*
X1234200Y119267D01*
X1235800D01*
X1236600Y118467D01*
Y116867D01*
X1235800Y116067D01*
X1234200D01*
X1233400Y115267D01*
Y113667D01*
X1234200Y112867D01*
X1235800D01*
X1236600Y112067D01*
Y110467D01*
X1235800Y109667D01*
X1234200D01*
X1233400Y108867D01*
Y107259D01*
X1234200Y106459D01*
X1235792D01*
X1236592Y105659D01*
Y104759D01*
X1235892Y104059D01*
X1234992D01*
X1234092Y103159D01*
Y100859D01*
X1234951Y100000D01*
X1235792D01*
X1236592Y99200D01*
Y97659D01*
X1235792Y96859D01*
X1234892D01*
X1234092Y96059D01*
Y94808D01*
X1235039Y93861D01*
Y92757D01*
G01X1238385Y87714D02*
X1236474Y89625D01*
Y91050D01*
X1239192Y93768D01*
Y127230D01*
X1238392Y128030D01*
X1236700D01*
X1235900Y128830D01*
Y130430D01*
X1236700Y131230D01*
X1238392D01*
X1239000Y131838D01*
Y133822D01*
X1238392Y134430D01*
X1236700D01*
X1235900Y135230D01*
Y149848D01*
X1226324Y159424D01*
X1216176D01*
X1189500Y186100D01*
X1171200D01*
X1166084Y191216D01*
X1159684D01*
X1147000Y203900D01*
G01X1137812Y201289D02*
X1138519Y200582D01*
X1139155D01*
X1139863Y199874D01*
Y199238D01*
X1140570Y198531D01*
X1141206D01*
X1141914Y197823D01*
Y197187D01*
X1142621Y196480D01*
X1143257D01*
X1143965Y195772D01*
Y195136D01*
X1144728Y194373D01*
X1145365D01*
X1146073Y193665D01*
Y193028D01*
X1146780Y192321D01*
X1147416D01*
X1148124Y191613D01*
Y190977D01*
X1148878Y190223D01*
X1149515D01*
X1150223Y189515D01*
Y188878D01*
X1150930Y188171D01*
X1151566D01*
X1152274Y187463D01*
Y186827D01*
X1152980Y186120D01*
X1153617D01*
X1154325Y185412D01*
Y184776D01*
X1155411Y183689D01*
X1158512D01*
X1159219Y182982D01*
X1159855D01*
X1160563Y182274D01*
Y181638D01*
X1161270Y180931D01*
X1161906D01*
X1162614Y180223D01*
Y179587D01*
X1163321Y178880D01*
X1163957D01*
X1164665Y178172D01*
Y177536D01*
X1165372Y176829D01*
X1166008D01*
X1166716Y176121D01*
Y175485D01*
X1168841Y173360D01*
X1171471D01*
X1172081Y173970D01*
Y176970D01*
X1173311Y178200D01*
X1175581D01*
X1176811Y176970D01*
Y173970D01*
X1177421Y173360D01*
X1188440D01*
X1213499Y148301D01*
X1224299D01*
X1227060Y145540D01*
Y104150D01*
X1227510Y103700D01*
Y99710D01*
X1224260Y96460D01*
Y94940D01*
X1224800Y94400D01*
X1225500D01*
X1226500Y93400D01*
Y91626D01*
X1224774Y89900D01*
G01X1139849Y203538D02*
X1157813Y185574D01*
X1162726D01*
X1168200Y180100D01*
X1186501D01*
X1215026Y151575D01*
X1225325D01*
X1230000Y146900D01*
Y98200D01*
X1228150Y96350D01*
Y89238D01*
X1229874Y87514D01*
G01X1137066Y200542D02*
X1154979Y182629D01*
X1158072D01*
X1168401Y172300D01*
X1171911D01*
X1173141Y173530D01*
Y176530D01*
X1173751Y177140D01*
X1175141D01*
X1175751Y176530D01*
Y173530D01*
X1176981Y172300D01*
X1188000D01*
X1213059Y147241D01*
X1223859D01*
X1226000Y145100D01*
Y99700D01*
X1223200Y96900D01*
Y93661D01*
X1222800Y93261D01*
Y89274D01*
X1224774Y87300D01*
G01X1140599Y204288D02*
X1158253Y186634D01*
X1163166D01*
X1168640Y181160D01*
X1186941D01*
X1215466Y152635D01*
X1225765D01*
X1231060Y147340D01*
Y97760D01*
X1229210Y95910D01*
Y95290D01*
X1230000Y94500D01*
X1230500D01*
X1231600Y93400D01*
Y91840D01*
X1229874Y90114D01*
G01X1097700Y417141D02*
Y451899D01*
X1125645Y479844D01*
X1161343D01*
X1168700Y487201D01*
Y494600D01*
X1169200Y495100D01*
Y496700D01*
X1170152Y497652D01*
Y499515D01*
X1169352Y500315D01*
X1169100D01*
X1168300Y501115D01*
Y502715D01*
X1169100Y503515D01*
X1169352D01*
X1170152Y504315D01*
Y511047D01*
X1167500Y513699D01*
Y517547D01*
X1168110Y518157D01*
G01X1100274Y417141D02*
Y451772D01*
X1100985Y452483D01*
X1101847D01*
X1103145Y451185D01*
X1104007D01*
X1104991Y452169D01*
Y453031D01*
X1103693Y454329D01*
Y455191D01*
X1105847Y457345D01*
X1106709D01*
X1107097Y456957D01*
X1107958D01*
X1109359Y458358D01*
Y459220D01*
X1108972Y459608D01*
Y460470D01*
X1110373Y461871D01*
X1111235D01*
X1111623Y461483D01*
X1112484D01*
X1113885Y462884D01*
Y463746D01*
X1113498Y464134D01*
Y464996D01*
X1114899Y466397D01*
X1115761D01*
X1116149Y466009D01*
X1117010D01*
X1118411Y467410D01*
Y468272D01*
X1118024Y468660D01*
Y469522D01*
X1119425Y470923D01*
X1120287D01*
X1120675Y470535D01*
X1121536D01*
X1122937Y471936D01*
Y472798D01*
X1122550Y473186D01*
Y474048D01*
X1125846Y477344D01*
X1162543D01*
X1172600Y487401D01*
Y491478D01*
X1172400Y491678D01*
Y502000D01*
X1172900Y502500D01*
Y511670D01*
X1171456Y513114D01*
G01X1108776Y415450D02*
Y436777D01*
X1117850Y445851D01*
Y450649D01*
X1135545Y468344D01*
X1175960D01*
X1177712Y470096D01*
Y471403D01*
X1174252Y474863D01*
Y475952D01*
X1182274Y483974D01*
Y496452D01*
X1183400Y497578D01*
Y502744D01*
X1184232Y503576D01*
Y508168D01*
X1183300Y509100D01*
Y510906D01*
X1180641Y513565D01*
Y517302D01*
X1181496Y518157D01*
G01X1111326Y415485D02*
Y436126D01*
X1120000Y444800D01*
Y449100D01*
X1136744Y465844D01*
X1176944D01*
X1188105Y477005D01*
Y478225D01*
X1186974Y479356D01*
X1185930D01*
X1180302Y473728D01*
X1179170D01*
X1178039Y474859D01*
Y475991D01*
X1186063Y484015D01*
Y501964D01*
X1187100Y503001D01*
Y508300D01*
X1186063Y509337D01*
Y510843D01*
X1184142Y512764D01*
Y513114D01*
G01X1127122Y420136D02*
Y429422D01*
X1133400Y435700D01*
Y442931D01*
X1143160Y452691D01*
X1157795D01*
X1165030Y445456D01*
X1180555D01*
X1203800Y468701D01*
Y485956D01*
X1206963Y489119D01*
Y491352D01*
X1206500Y491815D01*
Y497278D01*
X1206721Y497499D01*
Y511379D01*
X1203563Y514537D01*
Y516799D01*
X1204921Y518157D01*
G01X1128700Y418277D02*
X1129200Y418777D01*
Y427200D01*
X1136725Y434725D01*
Y443403D01*
X1144084Y450762D01*
X1156812D01*
X1164024Y443550D01*
X1168552D01*
X1169162Y442940D01*
Y441550D01*
X1169772Y440940D01*
X1171162D01*
X1171772Y441550D01*
Y442940D01*
X1172382Y443550D01*
X1173772D01*
X1174382Y442940D01*
Y441550D01*
X1174992Y440940D01*
X1176382D01*
X1176992Y441550D01*
Y442940D01*
X1177602Y443550D01*
X1182349D01*
X1206300Y467501D01*
Y484920D01*
X1210074Y488694D01*
Y497100D01*
X1209221Y497953D01*
Y512212D01*
X1208267Y513166D01*
Y513114D01*
G01X1103676Y414736D02*
Y444277D01*
X1118362Y458963D01*
Y460093D01*
X1117493Y460961D01*
Y462091D01*
X1118626Y463224D01*
X1119756D01*
X1120625Y462356D01*
X1121755D01*
X1122888Y463489D01*
Y464619D01*
X1122019Y465487D01*
Y466617D01*
X1123152Y467750D01*
X1124282D01*
X1125151Y466882D01*
X1126281D01*
X1127414Y468015D01*
Y469145D01*
X1126545Y470013D01*
Y471143D01*
X1127678Y472276D01*
X1128808D01*
X1129677Y471408D01*
X1130807D01*
X1132743Y473344D01*
X1164244D01*
X1175600Y484700D01*
Y491826D01*
X1175900Y492126D01*
Y496979D01*
X1176100Y497179D01*
Y500000D01*
X1175600Y500500D01*
Y508099D01*
X1176611Y509110D01*
Y511207D01*
X1174343Y513475D01*
Y517697D01*
X1174803Y518157D01*
G01X1106226Y414706D02*
Y437920D01*
X1110500Y442194D01*
Y443447D01*
X1108508Y445439D01*
Y446212D01*
X1110244Y447948D01*
X1111150D01*
X1113486Y445612D01*
X1114348D01*
X1115749Y447013D01*
Y447875D01*
X1113937Y449687D01*
Y450937D01*
X1133844Y470844D01*
X1165345D01*
X1167316Y472815D01*
X1168447D01*
X1170790Y470472D01*
X1171974D01*
X1173168Y471666D01*
Y472620D01*
X1170709Y475079D01*
Y476207D01*
X1179675Y485173D01*
Y494125D01*
X1178300Y495500D01*
Y501400D01*
X1177500Y502200D01*
Y504000D01*
X1178071Y504571D01*
X1181200D01*
X1182000Y505371D01*
Y506971D01*
X1181200Y507771D01*
X1179400D01*
X1178600Y508571D01*
Y512363D01*
X1177849Y513114D01*
G01X1121276Y418391D02*
Y432476D01*
X1128900Y440100D01*
Y443763D01*
X1141598Y456461D01*
X1160363D01*
X1164608Y452216D01*
X1179915D01*
X1198800Y471101D01*
Y494100D01*
X1199800Y495100D01*
Y497389D01*
X1200300Y497889D01*
Y510920D01*
X1197563Y513657D01*
Y517492D01*
X1198228Y518157D01*
G01X1123826Y419224D02*
Y430426D01*
X1131000Y437600D01*
Y443197D01*
X1142379Y454576D01*
X1158904D01*
X1166020Y447460D01*
X1168264D01*
X1168874Y448070D01*
Y449536D01*
X1169484Y450146D01*
X1170874D01*
X1171484Y449536D01*
Y448070D01*
X1172094Y447460D01*
X1173484D01*
X1174094Y448070D01*
Y449536D01*
X1174704Y450146D01*
X1176094D01*
X1176704Y449536D01*
Y448070D01*
X1177314Y447460D01*
X1178959D01*
X1201300Y469801D01*
Y486992D01*
X1203985Y489677D01*
Y493215D01*
X1202355Y494845D01*
Y502152D01*
X1203110Y502907D01*
X1204255D01*
X1204865Y503517D01*
Y504907D01*
X1204255Y505517D01*
X1203030D01*
X1202421Y506126D01*
Y512267D01*
X1201574Y513114D01*
G01X1145400Y421150D02*
X1149580Y425330D01*
X1155964D01*
X1160834Y430200D01*
X1182128D01*
X1225474Y473546D01*
Y489803D01*
X1224674Y490603D01*
X1223074D01*
X1222274Y489803D01*
Y488200D01*
X1221474Y487400D01*
X1219874D01*
X1219074Y488200D01*
Y508174D01*
X1220000Y509100D01*
Y511081D01*
X1216900Y514181D01*
Y516750D01*
X1218307Y518157D01*
G01X1147062Y419550D02*
X1150957Y423445D01*
X1156745D01*
X1161600Y428300D01*
X1183764D01*
X1222695Y467231D01*
X1223731D01*
X1225476Y468976D01*
Y470012D01*
X1227974Y472510D01*
Y473675D01*
X1229100Y474801D01*
Y476875D01*
X1227974Y478001D01*
Y491454D01*
X1226708Y492720D01*
X1222266D01*
X1221486Y493500D01*
Y495085D01*
X1222364Y495963D01*
X1227452D01*
X1228033Y496544D01*
Y498538D01*
X1227408Y499163D01*
X1222616D01*
X1221860Y499919D01*
Y501680D01*
X1222470Y502290D01*
X1225793D01*
X1226403Y502900D01*
Y504290D01*
X1225793Y504900D01*
X1222829D01*
X1222065Y505664D01*
Y511652D01*
X1220953Y512764D01*
Y513114D01*
G01X1172099Y412000D02*
X1178434D01*
X1182534Y416100D01*
X1193247D01*
X1219847Y442700D01*
X1225308D01*
X1251200Y468592D01*
Y495226D01*
X1250386Y496040D01*
X1248822D01*
X1248000Y495218D01*
Y492492D01*
X1247233Y491725D01*
X1245633D01*
X1244800Y492558D01*
Y507700D01*
X1243774Y508726D01*
Y510907D01*
X1241300Y513381D01*
Y517725D01*
X1241732Y518157D01*
G01X1172100Y409500D02*
X1178600D01*
X1183100Y414000D01*
X1194683D01*
X1221383Y440700D01*
X1226844D01*
X1253700Y467556D01*
Y506172D01*
X1253090Y506782D01*
X1251700D01*
X1251090Y506172D01*
Y499205D01*
X1250480Y498595D01*
X1249090D01*
X1248480Y499205D01*
Y507320D01*
X1246374Y509426D01*
Y511870D01*
X1245078Y513166D01*
Y513114D01*
G01X1143300Y421950D02*
X1148565Y427215D01*
X1155182D01*
X1160167Y432200D01*
X1180435D01*
X1182808Y434573D01*
Y436206D01*
X1184255Y437653D01*
X1185888D01*
X1187334Y439099D01*
Y440732D01*
X1188781Y442179D01*
X1190414D01*
X1191860Y443625D01*
Y445258D01*
X1193307Y446705D01*
X1194940D01*
X1196386Y448151D01*
Y449784D01*
X1197833Y451231D01*
X1199466D01*
X1200912Y452677D01*
Y454310D01*
X1202359Y455757D01*
X1203992D01*
X1205438Y457203D01*
Y458836D01*
X1206885Y460283D01*
X1208518D01*
X1209964Y461729D01*
Y463362D01*
X1211411Y464809D01*
X1213044D01*
X1222974Y474739D01*
Y484000D01*
X1222174Y484800D01*
X1220574D01*
X1219774Y484000D01*
Y481000D01*
X1218974Y480200D01*
X1217374D01*
X1216574Y481000D01*
Y508727D01*
X1215200Y510101D01*
Y512448D01*
X1214874Y512774D01*
G01X1172400Y416000D02*
X1177102D01*
X1181202Y420100D01*
X1190099D01*
X1222403Y452404D01*
X1227941D01*
X1246200Y470663D01*
Y478809D01*
X1245444Y479565D01*
X1243844D01*
X1243000Y478721D01*
Y472969D01*
X1242244Y472213D01*
X1240644D01*
X1239800Y473057D01*
Y505936D01*
X1237274Y508462D01*
Y510757D01*
X1234374Y513657D01*
Y517492D01*
X1235039Y518157D01*
G01X1172350Y414100D02*
X1177868D01*
X1181968Y418200D01*
X1191811D01*
X1219795Y446184D01*
X1220657D01*
X1221689Y445153D01*
X1222551D01*
X1223952Y446554D01*
Y447416D01*
X1222920Y448447D01*
Y449309D01*
X1223515Y449904D01*
X1228977D01*
X1248700Y469627D01*
Y481079D01*
X1247744Y482035D01*
X1242923D01*
X1242123Y482835D01*
Y484781D01*
X1242923Y485581D01*
X1246165D01*
X1246965Y486381D01*
Y487981D01*
X1246165Y488781D01*
X1243100D01*
X1242300Y489581D01*
Y506800D01*
X1239774Y509326D01*
Y511768D01*
X1239731D01*
X1238385Y513114D01*
G01X1115006Y416387D02*
Y434406D01*
X1123100Y442500D01*
Y446668D01*
X1138585Y462153D01*
X1179274D01*
X1179272Y462154D01*
X1191070Y473952D01*
Y512193D01*
X1187963Y515300D01*
G01X1155621Y417351D02*
X1159970Y421700D01*
X1175150D01*
X1178650Y425200D01*
X1185868D01*
X1232220Y471552D01*
Y503151D01*
X1227954Y507417D01*
Y512120D01*
X1224774Y515300D01*
G01X1117636Y419887D02*
Y433636D01*
X1125540Y441540D01*
Y444569D01*
X1140377Y459406D01*
X1164498D01*
X1165990Y457914D01*
Y456152D01*
X1166862Y455280D01*
X1168558D01*
X1169430Y456152D01*
Y457768D01*
X1170810Y459148D01*
X1173610D01*
X1174990Y457768D01*
Y456152D01*
X1175862Y455280D01*
X1177458D01*
X1188200Y466022D01*
Y466872D01*
X1188928Y467600D01*
X1189778D01*
X1190600Y468422D01*
Y469272D01*
X1191328Y470000D01*
X1192178D01*
X1192900Y470722D01*
Y471572D01*
X1193528Y472200D01*
X1194378D01*
X1195083Y472905D01*
Y474980D01*
X1194383Y475680D01*
Y476400D01*
X1195083Y477100D01*
Y478220D01*
X1194383Y478920D01*
Y479640D01*
X1195083Y480340D01*
Y481460D01*
X1194383Y482160D01*
Y482880D01*
X1195083Y483580D01*
Y484700D01*
X1194383Y485400D01*
Y486120D01*
X1195083Y486820D01*
Y487940D01*
X1194383Y488640D01*
Y489360D01*
X1195083Y490060D01*
Y499816D01*
X1194383Y500516D01*
Y501584D01*
X1195083Y502284D01*
Y503516D01*
X1194383Y504216D01*
Y505084D01*
X1195083Y505784D01*
Y506916D01*
X1194383Y507616D01*
Y508560D01*
X1195083Y509260D01*
Y511994D01*
X1193967Y513110D01*
X1193259D01*
X1193063Y512914D01*
G01X1156250Y415130D02*
X1160830Y419710D01*
X1176110D01*
X1179460Y423060D01*
X1187928D01*
X1222013Y457145D01*
X1224127D01*
X1225188Y456084D01*
X1226414D01*
X1228188Y457858D01*
Y459084D01*
X1227220Y460052D01*
Y462349D01*
X1229516Y464645D01*
X1231627D01*
X1232745Y463527D01*
X1233976D01*
X1236120Y465671D01*
Y484732D01*
X1235500Y485352D01*
Y486352D01*
X1236120Y486972D01*
Y487972D01*
X1235500Y488592D01*
Y489592D01*
X1236120Y490212D01*
Y491212D01*
X1235500Y491832D01*
Y492832D01*
X1236120Y493452D01*
Y494452D01*
X1235500Y495072D01*
Y496072D01*
X1236120Y496692D01*
Y497692D01*
X1235500Y498312D01*
Y499312D01*
X1236120Y499932D01*
Y500932D01*
X1235500Y501552D01*
Y502552D01*
X1236120Y503172D01*
Y504303D01*
X1234666Y505757D01*
X1234151D01*
X1233444Y506464D01*
Y506979D01*
X1232274Y508149D01*
Y511614D01*
X1230974Y512914D01*
X1229874D01*
G01X1113946Y416387D02*
Y434846D01*
X1122040Y442940D01*
Y447108D01*
X1138145Y463213D01*
X1178831D01*
X1190010Y474392D01*
Y506416D01*
X1189390Y507036D01*
Y508036D01*
X1190010Y508656D01*
Y511753D01*
X1189063Y512700D01*
X1187963D01*
G01X1154870Y418100D02*
X1159530Y422760D01*
X1174710D01*
X1178210Y426260D01*
X1185428D01*
X1231160Y471992D01*
Y479951D01*
X1230694Y480417D01*
Y481417D01*
X1231160Y481883D01*
Y483059D01*
X1230540Y483679D01*
Y484679D01*
X1231160Y485299D01*
Y486299D01*
X1230540Y486919D01*
Y487919D01*
X1231160Y488539D01*
Y489539D01*
X1230540Y490159D01*
Y491159D01*
X1231160Y491779D01*
Y492779D01*
X1230540Y493399D01*
Y494399D01*
X1231160Y495019D01*
Y496019D01*
X1230540Y496639D01*
Y497639D01*
X1231160Y498259D01*
Y499259D01*
X1230540Y499879D01*
Y500879D01*
X1231160Y501499D01*
Y502711D01*
X1229799Y504072D01*
X1229219D01*
X1228512Y504779D01*
Y505359D01*
X1226894Y506977D01*
Y511680D01*
X1225874Y512700D01*
X1224774D01*
G01X1118696Y419887D02*
Y433196D01*
X1126600Y441100D01*
Y444129D01*
X1140817Y458346D01*
X1164058D01*
X1164930Y457474D01*
Y455709D01*
X1166419Y454220D01*
X1168998D01*
X1170490Y455712D01*
Y457328D01*
X1171250Y458088D01*
X1173170D01*
X1173930Y457328D01*
Y455712D01*
X1175422Y454220D01*
X1177898D01*
X1196143Y472465D01*
Y512434D01*
X1193063Y515514D01*
G01X1157120Y414500D02*
X1161270Y418650D01*
X1176550D01*
X1179900Y422000D01*
X1188368D01*
X1222453Y456085D01*
X1223684D01*
X1224745Y455024D01*
X1226857D01*
X1229248Y457415D01*
Y459527D01*
X1228280Y460495D01*
Y461909D01*
X1229956Y463585D01*
X1231187D01*
X1232305Y462467D01*
X1234416D01*
X1237180Y465231D01*
Y504743D01*
X1233334Y508589D01*
Y512054D01*
X1229874Y515514D01*
G01X1141600Y423500D02*
X1147200Y429100D01*
X1154400D01*
X1160000Y434700D01*
X1177899D01*
X1210400Y467201D01*
Y473583D01*
X1211246Y474429D01*
X1217454D01*
X1218244Y475219D01*
Y476819D01*
X1217434Y477629D01*
X1211200D01*
X1210400Y478429D01*
Y480029D01*
X1211200Y480829D01*
X1213274D01*
X1214074Y481629D01*
Y498757D01*
X1213414Y499417D01*
Y511275D01*
X1210374Y514315D01*
Y516917D01*
X1211614Y518157D01*
G01X1110520Y534700D02*
X1109354D01*
X1106169Y531515D01*
Y519862D01*
X1107874Y518157D01*
G01Y528899D02*
X1108854D01*
X1109453Y528300D01*
Y527100D01*
X1108509Y526156D01*
Y524944D01*
X1109353Y524100D01*
Y522400D01*
X1108509Y521556D01*
Y520136D01*
X1109653Y518992D01*
Y517399D01*
X1108746Y516492D01*
Y514800D01*
X1110432Y513114D01*
X1110520D01*
G01X1134645Y535100D02*
X1129594Y530049D01*
Y519862D01*
X1131299Y518157D01*
G01Y528899D02*
X1132371D01*
X1133071Y528199D01*
Y526925D01*
X1131934Y525788D01*
Y524712D01*
X1132946Y523700D01*
Y522500D01*
X1131934Y521488D01*
Y520412D01*
X1133046Y519300D01*
Y516667D01*
X1132871Y516492D01*
Y514800D01*
X1134557Y513114D01*
X1134645D01*
G01X1104141Y534700D02*
X1103153D01*
X1100098Y531645D01*
Y530457D01*
X1099476Y529835D01*
Y519862D01*
X1101181Y518157D01*
G01Y528899D02*
X1102253D01*
X1102853Y528299D01*
Y527401D01*
X1101816Y526364D01*
Y525136D01*
X1102753Y524199D01*
Y522801D01*
X1101816Y521864D01*
Y520536D01*
X1102953Y519399D01*
Y517500D01*
X1102453Y517000D01*
Y514800D01*
X1104139Y513114D01*
X1104227D01*
G01X1127952Y535100D02*
X1122901Y530049D01*
Y519862D01*
X1124606Y518157D01*
G01Y528899D02*
X1125678D01*
X1126378Y528199D01*
Y526925D01*
X1125241Y525788D01*
Y524712D01*
X1126253Y523700D01*
Y522500D01*
X1125241Y521488D01*
Y520412D01*
X1126353Y519300D01*
Y516667D01*
X1126178Y516492D01*
Y514800D01*
X1127864Y513114D01*
X1127952D01*
G01X1144685Y518157D02*
X1142980Y519862D01*
Y531515D01*
X1146165Y534700D01*
X1147331D01*
G01Y513114D02*
X1147243D01*
X1145557Y514800D01*
Y516492D01*
X1146464Y517399D01*
Y518992D01*
X1145320Y520136D01*
Y521556D01*
X1146164Y522400D01*
Y524100D01*
X1145320Y524944D01*
Y526156D01*
X1146264Y527100D01*
Y528300D01*
X1145665Y528899D01*
X1144685D01*
G01X1137992Y518157D02*
X1136287Y519862D01*
Y529835D01*
X1136909Y530457D01*
Y531645D01*
X1139964Y534700D01*
X1140952D01*
G01X1141038Y513114D02*
X1140950D01*
X1139264Y514800D01*
Y517000D01*
X1139764Y517500D01*
Y519399D01*
X1138627Y520536D01*
Y521864D01*
X1139564Y522801D01*
Y524199D01*
X1138627Y525136D01*
Y526364D01*
X1139664Y527401D01*
Y528299D01*
X1139064Y528899D01*
X1137992D01*
G01X1114366Y531750D02*
X1114367D01*
X1116072Y530045D01*
Y528139D01*
X1115333Y527400D01*
X1114053D01*
X1113413Y526760D01*
Y525340D01*
X1113963Y524790D01*
X1114543D01*
X1115153Y524180D01*
Y522790D01*
X1114543Y522180D01*
X1113933D01*
X1113413Y521660D01*
Y520290D01*
X1114003Y519700D01*
X1114953D01*
X1116053Y518600D01*
Y517013D01*
X1114340Y515300D01*
G01X1151152D02*
X1152864Y517012D01*
Y518600D01*
X1151764Y519700D01*
X1150814D01*
X1150224Y520290D01*
Y521660D01*
X1150744Y522180D01*
X1151354D01*
X1151964Y522790D01*
Y524180D01*
X1151354Y524790D01*
X1150774D01*
X1150224Y525340D01*
Y526760D01*
X1150864Y527400D01*
X1152144D01*
X1152883Y528139D01*
Y530045D01*
X1151178Y531750D01*
G01X1119440Y534149D02*
X1117735Y532444D01*
Y527499D01*
X1116906Y526670D01*
Y520130D01*
X1117735Y519301D01*
Y514265D01*
X1119086Y512914D01*
X1119440D01*
G01X1156252D02*
X1155964D01*
X1154547Y514331D01*
Y519300D01*
X1153717Y520130D01*
Y526670D01*
X1154547Y527500D01*
Y532444D01*
X1156252Y534149D01*
G01X1114340Y534399D02*
X1112353Y532412D01*
Y514347D01*
X1114000Y512700D01*
X1114340D01*
G01X1151152D02*
X1150800D01*
X1149164Y514336D01*
Y532411D01*
X1151152Y534399D01*
G01X1119440Y531540D02*
X1119441D01*
X1121253Y529728D01*
Y528000D01*
X1120253Y527000D01*
X1118737D01*
X1117966Y526229D01*
Y525338D01*
X1118506Y524798D01*
X1118743D01*
X1119453Y524088D01*
Y523000D01*
X1118753Y522300D01*
X1118418D01*
X1117966Y521848D01*
Y520571D01*
X1118637Y519900D01*
X1120153D01*
X1121153Y518900D01*
Y517226D01*
X1119441Y515514D01*
X1119440D01*
G01X1156252D02*
X1157964Y517226D01*
Y518900D01*
X1156964Y519900D01*
X1155448D01*
X1154777Y520571D01*
Y521848D01*
X1155229Y522300D01*
X1155564D01*
X1156264Y523000D01*
Y524088D01*
X1155554Y524798D01*
X1155317D01*
X1154777Y525338D01*
Y526229D01*
X1155548Y527000D01*
X1157064D01*
X1158064Y528000D01*
Y529728D01*
X1156252Y531540D01*
G01X1168110Y92757D02*
X1166989Y91636D01*
Y88700D01*
X1170331Y85358D01*
Y84300D01*
X1168531Y82500D01*
Y80925D01*
X1169731Y79725D01*
Y78599D01*
X1168531Y77399D01*
Y76026D01*
X1169889Y74668D01*
Y73467D01*
X1171456Y71900D01*
G01Y87714D02*
X1172845Y86325D01*
Y73312D01*
X1173457Y72700D01*
Y71300D01*
X1171657Y69500D01*
X1170657D01*
X1168110Y66953D01*
Y65699D01*
G01X1161417Y92757D02*
X1160489Y91829D01*
Y88701D01*
X1163531Y85659D01*
Y84274D01*
X1161856Y82599D01*
Y81476D01*
X1163356Y79976D01*
Y78624D01*
X1161856Y77124D01*
Y75901D01*
X1163289Y74468D01*
Y73374D01*
X1164763Y71900D01*
G01Y87714D02*
X1166152Y86325D01*
Y73312D01*
X1166764Y72700D01*
Y71300D01*
X1164964Y69500D01*
X1163964D01*
X1161417Y66953D01*
Y65699D01*
G01X1181496Y92757D02*
X1180375Y91636D01*
Y88700D01*
X1183275Y85800D01*
Y83832D01*
X1181742Y82299D01*
Y81100D01*
X1182992Y79850D01*
Y78950D01*
X1181642Y77600D01*
Y76301D01*
X1183275Y74668D01*
Y72367D01*
X1184142Y71500D01*
G01Y87714D02*
X1185615Y86241D01*
Y73116D01*
X1186231Y72500D01*
Y71156D01*
X1184775Y69700D01*
X1183375D01*
X1181496Y67821D01*
Y65699D01*
G01X1204921Y92757D02*
X1203800Y91636D01*
Y88700D01*
X1207142Y85358D01*
Y84300D01*
X1205342Y82500D01*
Y80925D01*
X1206542Y79725D01*
Y78599D01*
X1205342Y77399D01*
Y76026D01*
X1206700Y74668D01*
Y73467D01*
X1208267Y71900D01*
G01Y87714D02*
X1209656Y86325D01*
Y73312D01*
X1210268Y72700D01*
Y71300D01*
X1208468Y69500D01*
X1207468D01*
X1204921Y66953D01*
Y65699D01*
G01X1174803Y92757D02*
X1173875Y91829D01*
Y88701D01*
X1176675Y85901D01*
Y84032D01*
X1175292Y82649D01*
Y81250D01*
X1176742Y79800D01*
Y78600D01*
X1175242Y77100D01*
Y75901D01*
X1176675Y74468D01*
Y72588D01*
X1177763Y71500D01*
G01X1177849Y87714D02*
X1179075Y86488D01*
Y73475D01*
X1179850Y72700D01*
Y71076D01*
X1178274Y69500D01*
X1177050D01*
X1174803Y67253D01*
Y65699D01*
G01X1198228Y92757D02*
X1197300Y91829D01*
Y88701D01*
X1200342Y85659D01*
Y84274D01*
X1198667Y82599D01*
Y81476D01*
X1200167Y79976D01*
Y78624D01*
X1198667Y77124D01*
Y75901D01*
X1200100Y74468D01*
Y73374D01*
X1201574Y71900D01*
G01Y87714D02*
X1202963Y86325D01*
Y73312D01*
X1203575Y72700D01*
Y71300D01*
X1201775Y69500D01*
X1200775D01*
X1198228Y66953D01*
Y65699D01*
G01X1218307Y92757D02*
X1217186Y91636D01*
Y88700D01*
X1220086Y85800D01*
Y83832D01*
X1218553Y82299D01*
Y81100D01*
X1219803Y79850D01*
Y78950D01*
X1218453Y77600D01*
Y76301D01*
X1220086Y74668D01*
Y72367D01*
X1220953Y71500D01*
G01Y87714D02*
X1222426Y86241D01*
Y73116D01*
X1223042Y72500D01*
Y71156D01*
X1221586Y69700D01*
X1220186D01*
X1218307Y67821D01*
Y65699D01*
G01X1211614Y92757D02*
X1210686Y91829D01*
Y88701D01*
X1213486Y85901D01*
Y84032D01*
X1212103Y82649D01*
Y81250D01*
X1213553Y79800D01*
Y78600D01*
X1212053Y77100D01*
Y75901D01*
X1213486Y74468D01*
Y72588D01*
X1214574Y71500D01*
G01X1214874Y87374D02*
X1215000D01*
X1215886Y86488D01*
Y73475D01*
X1216661Y72700D01*
Y71076D01*
X1215085Y69500D01*
X1213861D01*
X1211614Y67253D01*
Y65699D01*
G01X1187963Y89900D02*
X1189082Y88782D01*
X1190597Y87266D01*
X1191069Y86794D01*
Y70648D01*
X1189741Y69320D01*
X1188759D01*
X1187989Y68550D01*
G01X1193063Y87514D02*
Y87515D01*
X1194161D01*
X1195195Y86481D01*
Y83706D01*
X1194489Y83000D01*
X1193975D01*
X1193275Y82300D01*
Y81300D01*
X1193975Y80600D01*
X1194475D01*
X1195195Y79880D01*
Y78507D01*
X1194388Y77700D01*
X1193690D01*
X1193089Y77099D01*
Y75901D01*
X1193690Y75300D01*
X1194488D01*
X1195195Y74593D01*
Y71972D01*
X1194172Y70949D01*
X1193063D01*
G01X1187963Y87300D02*
X1189064D01*
X1190009Y86355D01*
Y83820D01*
X1189039Y82850D01*
X1188691D01*
X1188075Y82234D01*
Y80902D01*
X1188577Y80400D01*
X1189289D01*
X1190009Y79680D01*
Y78720D01*
X1189189Y77900D01*
X1188689D01*
X1188089Y77300D01*
Y76300D01*
X1190009Y74380D01*
Y71091D01*
X1189298Y70380D01*
X1188782D01*
X1187963Y71199D01*
G01X1193063Y90114D02*
X1194138Y89038D01*
X1194630Y88546D01*
X1195911Y87266D01*
X1196255Y86922D01*
Y71532D01*
X1193063Y68340D01*
G01X1168110Y518157D02*
X1166405Y519862D01*
Y530049D01*
X1171456Y535100D01*
G01Y513114D02*
X1171368D01*
X1169682Y514800D01*
Y516492D01*
X1169857Y516667D01*
Y519300D01*
X1168745Y520412D01*
Y521488D01*
X1169757Y522500D01*
Y523700D01*
X1168745Y524712D01*
Y525788D01*
X1169882Y526925D01*
Y528199D01*
X1169182Y528899D01*
X1168110D01*
G01X1161417Y518157D02*
X1159712Y519862D01*
Y530049D01*
X1164763Y535100D01*
G01Y513114D02*
X1164675D01*
X1162989Y514800D01*
Y516492D01*
X1163164Y516667D01*
Y519300D01*
X1162052Y520412D01*
Y521488D01*
X1163064Y522500D01*
Y523700D01*
X1162052Y524712D01*
Y525788D01*
X1163189Y526925D01*
Y528199D01*
X1162489Y528899D01*
X1161417D01*
G01X1181496Y518157D02*
X1179791Y519862D01*
Y531515D01*
X1182976Y534700D01*
X1184142D01*
G01Y513114D02*
X1184054D01*
X1182368Y514800D01*
Y516492D01*
X1183275Y517399D01*
Y518992D01*
X1182131Y520136D01*
Y521556D01*
X1182975Y522400D01*
Y524100D01*
X1182131Y524944D01*
Y526156D01*
X1183075Y527100D01*
Y528300D01*
X1182476Y528899D01*
X1181496D01*
G01X1204921Y518157D02*
X1203216Y519862D01*
Y530049D01*
X1208267Y535100D01*
G01Y513114D02*
X1208179D01*
X1206493Y514800D01*
Y516492D01*
X1206668Y516667D01*
Y519300D01*
X1205556Y520412D01*
Y521488D01*
X1206568Y522500D01*
Y523700D01*
X1205556Y524712D01*
Y525788D01*
X1206693Y526925D01*
Y528199D01*
X1205993Y528899D01*
X1204921D01*
G01X1174803Y518157D02*
X1173098Y519862D01*
Y529835D01*
X1173720Y530457D01*
Y531645D01*
X1176775Y534700D01*
X1177763D01*
G01X1177849Y513114D02*
X1177761D01*
X1176075Y514800D01*
Y517000D01*
X1176575Y517500D01*
Y519399D01*
X1175438Y520536D01*
Y521864D01*
X1176375Y522801D01*
Y524199D01*
X1175438Y525136D01*
Y526364D01*
X1176475Y527401D01*
Y528299D01*
X1175875Y528899D01*
X1174803D01*
G01X1198228Y518157D02*
X1196523Y519862D01*
Y530049D01*
X1201574Y535100D01*
G01Y513114D02*
X1201486D01*
X1199800Y514800D01*
Y516492D01*
X1199975Y516667D01*
Y519300D01*
X1198863Y520412D01*
Y521488D01*
X1199875Y522500D01*
Y523700D01*
X1198863Y524712D01*
Y525788D01*
X1200000Y526925D01*
Y528199D01*
X1199300Y528899D01*
X1198228D01*
G01X1218307Y518157D02*
X1216602Y519862D01*
Y531515D01*
X1219787Y534700D01*
X1220953D01*
G01X1211614Y518157D02*
X1209909Y519862D01*
Y529835D01*
X1210531Y530457D01*
Y531645D01*
X1213586Y534700D01*
X1214574D01*
G01X1214874Y512774D02*
X1212886Y514762D01*
Y517000D01*
X1213386Y517500D01*
Y519399D01*
X1212249Y520536D01*
Y521864D01*
X1213100Y522715D01*
Y524285D01*
X1212249Y525136D01*
Y526364D01*
X1213086Y527201D01*
Y528215D01*
X1212402Y528899D01*
X1211614D01*
G01X1187963Y515300D02*
X1189675Y517012D01*
Y518600D01*
X1188575Y519700D01*
X1187625D01*
X1187035Y520290D01*
Y521660D01*
X1187555Y522180D01*
X1188165D01*
X1188775Y522790D01*
Y524180D01*
X1188165Y524790D01*
X1187585D01*
X1187035Y525340D01*
Y526760D01*
X1187675Y527400D01*
X1188955D01*
X1189694Y528139D01*
Y530045D01*
X1187989Y531750D01*
G01X1193063Y512914D02*
X1192775D01*
X1191358Y514331D01*
Y519300D01*
X1190528Y520130D01*
Y526670D01*
X1191358Y527500D01*
Y532444D01*
X1193063Y534149D01*
G01X1187963Y512700D02*
X1187675D01*
X1185975Y514400D01*
Y532411D01*
X1187963Y534399D01*
G01X1193063Y515514D02*
X1194775Y517226D01*
Y518900D01*
X1193775Y519900D01*
X1192259D01*
X1191588Y520571D01*
Y521848D01*
X1192040Y522300D01*
X1192375D01*
X1193075Y523000D01*
Y524088D01*
X1192365Y524798D01*
X1192128D01*
X1191588Y525338D01*
Y526229D01*
X1192359Y527000D01*
X1193875D01*
X1194875Y528000D01*
Y529728D01*
X1193063Y531540D01*
G01X1220953Y513114D02*
X1220865D01*
X1219179Y514800D01*
Y516492D01*
X1220086Y517399D01*
Y518992D01*
X1218942Y520136D01*
Y521556D01*
X1219786Y522400D01*
Y524100D01*
X1218942Y524944D01*
Y526156D01*
X1219886Y527100D01*
Y528300D01*
X1219287Y528899D01*
X1218307D01*
G01X1241732Y92757D02*
X1240611Y91636D01*
Y88700D01*
X1243953Y85358D01*
Y84300D01*
X1242153Y82500D01*
Y80925D01*
X1243353Y79725D01*
Y78599D01*
X1242153Y77399D01*
Y76026D01*
X1243511Y74668D01*
Y73467D01*
X1245078Y71900D01*
G01X1241732Y65699D02*
Y66953D01*
X1244279Y69500D01*
X1245279D01*
X1247079Y71300D01*
Y72700D01*
X1246467Y73312D01*
Y86325D01*
X1245078Y87714D01*
G01X1235039Y92757D02*
X1234111Y91829D01*
Y88701D01*
X1237153Y85659D01*
Y84274D01*
X1235478Y82599D01*
Y81476D01*
X1236978Y79976D01*
Y78624D01*
X1235478Y77124D01*
Y75901D01*
X1236911Y74468D01*
Y73374D01*
X1238385Y71900D01*
G01X1235039Y65699D02*
Y66953D01*
X1237586Y69500D01*
X1238586D01*
X1240386Y71300D01*
Y72700D01*
X1239774Y73312D01*
Y86325D01*
X1238385Y87714D01*
G01X1224774Y89900D02*
X1227880Y86794D01*
Y70648D01*
X1226552Y69320D01*
X1225570D01*
X1224800Y68550D01*
G01X1229874Y87514D02*
Y87515D01*
X1230972D01*
X1232006Y86481D01*
Y83706D01*
X1231300Y83000D01*
X1230786D01*
X1230086Y82300D01*
Y81300D01*
X1230786Y80600D01*
X1231286D01*
X1232006Y79880D01*
Y78507D01*
X1231199Y77700D01*
X1230501D01*
X1229900Y77099D01*
Y75901D01*
X1230501Y75300D01*
X1231299D01*
X1232006Y74593D01*
Y71972D01*
X1230983Y70949D01*
X1229874D01*
G01X1224774Y87300D02*
X1225873D01*
X1226820Y86353D01*
Y83820D01*
X1225850Y82850D01*
X1225502D01*
X1224886Y82234D01*
Y80902D01*
X1225388Y80400D01*
X1226100D01*
X1226820Y79680D01*
Y78720D01*
X1226000Y77900D01*
X1225500D01*
X1224900Y77300D01*
Y76300D01*
X1226820Y74380D01*
Y71091D01*
X1226109Y70380D01*
X1225593D01*
X1224774Y71199D01*
G01X1229874Y90114D02*
X1233066Y86922D01*
Y71532D01*
X1229874Y68340D01*
G01X1241732Y518157D02*
X1240027Y519862D01*
Y530049D01*
X1245078Y535100D01*
G01Y513114D02*
X1244990D01*
X1243304Y514800D01*
Y516492D01*
X1243479Y516667D01*
Y519300D01*
X1242367Y520412D01*
Y521488D01*
X1243379Y522500D01*
Y523700D01*
X1242367Y524712D01*
Y525788D01*
X1243504Y526925D01*
Y528199D01*
X1242804Y528899D01*
X1241732D01*
G01X1235039Y518157D02*
X1233334Y519862D01*
Y530049D01*
X1238385Y535100D01*
G01Y513114D02*
X1238297D01*
X1236611Y514800D01*
Y516492D01*
X1236786Y516667D01*
Y519300D01*
X1235674Y520412D01*
Y521488D01*
X1236686Y522500D01*
Y523700D01*
X1235674Y524712D01*
Y525788D01*
X1236811Y526925D01*
Y528199D01*
X1236111Y528899D01*
X1235039D01*
G01X1224774Y515300D02*
X1226486Y517012D01*
Y518600D01*
X1225386Y519700D01*
X1224436D01*
X1223846Y520290D01*
Y521660D01*
X1224366Y522180D01*
X1224976D01*
X1225586Y522790D01*
Y524180D01*
X1224976Y524790D01*
X1224396D01*
X1223846Y525340D01*
Y526760D01*
X1224486Y527400D01*
X1225766D01*
X1226505Y528139D01*
Y530045D01*
X1224800Y531750D01*
G01X1229874Y512914D02*
X1229586D01*
X1228169Y514331D01*
Y519300D01*
X1227339Y520130D01*
Y526670D01*
X1228169Y527500D01*
Y532444D01*
X1229874Y534149D01*
G01X1224774Y512700D02*
X1224486D01*
X1222786Y514400D01*
Y532411D01*
X1224774Y534399D01*
G01X1229874Y515514D02*
X1231586Y517226D01*
Y518900D01*
X1230586Y519900D01*
X1229070D01*
X1228399Y520571D01*
Y521848D01*
X1228851Y522300D01*
X1229186D01*
X1229886Y523000D01*
Y524088D01*
X1229176Y524798D01*
X1228939D01*
X1228399Y525338D01*
Y526229D01*
X1229170Y527000D01*
X1230686D01*
X1231686Y528000D01*
Y529728D01*
X1229874Y531540D01*
G54D25*
G01X779932Y244033D02*
Y242935D01*
X780400Y242467D01*
Y213499D01*
X780032Y213131D01*
Y212133D01*
X779932Y212033D01*
G01X779400Y276200D02*
Y275757D01*
X780600Y274557D01*
Y248068D01*
X779932Y247400D01*
G01Y244033D02*
Y247400D01*
G01X779100Y307900D02*
Y307360D01*
X780600Y305860D01*
Y277709D01*
X779400Y276509D01*
Y276200D01*
G01X779100Y307900D02*
Y308290D01*
X779932Y309122D01*
Y312000D01*
G01Y340033D02*
Y337269D01*
X780500Y336701D01*
Y312568D01*
X779932Y312000D01*
G01Y344200D02*
Y340033D01*
G01X779882Y372033D02*
Y370317D01*
X780300Y369899D01*
Y344568D01*
X779932Y344200D01*
G01X1458550Y503120D02*
X1454140Y507530D01*
Y523824D01*
X1457366Y527050D01*
X1461380D01*
X1471370Y537040D01*
X1485030D01*
X1489380Y541390D01*
Y546030D01*
G01X1474110Y503290D02*
X1464940D01*
X1458960Y509270D01*
Y512470D01*
X1458935D01*
G01X1478700Y533700D02*
X1478400Y533400D01*
X1472850D01*
X1468740Y529290D01*
Y508710D01*
X1469880Y507570D01*
G54D16*
X42724Y644684D03*
Y644656D03*
Y654684D03*
Y654656D03*
X67724Y644684D03*
Y644656D03*
Y654684D03*
Y654656D03*
X221656Y644656D03*
X196656D03*
X231446Y644756D03*
Y644784D03*
X221656Y644684D03*
X196656D03*
X221656Y654656D03*
X196656D03*
X231446Y654756D03*
Y654784D03*
X221656Y654684D03*
X196656D03*
X409240Y644564D03*
X418914Y644486D03*
Y644514D03*
X409240Y644536D03*
Y654564D03*
X418914Y654486D03*
Y654514D03*
X409240Y654536D03*
X443914Y644486D03*
Y644514D03*
Y654486D03*
Y654514D03*
X596707Y644293D03*
X571707D03*
X596708Y644266D03*
X571708D03*
X596707Y654293D03*
X571707D03*
X596708Y654266D03*
X571708D03*
X606462Y644245D03*
X631462D03*
X606462Y644217D03*
X631462D03*
X606462Y654245D03*
X631462D03*
X606462Y654217D03*
X631462D03*
X912351Y644245D03*
X887351D03*
X912351Y644273D03*
X887351D03*
X912351Y654245D03*
X887351D03*
X912351Y654273D03*
X887351D03*
X922116Y644206D03*
Y644234D03*
Y654206D03*
Y654234D03*
X1225877Y644262D03*
X1235614Y644236D03*
X1260614D03*
X1235614Y644264D03*
X1260614D03*
X1225877Y644234D03*
Y654262D03*
X1235614Y654236D03*
X1260614D03*
X1235614Y654264D03*
X1260614D03*
X1225877Y654234D03*
X1514375Y644292D03*
Y644264D03*
Y654292D03*
Y654264D03*
X1539375Y644292D03*
Y644264D03*
Y654292D03*
Y654264D03*
G54D26*
G01X3600Y36200D02*
Y35800D01*
X10300Y29100D01*
X14700D01*
X16400Y27400D01*
Y24744D01*
G01X16625Y56211D02*
Y55133D01*
X15100Y53608D01*
X3500D01*
X1900Y52008D01*
Y44616D01*
X4500Y42016D01*
Y38100D01*
X3600Y37200D01*
Y36200D01*
G01X3100Y65900D02*
X4900D01*
X11300Y59500D01*
X15024D01*
X16625Y57899D01*
Y56211D01*
G01X66350Y347950D02*
X66300Y347900D01*
Y346000D01*
X65400Y345100D01*
X60100D01*
X56400Y348800D01*
Y359947D01*
X52103Y364244D01*
Y395175D01*
X58737Y401809D01*
Y405774D01*
X61327Y408364D01*
Y416327D01*
X89610Y444610D01*
Y471447D01*
X94578Y476415D01*
Y481192D01*
X94998Y481612D01*
G01X90518Y388828D02*
X84828D01*
X82600Y386600D01*
X64400D01*
X59700Y391300D01*
X56800D01*
X54900Y389400D01*
G01X448226Y11100D02*
Y8916D01*
X450282Y6860D01*
X599866D01*
X602163Y9157D01*
G01X558911Y218147D02*
X560000Y217058D01*
Y213000D01*
G01D02*
X622122Y150878D01*
Y126808D01*
X626507Y122423D01*
X634657D01*
X637096Y119984D01*
Y111286D01*
X640010Y108372D01*
X647228D01*
X655189Y100411D01*
Y85700D01*
X653589Y84100D01*
X647700D01*
X647600Y84200D01*
G01X645430Y31067D02*
Y76291D01*
X647600Y78461D01*
Y84200D01*
G01X674300Y489500D02*
X672000Y487200D01*
Y461300D01*
X699100Y434200D01*
Y402400D01*
X696700Y400000D01*
Y381676D01*
X704600Y373776D01*
Y361200D01*
X706800Y359000D01*
Y329200D01*
X708300Y327700D01*
X711900D01*
G01X797000Y404700D02*
X796880Y404580D01*
X774352D01*
X773212Y405720D01*
X747517D01*
X743372Y409865D01*
X727784D01*
X720711Y402792D01*
Y385144D01*
X722490Y383365D01*
Y322562D01*
X721880Y321952D01*
Y321948D01*
X718135Y318203D01*
Y315025D01*
X713970Y310860D01*
G01X770300Y204930D02*
X768026Y207204D01*
Y207662D01*
X768000Y207688D01*
Y209512D01*
X768026Y209538D01*
Y221195D01*
X766632Y222589D01*
G01X766532Y254652D02*
X767548D01*
X774200Y248000D01*
X779332D01*
X779932Y247400D01*
G01X767310Y286530D02*
X767464Y286376D01*
Y285757D01*
X772921Y280300D01*
X775300D01*
X779400Y276200D01*
G01X779932Y312000D02*
X773900D01*
X767400Y318500D01*
X767000D01*
G01X766643Y382724D02*
X774167Y375200D01*
X777999D01*
X779882Y373317D01*
Y372033D01*
G01X767477Y350708D02*
X774085Y344100D01*
X779832D01*
X779932Y344200D01*
G01X769500Y510100D02*
Y511608D01*
X764274Y516834D01*
Y519097D01*
X767600Y522423D01*
Y530099D01*
X769500Y531999D01*
Y536983D01*
G01Y574700D02*
Y569899D01*
X767300Y567699D01*
Y561699D01*
X764130Y558529D01*
Y553270D01*
X769500Y547900D01*
G01Y585700D02*
Y595950D01*
X767500Y597950D01*
Y606400D01*
X769500Y608400D01*
Y612583D01*
G01X1097834Y11100D02*
Y8916D01*
X1099890Y6860D01*
X1249270D01*
X1251567Y9157D01*
X1251771D01*
G01X1324707Y545493D02*
X1324502Y545698D01*
X1303082D01*
X1300660Y543276D01*
Y526788D01*
X1299272Y525400D01*
X1284377D01*
X1278573Y519596D01*
G01X1457300Y563900D02*
Y564600D01*
X1456362Y565538D01*
Y574508D01*
X1449452Y581418D01*
Y589794D01*
X1465746Y606088D01*
Y614475D01*
X1467839Y616568D01*
Y618964D01*
G01X1794500Y612500D02*
X1790920Y616080D01*
X1773672D01*
X1767637Y610045D01*
X1715600D01*
X1714000Y608445D01*
Y595400D01*
X1711500Y592900D01*
X1709950D01*
G01X1792100Y566900D02*
X1793000Y566000D01*
X1800500D01*
X1801900Y567400D01*
Y571200D01*
X1806800Y576100D01*
X1816000D01*
X1816100Y576200D01*
G01X1794500Y612500D02*
X1794952Y612048D01*
X1825111D01*
X1842560Y594599D01*
Y587940D01*
X1844018Y586482D01*
G01D02*
X1847882D01*
X1854700Y593300D01*
X1878950D01*
X1882420Y596770D01*
X1893880D01*
X1896565Y599455D01*
X1903855D01*
X1913500Y609100D01*
X1928000D01*
X1933553Y614653D01*
X1956207D01*
X1966761Y604099D01*
Y577085D01*
X1966562Y576886D01*
Y576562D01*
X1963000Y573000D01*
G01X1957700Y508670D02*
X1956500Y507470D01*
G01X1947550Y485350D02*
Y498520D01*
X1956500Y507470D01*
G54D17*
X92485Y105000D03*
X72800D03*
G54D27*
G01X280203Y194811D02*
X279992Y194600D01*
G01X929811Y194811D02*
X929600Y194600D01*
G54D18*
X72074Y243282D03*
X65180Y243368D03*
X61800Y243400D03*
X68498Y243368D03*
X49560Y649770D03*
Y644670D03*
X54360D03*
X49560Y649570D03*
Y644670D03*
X54360D03*
X49560Y654670D03*
X54360D03*
X49560D03*
X54360D03*
X214820Y649570D03*
Y644670D03*
X210020D03*
X214820Y649770D03*
Y644670D03*
X210020D03*
X214820Y654670D03*
X210020D03*
X214820D03*
X210020D03*
X238282Y649670D03*
Y644770D03*
Y649870D03*
Y644770D03*
Y654770D03*
D03*
X402404Y649650D03*
Y644550D03*
Y649450D03*
Y644550D03*
Y654550D03*
D03*
X425750Y649400D03*
Y644500D03*
X430550D03*
X425750Y649600D03*
Y644500D03*
X430550D03*
X425750Y654500D03*
X430550D03*
X425750D03*
X430550D03*
X589871Y649379D03*
Y644279D03*
X585071D03*
X589872Y649180D03*
Y644280D03*
X585072D03*
X589871Y654279D03*
X585071D03*
X589872Y654280D03*
X585072D03*
X613298Y649331D03*
Y644231D03*
X618098D03*
X613298Y649131D03*
Y644231D03*
X618098D03*
X613298Y654231D03*
X618098D03*
X613298D03*
X618098D03*
X905515Y649159D03*
Y644259D03*
X900715D03*
X905515Y649359D03*
Y644259D03*
X900715D03*
X905515Y654259D03*
X900715D03*
X905515D03*
X900715D03*
X928952Y649120D03*
Y644220D03*
Y649320D03*
Y644220D03*
Y654220D03*
D03*
X1219041Y649348D03*
Y644248D03*
Y649148D03*
Y644248D03*
Y654248D03*
D03*
X1242450Y649150D03*
Y644250D03*
X1247250D03*
X1242450Y649350D03*
Y644250D03*
X1247250D03*
X1242450Y654250D03*
X1247250D03*
X1242450D03*
X1247250D03*
X1527739Y644278D03*
D03*
Y654278D03*
D03*
X1532539Y649378D03*
Y644278D03*
Y649178D03*
Y644278D03*
Y654278D03*
D03*
G54D28*
G01X548049Y-193422D02*
Y-210922D01*
G01X543027Y-193422D02*
X553071D01*
G01X565549Y-199256D02*
Y-210922D01*
G01Y-194589D02*
X565112Y-194297D01*
Y-193714D01*
X565549Y-193422D01*
X565986Y-193714D01*
Y-194297D01*
X565549Y-194589D01*
G01X583049Y-210922D02*
X581739Y-210630D01*
X580429Y-209464D01*
X579555Y-207422D01*
X579119Y-205089D01*
X579555Y-202755D01*
X580429Y-200714D01*
X581739Y-199547D01*
X583049Y-199256D01*
X584359Y-199547D01*
X585669Y-200714D01*
X586542Y-202755D01*
X586761Y-205089D01*
X586542Y-207422D01*
X585669Y-209464D01*
X584359Y-210630D01*
X583049Y-210922D01*
G01X597492Y-215297D02*
X599021Y-216464D01*
X600767Y-216755D01*
X602295Y-216464D01*
X603606Y-215006D01*
X604479Y-212964D01*
Y-199256D01*
G01Y-201589D02*
X603606Y-200422D01*
X602295Y-199547D01*
X600767Y-199256D01*
X599021Y-199839D01*
X597929Y-201005D01*
X597055Y-203047D01*
X596619Y-205089D01*
X596837Y-206839D01*
X597711Y-208881D01*
X599021Y-210339D01*
X600767Y-210922D01*
X602077Y-210630D01*
X603606Y-209464D01*
X604479Y-208298D01*
G01X621979Y-210922D02*
Y-199256D01*
G01Y-201297D02*
X621106Y-200131D01*
X619795Y-199547D01*
X618267Y-199256D01*
X616739Y-199839D01*
X615429Y-201005D01*
X614555Y-202755D01*
X614119Y-205089D01*
X614555Y-207422D01*
X615429Y-209172D01*
X616739Y-210339D01*
X618267Y-210922D01*
X619795Y-210630D01*
X621106Y-209756D01*
X621979Y-208589D01*
G01X648682Y-210922D02*
Y-193422D01*
X653922D01*
X655669Y-194297D01*
X656979Y-196339D01*
X657416Y-198672D01*
X656979Y-201005D01*
X655887Y-202755D01*
X653922Y-203631D01*
X648682D01*
G01X674479Y-210922D02*
Y-199256D01*
G01Y-201297D02*
X673606Y-200131D01*
X672295Y-199547D01*
X670767Y-199256D01*
X669239Y-199839D01*
X667929Y-201005D01*
X667055Y-202755D01*
X666619Y-205089D01*
X667055Y-207422D01*
X667929Y-209172D01*
X669239Y-210339D01*
X670767Y-210922D01*
X672295Y-210630D01*
X673606Y-209756D01*
X674479Y-208589D01*
G01X684774Y-208881D02*
X685866Y-210047D01*
X687394Y-210922D01*
X688704D01*
X690014Y-210339D01*
X690887Y-209464D01*
X691324Y-208298D01*
X691106Y-206547D01*
X690232Y-205672D01*
X686302Y-203922D01*
X685429Y-201880D01*
X685866Y-200422D01*
X686739Y-199547D01*
X688049Y-199256D01*
X689359Y-199547D01*
X690669Y-200422D01*
G01X702274Y-208881D02*
X703366Y-210047D01*
X704894Y-210922D01*
X706204D01*
X707514Y-210339D01*
X708387Y-209464D01*
X708824Y-208298D01*
X708606Y-206547D01*
X707732Y-205672D01*
X703802Y-203922D01*
X702929Y-201880D01*
X703366Y-200422D01*
X704239Y-199547D01*
X705549Y-199256D01*
X706859Y-199547D01*
X708169Y-200422D01*
G01X735746Y-210922D02*
Y-193422D01*
X740112D01*
X741859Y-194297D01*
X743169Y-195464D01*
X744261Y-197213D01*
X745134Y-199256D01*
X745352Y-202172D01*
X745134Y-205089D01*
X744261Y-207131D01*
X743169Y-208881D01*
X741859Y-210047D01*
X740112Y-210922D01*
X735746D01*
G01X752590Y-193422D02*
X758049Y-210922D01*
X763508Y-193422D01*
G01X775549D02*
Y-210922D01*
G01X770527Y-193422D02*
X780571D01*
G01X804872Y-210922D02*
Y-193422D01*
X810549Y-208005D01*
X816226Y-193422D01*
Y-210922D01*
G01X829795Y-201589D02*
X830669Y-200714D01*
X831324Y-199256D01*
X831761Y-197213D01*
X831324Y-195464D01*
X830451Y-194297D01*
X828922Y-193422D01*
X823027D01*
Y-210922D01*
X830232D01*
X831761Y-209756D01*
X832634Y-208005D01*
X833071Y-205964D01*
X832634Y-203922D01*
X831324Y-202172D01*
X829795Y-201589D01*
X823027D01*
G01X647372Y-165922D02*
Y-148422D01*
X653049Y-163005D01*
X658726Y-148422D01*
Y-165922D01*
G01X670549D02*
X669239Y-165630D01*
X667929Y-164464D01*
X667055Y-162422D01*
X666619Y-160089D01*
X667055Y-157755D01*
X667929Y-155714D01*
X669239Y-154547D01*
X670549Y-154256D01*
X671859Y-154547D01*
X673169Y-155714D01*
X674042Y-157755D01*
X674261Y-160089D01*
X674042Y-162422D01*
X673169Y-164464D01*
X671859Y-165630D01*
X670549Y-165922D01*
G01X691979Y-148422D02*
Y-165922D01*
G01Y-163298D02*
X691106Y-164756D01*
X689795Y-165630D01*
X688267Y-165922D01*
X686521Y-165339D01*
X685211Y-163881D01*
X684337Y-162131D01*
X684119Y-160089D01*
X684337Y-158047D01*
X685211Y-156297D01*
X686521Y-154839D01*
X688267Y-154256D01*
X689795Y-154547D01*
X690887Y-155131D01*
X691979Y-156297D01*
G01X702274Y-158047D02*
X709261D01*
X708606Y-156005D01*
X707514Y-154839D01*
X705986Y-154256D01*
X704457Y-154547D01*
X703147Y-155422D01*
X702274Y-157464D01*
X701837Y-159214D01*
Y-160964D01*
X702274Y-162714D01*
X703366Y-164464D01*
X704676Y-165630D01*
X706204Y-165922D01*
X707732Y-165339D01*
X709261Y-163589D01*
G01X723049Y-165922D02*
Y-148422D01*
G01X975549Y-210922D02*
Y-193422D01*
X972929Y-196922D01*
G01Y-210922D02*
X978169D01*
G01X988246Y-208298D02*
X989555Y-209756D01*
X991084Y-210630D01*
X993049Y-210922D01*
X995014Y-210339D01*
X996542Y-209172D01*
X997634Y-207131D01*
X997852Y-204797D01*
X997416Y-202464D01*
X996324Y-201005D01*
X994795Y-199839D01*
X993267Y-199547D01*
X991739Y-199839D01*
X989774Y-201005D01*
X990429Y-193422D01*
X996324D01*
G01X1010549Y-210922D02*
Y-193422D01*
X1007929Y-196922D01*
G01Y-210922D02*
X1013169D01*
G01X1023901Y-196339D02*
X1025211Y-194589D01*
X1026739Y-193714D01*
X1028486Y-193422D01*
X1030669Y-194005D01*
X1032197Y-195464D01*
X1032634Y-197213D01*
X1032416Y-198964D01*
X1031542Y-200422D01*
X1027176Y-203339D01*
X1025211Y-205380D01*
X1023901Y-208298D01*
X1023464Y-210922D01*
X1032634D01*
G01X1041401Y-203631D02*
X1042929Y-201589D01*
X1044239Y-200422D01*
X1045986Y-199839D01*
X1047514Y-200422D01*
X1048606Y-201589D01*
X1049479Y-203339D01*
X1049697Y-205380D01*
X1049479Y-207131D01*
X1048606Y-208881D01*
X1047295Y-210339D01*
X1045767Y-210922D01*
X1044021Y-210339D01*
X1042492Y-208589D01*
X1041619Y-205964D01*
X1041401Y-203047D01*
X1041837Y-199256D01*
X1042492Y-197213D01*
X1043584Y-195172D01*
X1045112Y-193714D01*
X1046641Y-193422D01*
X1048169Y-194005D01*
X1049261Y-195464D01*
G01X962432Y-165922D02*
Y-148422D01*
X967672D01*
X969419Y-149297D01*
X970729Y-151339D01*
X971166Y-153672D01*
X970729Y-156005D01*
X969637Y-157755D01*
X967672Y-158631D01*
X962432D01*
G01X989102Y-149881D02*
X987792Y-149005D01*
X986264Y-148422D01*
X984517D01*
X982552Y-149297D01*
X981024Y-150755D01*
X979932Y-152506D01*
X979059Y-155422D01*
X978840Y-158047D01*
X979277Y-160672D01*
X979932Y-162422D01*
X981242Y-164172D01*
X982771Y-165339D01*
X984299Y-165922D01*
X985827D01*
X987356Y-165339D01*
X988666Y-164464D01*
X989758Y-163298D01*
G01X1003545Y-156589D02*
X1004419Y-155714D01*
X1005074Y-154256D01*
X1005511Y-152213D01*
X1005074Y-150464D01*
X1004201Y-149297D01*
X1002672Y-148422D01*
X996777D01*
Y-165922D01*
X1003982D01*
X1005511Y-164756D01*
X1006384Y-163005D01*
X1006821Y-160964D01*
X1006384Y-158922D01*
X1005074Y-157172D01*
X1003545Y-156589D01*
X996777D01*
G01X1012749Y-171755D02*
X1025849D01*
G01X1031777Y-165922D02*
Y-148422D01*
X1041821Y-165922D01*
Y-148422D01*
G01X1054299Y-165922D02*
X1052552Y-165630D01*
X1051024Y-164464D01*
X1049714Y-162714D01*
X1048840Y-160672D01*
X1048404Y-158339D01*
Y-156005D01*
X1048840Y-153672D01*
X1049714Y-151630D01*
X1051024Y-149881D01*
X1052552Y-148714D01*
X1054299Y-148422D01*
X1056045Y-148714D01*
X1057574Y-149881D01*
X1058884Y-151630D01*
X1059758Y-153672D01*
X1060194Y-156005D01*
Y-158339D01*
X1059758Y-160672D01*
X1058884Y-162714D01*
X1057574Y-164464D01*
X1056045Y-165630D01*
X1054299Y-165922D01*
G01X1128099Y-210922D02*
Y-193422D01*
X1125479Y-196922D01*
G01Y-210922D02*
X1130719D01*
G01X1147345Y-201589D02*
X1148219Y-200714D01*
X1148874Y-199256D01*
X1149311Y-197213D01*
X1148874Y-195464D01*
X1148001Y-194297D01*
X1146472Y-193422D01*
X1140577D01*
Y-210922D01*
X1147782D01*
X1149311Y-209756D01*
X1150184Y-208005D01*
X1150621Y-205964D01*
X1150184Y-203922D01*
X1148874Y-202172D01*
X1147345Y-201589D01*
X1140577D01*
G01X1105140Y-148422D02*
X1110599Y-165922D01*
X1116058Y-148422D01*
G01X1132466Y-165922D02*
X1123732D01*
Y-148422D01*
X1132466D01*
G01X1128972Y-156880D02*
X1123732D01*
G01X1141232Y-165922D02*
Y-148422D01*
X1146691D01*
X1148437Y-149297D01*
X1149529Y-150464D01*
X1149966Y-152797D01*
X1149529Y-155131D01*
X1148219Y-156589D01*
X1146691Y-157464D01*
X1141232D01*
G01X1146691D02*
X1149966Y-165922D01*
G01X1163099Y-166505D02*
X1162662Y-166214D01*
Y-165630D01*
X1163099Y-165339D01*
X1163536Y-165630D01*
Y-166214D01*
X1163099Y-166505D01*
G01X1264932Y-193422D02*
Y-210922D01*
X1273666D01*
G01X1281996Y-207422D02*
X1283305Y-209464D01*
X1285052Y-210630D01*
X1287017Y-210922D01*
X1288764Y-210630D01*
X1290511Y-209172D01*
X1291602Y-207422D01*
X1291821Y-205672D01*
X1291384Y-203631D01*
X1289856Y-202172D01*
X1288327Y-201589D01*
X1286362D01*
G01X1288327D02*
X1289637Y-200714D01*
X1290729Y-199256D01*
X1291166Y-197506D01*
X1290729Y-195755D01*
X1289637Y-194297D01*
X1287672Y-193422D01*
X1285707Y-193714D01*
X1283742Y-194881D01*
G01X1238682Y-148422D02*
Y-165922D01*
X1247416D01*
G01X1264479D02*
Y-154256D01*
G01Y-156297D02*
X1263606Y-155131D01*
X1262295Y-154547D01*
X1260767Y-154256D01*
X1259239Y-154839D01*
X1257929Y-156005D01*
X1257055Y-157755D01*
X1256619Y-160089D01*
X1257055Y-162422D01*
X1257929Y-164172D01*
X1259239Y-165339D01*
X1260767Y-165922D01*
X1262295Y-165630D01*
X1263606Y-164756D01*
X1264479Y-163589D01*
G01X1273464Y-171172D02*
X1274774Y-171755D01*
X1276521Y-171172D01*
X1277612Y-170006D01*
X1278486Y-168547D01*
X1279795Y-163881D01*
X1282634Y-154256D01*
G01X1275647D02*
X1279795Y-163881D01*
G01X1292274Y-158047D02*
X1299261D01*
X1298606Y-156005D01*
X1297514Y-154839D01*
X1295986Y-154256D01*
X1294457Y-154547D01*
X1293147Y-155422D01*
X1292274Y-157464D01*
X1291837Y-159214D01*
Y-160964D01*
X1292274Y-162714D01*
X1293366Y-164464D01*
X1294676Y-165630D01*
X1296204Y-165922D01*
X1297732Y-165339D01*
X1299261Y-163589D01*
G01X1309992Y-165922D02*
Y-154256D01*
G01Y-156589D02*
X1311084Y-155422D01*
X1312176Y-154547D01*
X1313704Y-154256D01*
X1314795Y-154547D01*
X1316106Y-155422D01*
G01X1380796Y-165922D02*
Y-148422D01*
X1385162D01*
X1386909Y-149297D01*
X1388219Y-150464D01*
X1389311Y-152213D01*
X1390184Y-154256D01*
X1390402Y-157172D01*
X1390184Y-160089D01*
X1389311Y-162131D01*
X1388219Y-163881D01*
X1386909Y-165047D01*
X1385162Y-165922D01*
X1380796D01*
G01X1399824Y-158047D02*
X1406811D01*
X1406156Y-156005D01*
X1405064Y-154839D01*
X1403536Y-154256D01*
X1402007Y-154547D01*
X1400697Y-155422D01*
X1399824Y-157464D01*
X1399387Y-159214D01*
Y-160964D01*
X1399824Y-162714D01*
X1400916Y-164464D01*
X1402226Y-165630D01*
X1403754Y-165922D01*
X1405282Y-165339D01*
X1406811Y-163589D01*
G01X1417324Y-163881D02*
X1418416Y-165047D01*
X1419944Y-165922D01*
X1421254D01*
X1422564Y-165339D01*
X1423437Y-164464D01*
X1423874Y-163298D01*
X1423656Y-161547D01*
X1422782Y-160672D01*
X1418852Y-158922D01*
X1417979Y-156880D01*
X1418416Y-155422D01*
X1419289Y-154547D01*
X1420599Y-154256D01*
X1421909Y-154547D01*
X1423219Y-155422D01*
G01X1438099Y-154256D02*
Y-165922D01*
G01Y-149589D02*
X1437662Y-149297D01*
Y-148714D01*
X1438099Y-148422D01*
X1438536Y-148714D01*
Y-149297D01*
X1438099Y-149589D01*
G01X1452542Y-170297D02*
X1454071Y-171464D01*
X1455817Y-171755D01*
X1457345Y-171464D01*
X1458656Y-170006D01*
X1459529Y-167964D01*
Y-154256D01*
G01Y-156589D02*
X1458656Y-155422D01*
X1457345Y-154547D01*
X1455817Y-154256D01*
X1454071Y-154839D01*
X1452979Y-156005D01*
X1452105Y-158047D01*
X1451669Y-160089D01*
X1451887Y-161839D01*
X1452761Y-163881D01*
X1454071Y-165339D01*
X1455817Y-165922D01*
X1457127Y-165630D01*
X1458656Y-164464D01*
X1459529Y-163298D01*
G01X1469387Y-165922D02*
Y-154256D01*
G01Y-157172D02*
X1470261Y-155714D01*
X1471571Y-154547D01*
X1473317Y-154256D01*
X1474845Y-154547D01*
X1476156Y-155714D01*
X1476811Y-157755D01*
Y-165922D01*
G01X1487324Y-158047D02*
X1494311D01*
X1493656Y-156005D01*
X1492564Y-154839D01*
X1491036Y-154256D01*
X1489507Y-154547D01*
X1488197Y-155422D01*
X1487324Y-157464D01*
X1486887Y-159214D01*
Y-160964D01*
X1487324Y-162714D01*
X1488416Y-164464D01*
X1489726Y-165630D01*
X1491254Y-165922D01*
X1492782Y-165339D01*
X1494311Y-163589D01*
G01X1505042Y-165922D02*
Y-154256D01*
G01Y-156589D02*
X1506134Y-155422D01*
X1507226Y-154547D01*
X1508754Y-154256D01*
X1509845Y-154547D01*
X1511156Y-155422D01*
G01X1426729Y-193422D02*
X1431969D01*
G01X1429349D02*
Y-210922D01*
G01X1426729D02*
X1431969D01*
G01X1441390Y-193422D02*
X1446849Y-210922D01*
X1452308Y-193422D01*
G01X1464349Y-210922D02*
Y-203047D01*
X1459982Y-193422D01*
G01X1468716D02*
X1464349Y-203047D01*
G01X1551799Y-193422D02*
X1550052Y-194005D01*
X1548742Y-195464D01*
X1547869Y-197213D01*
X1547214Y-199547D01*
X1546996Y-202172D01*
X1547214Y-204797D01*
X1547869Y-207131D01*
X1548742Y-208881D01*
X1550052Y-210339D01*
X1551799Y-210922D01*
X1553545Y-210339D01*
X1554856Y-208881D01*
X1555729Y-207131D01*
X1556384Y-204797D01*
X1556602Y-202172D01*
X1556384Y-199547D01*
X1555729Y-197213D01*
X1554856Y-195464D01*
X1553545Y-194005D01*
X1551799Y-193422D01*
G01X1565151Y-196339D02*
X1566461Y-194589D01*
X1567989Y-193714D01*
X1569736Y-193422D01*
X1571919Y-194005D01*
X1573447Y-195464D01*
X1573884Y-197213D01*
X1573666Y-198964D01*
X1572792Y-200422D01*
X1568426Y-203339D01*
X1566461Y-205380D01*
X1565151Y-208298D01*
X1564714Y-210922D01*
X1573884D01*
G01X1582869Y-211505D02*
X1590729Y-193422D01*
G01X1604299Y-210922D02*
Y-193422D01*
X1601679Y-196922D01*
G01Y-210922D02*
X1606919D01*
G01X1621799Y-193422D02*
X1620052Y-194005D01*
X1618742Y-195464D01*
X1617869Y-197213D01*
X1617214Y-199547D01*
X1616996Y-202172D01*
X1617214Y-204797D01*
X1617869Y-207131D01*
X1618742Y-208881D01*
X1620052Y-210339D01*
X1621799Y-210922D01*
X1623545Y-210339D01*
X1624856Y-208881D01*
X1625729Y-207131D01*
X1626384Y-204797D01*
X1626602Y-202172D01*
X1626384Y-199547D01*
X1625729Y-197213D01*
X1624856Y-195464D01*
X1623545Y-194005D01*
X1621799Y-193422D01*
G01X1635369Y-211505D02*
X1643229Y-193422D01*
G01X1652651Y-196339D02*
X1653961Y-194589D01*
X1655489Y-193714D01*
X1657236Y-193422D01*
X1659419Y-194005D01*
X1660947Y-195464D01*
X1661384Y-197213D01*
X1661166Y-198964D01*
X1660292Y-200422D01*
X1655926Y-203339D01*
X1653961Y-205380D01*
X1652651Y-208298D01*
X1652214Y-210922D01*
X1661384D01*
G01X1674299Y-193422D02*
X1672552Y-194005D01*
X1671242Y-195464D01*
X1670369Y-197213D01*
X1669714Y-199547D01*
X1669496Y-202172D01*
X1669714Y-204797D01*
X1670369Y-207131D01*
X1671242Y-208881D01*
X1672552Y-210339D01*
X1674299Y-210922D01*
X1676045Y-210339D01*
X1677356Y-208881D01*
X1678229Y-207131D01*
X1678884Y-204797D01*
X1679102Y-202172D01*
X1678884Y-199547D01*
X1678229Y-197213D01*
X1677356Y-195464D01*
X1676045Y-194005D01*
X1674299Y-193422D01*
G01X1691799Y-210922D02*
Y-193422D01*
X1689179Y-196922D01*
G01Y-210922D02*
X1694419D01*
G01X1708862D02*
X1709299Y-207131D01*
X1709954Y-203922D01*
X1710827Y-201005D01*
X1711919Y-197797D01*
X1713666Y-193422D01*
X1704932D01*
G01X1599496Y-165922D02*
Y-148422D01*
X1603862D01*
X1605609Y-149297D01*
X1606919Y-150464D01*
X1608011Y-152213D01*
X1608884Y-154256D01*
X1609102Y-157172D01*
X1608884Y-160089D01*
X1608011Y-162131D01*
X1606919Y-163881D01*
X1605609Y-165047D01*
X1603862Y-165922D01*
X1599496D01*
G01X1625729D02*
Y-154256D01*
G01Y-156297D02*
X1624856Y-155131D01*
X1623545Y-154547D01*
X1622017Y-154256D01*
X1620489Y-154839D01*
X1619179Y-156005D01*
X1618305Y-157755D01*
X1617869Y-160089D01*
X1618305Y-162422D01*
X1619179Y-164172D01*
X1620489Y-165339D01*
X1622017Y-165922D01*
X1623545Y-165630D01*
X1624856Y-164756D01*
X1625729Y-163589D01*
G01X1639299Y-148422D02*
Y-165922D01*
G01X1636242Y-154256D02*
X1642356D01*
G01X1653524Y-158047D02*
X1660511D01*
X1659856Y-156005D01*
X1658764Y-154839D01*
X1657236Y-154256D01*
X1655707Y-154547D01*
X1654397Y-155422D01*
X1653524Y-157464D01*
X1653087Y-159214D01*
Y-160964D01*
X1653524Y-162714D01*
X1654616Y-164464D01*
X1655926Y-165630D01*
X1657454Y-165922D01*
X1658982Y-165339D01*
X1660511Y-163589D01*
G54D19*
X311021Y9114D03*
X314368Y17057D03*
X324407D03*
X327754Y9114D03*
X321061Y17057D03*
X341140D03*
X337793Y9114D03*
X344486Y17057D03*
Y9122D03*
X347833D03*
X351179Y17057D03*
X354525Y9122D03*
X354526Y17057D03*
X324407Y585714D03*
X344486Y585722D03*
X337793Y585714D03*
X334446D03*
X311021D03*
X341140Y593657D03*
X344486D03*
X351179D03*
X354526D03*
X314368D03*
X324407D03*
X321061D03*
X404723Y17057D03*
X408069Y17042D03*
X414763Y9122D03*
X398029Y17042D03*
X414762Y17058D03*
X414763Y585722D03*
X408069Y593642D03*
X398029D03*
X404723Y593657D03*
X414763D03*
X421455Y9121D03*
X438187Y17059D03*
X424801Y17042D03*
X444880Y9122D03*
Y17059D03*
X431494Y17042D03*
X444880Y585722D03*
Y593659D03*
X431494Y593642D03*
X424801D03*
X438187Y593659D03*
X960629Y9114D03*
X963976Y17057D03*
X970669D03*
X960629Y585714D03*
X963976Y593657D03*
X970669D03*
X990748Y17057D03*
X987401Y9114D03*
X994094Y17057D03*
Y9122D03*
X997441D03*
X1000787Y17057D03*
X1004133Y9122D03*
X1004134Y17057D03*
X974015D03*
X977362Y9114D03*
X987401Y585714D03*
X994094Y585722D03*
X984054Y585714D03*
X974015D03*
X990748Y593657D03*
X994094D03*
X1000787D03*
X1004134D03*
X974015D03*
X1071064Y9122D03*
X1094488D03*
Y17059D03*
X1081102Y17042D03*
X1064371Y17057D03*
X1054331D03*
X1087795Y17059D03*
X1074409Y17042D03*
X1057677D03*
X1064371Y9122D03*
X1047637Y17042D03*
X1064371Y585722D03*
X1094488D03*
X1087795Y593659D03*
X1057677Y593642D03*
X1047637D03*
X1094488Y593659D03*
X1081102Y593642D03*
X1064371Y593657D03*
X1054331D03*
X1464351Y276753D03*
X1461300Y270400D03*
X1454902Y273603D03*
X1458052Y308247D03*
X1464351Y301948D03*
X1451753Y298798D03*
X1458052Y311397D03*
X1454902Y298798D03*
X1451753Y317696D03*
X1448603D03*
X1454902Y301948D03*
Y286202D03*
X1445427Y292526D03*
X1470649Y270454D03*
X1473798Y276753D03*
X1476948Y273603D03*
X1480098D03*
X1496030Y267665D03*
X1480098Y295649D03*
X1473798Y301948D03*
X1483247Y314546D03*
X1486397D03*
X1588176Y157600D03*
X1632574Y106107D03*
X1642150Y118660D03*
X1651536Y134388D03*
X1648386Y156435D03*
X1651536Y112341D03*
Y140687D03*
Y143837D03*
Y131239D03*
Y124939D03*
X1645237Y118640D03*
X1642087Y153286D03*
X1600182Y148562D03*
X1607401Y146947D03*
X1604292Y150137D03*
X1598190Y110711D03*
X1613741Y153286D03*
X1620100Y153300D03*
X1626313Y153312D03*
X1632638Y153286D03*
X1620100Y150200D03*
X1620040Y146987D03*
Y140687D03*
X1632639Y124940D03*
X1600900Y131900D03*
X1610591Y140688D03*
X1651536Y165884D03*
X1638938D03*
X1651536Y162735D03*
X1635788Y159585D03*
X1616891Y165885D03*
X1624966Y172936D03*
X1623276Y165798D03*
X1643662Y172609D03*
X1660985Y156435D03*
X1654673Y118628D03*
X1660985Y115491D03*
X1667238Y112387D03*
X1658154Y99400D03*
X1657835Y115491D03*
Y109191D03*
X1660985D03*
Y146987D03*
X1657836Y137538D03*
X1654686Y134389D03*
X1660985Y131239D03*
Y121790D03*
X1654685Y131239D03*
Y140687D03*
X1664136Y137538D03*
X1657836Y153288D03*
X1657835Y143837D03*
X1660985Y150137D03*
X1657835Y146987D03*
X1654685Y143837D03*
X1660985D03*
Y140688D03*
X1654686Y124940D03*
X1654638Y159685D03*
X1657835Y165884D03*
X1665063Y172608D03*
X1688207Y168972D03*
X1689785Y161180D03*
X1735912Y123750D03*
X1717014Y97550D03*
X1743500Y96400D03*
X1735914Y101700D03*
X1745364Y117450D03*
Y98550D03*
X1745363Y108004D03*
X1746189Y131624D03*
X1745364Y142650D03*
X1745768Y111743D03*
X1745364Y123750D03*
X1742214Y114300D03*
X1731789Y139450D03*
X1723314Y108000D03*
X1726464Y111150D03*
X1739064Y139500D03*
Y123750D03*
X1742214Y120600D03*
X1739064Y130050D03*
Y142650D03*
X1726464Y123750D03*
X1742214Y142650D03*
X1720164Y108000D03*
X1734989Y142750D03*
X1739064Y145800D03*
X1735989Y149050D03*
X1742214Y130050D03*
X1735989Y133250D03*
X1739064Y120600D03*
Y126900D03*
X1735914Y139500D03*
X1739064Y136350D03*
X1723314Y142650D03*
X1742214Y145800D03*
G54D29*
G01X1826Y56447D02*
Y57174D01*
X1316Y57684D01*
X-293D01*
X-3647Y54330D01*
X-12742D01*
X-16200Y50872D01*
Y-6939D01*
X-3566Y-19573D01*
X19424D01*
X19924Y-19073D01*
Y-18875D01*
G01X1863Y59426D02*
Y59184D01*
X1363Y58684D01*
X-708D01*
X-4062Y55330D01*
X-13157D01*
X-17200Y51287D01*
Y-7354D01*
X-3981Y-20573D01*
X21307D01*
X22499Y-19381D01*
G01X74386Y-18439D02*
X72009Y-16062D01*
X63894D01*
X63490Y-15658D01*
X60367D01*
X58641Y-17384D01*
X47157D01*
X44743Y-19798D01*
X42215D01*
X39331Y-16914D01*
X31886D01*
X28940Y-13968D01*
Y2932D01*
X21423Y10449D01*
Y14690D01*
X22947Y16214D01*
X25060D01*
G01X71172Y-18486D02*
X69748Y-17062D01*
X63479D01*
X63075Y-16658D01*
X60782D01*
X59056Y-18384D01*
X47572D01*
X45158Y-20798D01*
X41800D01*
X38916Y-17914D01*
X31471D01*
X27940Y-14383D01*
Y2517D01*
X20423Y10034D01*
Y15105D01*
X23728Y18410D01*
Y18731D01*
G01X150000Y194850D02*
Y196300D01*
X149398Y196900D01*
X129136D01*
X115278Y210758D01*
X114396D01*
X112786Y212368D01*
Y214816D01*
X104000Y223602D01*
Y267251D01*
X99900Y271351D01*
Y290200D01*
X98000Y292100D01*
Y308227D01*
X97203Y309024D01*
Y328477D01*
X89540Y336140D01*
Y337860D01*
X86230Y341170D01*
Y343053D01*
X86150Y343133D01*
Y344667D01*
X87900Y346417D01*
Y347500D01*
G01X88000Y343900D02*
X87130Y343030D01*
Y341543D01*
X90440Y338233D01*
Y336513D01*
X98103Y328850D01*
Y309397D01*
X98900Y308600D01*
Y292473D01*
X100273Y291100D01*
X100274D01*
X100800Y290574D01*
Y271724D01*
X104900Y267624D01*
Y223975D01*
X113686Y215189D01*
Y212741D01*
X114769Y211658D01*
X115651D01*
X129509Y197800D01*
X149450D01*
X150000Y198350D01*
Y199850D01*
G01X93712Y380507D02*
X96572Y383367D01*
Y391912D01*
X92212Y396272D01*
Y412010D01*
X100237Y420035D01*
X109813D01*
X115482Y414366D01*
Y411219D01*
X117256Y409445D01*
X144654D01*
X147899Y406200D01*
X152092D01*
X153392Y407500D01*
G01X97472Y380934D02*
Y392285D01*
X93112Y396645D01*
Y411637D01*
X100610Y419135D01*
X109440D01*
X114582Y413993D01*
Y410846D01*
X116883Y408545D01*
X144281D01*
X147526Y405300D01*
X152091D01*
X153392Y404000D01*
G01X162800Y195600D02*
X164600Y197400D01*
X169963D01*
X243456Y270893D01*
X256685D01*
X257778Y269800D01*
X264576D01*
X265824Y271048D01*
X266227Y271808D01*
X266903Y272016D01*
X267859Y271509D01*
G01X162788Y200650D02*
Y200450D01*
X164938Y198300D01*
X169590D01*
X243083Y271793D01*
X257058D01*
X258151Y270700D01*
X264203D01*
X265092Y271589D01*
X265384Y272141D01*
X265137Y272952D01*
X264179Y273460D01*
G01X564600Y290270D02*
X565740Y289130D01*
X598900D01*
X603405Y284625D01*
Y241075D01*
X611250Y233230D01*
X620880D01*
X625910Y228200D01*
Y199290D01*
X653100Y172100D01*
X660000D01*
X660600Y171500D01*
Y170000D01*
G01X565307Y290978D02*
X566155Y290130D01*
X599315D01*
X604405Y285040D01*
Y241490D01*
X611665Y234230D01*
X621295D01*
X626910Y228615D01*
Y199705D01*
X653515Y173100D01*
X660100D01*
X660600Y173600D01*
Y175000D01*
G01X633410Y269610D02*
X631420Y271600D01*
X628627D01*
X604531Y295696D01*
X563187D01*
G01X633410Y274610D02*
X631300Y272500D01*
X629000D01*
X604904Y296596D01*
X563187D01*
G01X739400Y253400D02*
Y251601D01*
X738868Y251069D01*
X735911D01*
X733912Y249070D01*
Y245846D01*
X736193Y243565D01*
X738580D01*
X744998Y237147D01*
X748594D01*
X755500Y230241D01*
Y210885D01*
X769585Y196800D01*
X798100D01*
X799300Y195600D01*
G01X739500Y247500D02*
Y249537D01*
X738968Y250069D01*
X736326D01*
X734912Y248655D01*
Y246261D01*
X736608Y244565D01*
X738995D01*
X745413Y238147D01*
X749009D01*
X756500Y230656D01*
Y211300D01*
X770000Y197800D01*
X798000D01*
X799300Y199100D01*
G01X917467Y271509D02*
X916511Y272016D01*
X915873Y271819D01*
X915425Y270971D01*
X914154Y269700D01*
X910272D01*
X909372Y270600D01*
X897299D01*
X823599Y196900D01*
X815000D01*
X813700Y195600D01*
G01X913787Y273460D02*
X914745Y272952D01*
X914962Y272239D01*
X914963Y272238D01*
X914610Y271572D01*
X913739Y270700D01*
X910687D01*
X909787Y271600D01*
X896884D01*
X823184Y197900D01*
X814700D01*
X813700Y198900D01*
G01X1208821Y262241D02*
X1209247Y261673D01*
X1210125Y260643D01*
Y260642D01*
X1211003Y259614D01*
X1216465Y254148D01*
X1223444Y245273D01*
Y226944D01*
X1215244Y218744D01*
Y179184D01*
X1221254Y173174D01*
X1229382D01*
X1236801Y165755D01*
X1273460D01*
X1275757Y163458D01*
X1296918D01*
X1297900Y162476D01*
Y161815D01*
X1299907Y159808D01*
G01X1208020Y261642D02*
X1208464Y261048D01*
X1210267Y258934D01*
X1215716Y253482D01*
X1215715D01*
X1222444Y244926D01*
Y227359D01*
X1214244Y219159D01*
Y178769D01*
X1220839Y172174D01*
X1228967D01*
X1236386Y164755D01*
X1273045D01*
X1275342Y162458D01*
X1296503D01*
X1297000Y161961D01*
Y161470D01*
X1295500Y159970D01*
G01X1353569Y208960D02*
X1352169D01*
X1350645Y207436D01*
Y206868D01*
X1342272Y198495D01*
X1303964D01*
X1250879Y251580D01*
Y264421D01*
X1219593Y295707D01*
X1210691D01*
G01X1348569Y208960D02*
X1349245D01*
X1349745Y208460D01*
Y207241D01*
X1341899Y199395D01*
X1304337D01*
X1251779Y251953D01*
Y264794D01*
X1219966Y296607D01*
X1210691D01*
G01X1315130Y164870D02*
X1312930Y167070D01*
Y179336D01*
X1243540Y248726D01*
Y261943D01*
X1213692Y291791D01*
X1209754D01*
G01X1315180Y169950D02*
X1313930Y171200D01*
Y179751D01*
X1244540Y249141D01*
Y262358D01*
X1214107Y292791D01*
X1209754D01*
G01X1380219Y5581D02*
X1380844Y4956D01*
X1381553D01*
X1387966Y11369D01*
Y31800D01*
X1377944Y41822D01*
X1368677D01*
X1368676Y41821D01*
X1367848D01*
X1365429Y44240D01*
X1363275D01*
X1362448Y43413D01*
G01X1380300Y2944D02*
X1381312Y3956D01*
X1381968D01*
X1388966Y10954D01*
Y32215D01*
X1378359Y42822D01*
X1368262D01*
X1365844Y45240D01*
X1363492D01*
X1362674Y46058D01*
G01X1376989Y46971D02*
X1369816D01*
X1366087Y50700D01*
X1354104D01*
X1349985Y46581D01*
Y41304D01*
X1348945Y40264D01*
G01X1351908Y40402D02*
X1350985Y41325D01*
Y46166D01*
X1354519Y49700D01*
X1365672D01*
X1369401Y45971D01*
X1375207D01*
X1376145Y45033D01*
X1379110D01*
G01X1383074Y581963D02*
X1384037Y581000D01*
X1389259D01*
X1393406Y576853D01*
Y571094D01*
X1396380Y568120D01*
X1414358D01*
X1416980Y565498D01*
Y564046D01*
X1418402Y562624D01*
G01X1382500Y579100D02*
X1382599D01*
X1383499Y580000D01*
X1388844D01*
X1392406Y576438D01*
Y570679D01*
X1396065Y567020D01*
X1414043D01*
X1415980Y565083D01*
Y563302D01*
X1415582Y562904D01*
G01X1432560Y561160D02*
X1433800Y562400D01*
Y563735D01*
X1438250Y568185D01*
Y588637D01*
X1434387Y592500D01*
X1404085D01*
X1390000Y606585D01*
Y615600D01*
X1388300Y617300D01*
Y619400D01*
X1387011Y620689D01*
X1386921D01*
G01X1436160Y561200D02*
X1434800Y562560D01*
Y563320D01*
X1439250Y567770D01*
Y589052D01*
X1434802Y593500D01*
X1404500D01*
X1391000Y607000D01*
Y616015D01*
X1389300Y617715D01*
Y619400D01*
X1390589Y620689D01*
X1390851D01*
G01X1451533Y527867D02*
X1449500Y529900D01*
X1447714D01*
X1447000Y529186D01*
Y504499D01*
X1452948Y498551D01*
X1459229D01*
X1459790Y497990D01*
X1469340D01*
X1469901Y498551D01*
X1474823D01*
X1479874Y493500D01*
X1499172D01*
X1503625Y489047D01*
Y487249D01*
G01X1453533Y532667D02*
X1451766Y530900D01*
X1447299D01*
X1445999Y529600D01*
Y528772D01*
X1446000Y528771D01*
Y504084D01*
X1452533Y497551D01*
X1458814D01*
X1459375Y496990D01*
X1469755D01*
X1470316Y497551D01*
X1474408D01*
X1479459Y492500D01*
X1498757D01*
X1502625Y488632D01*
Y487249D01*
G01X1447022Y546578D02*
Y547074D01*
X1447951Y548003D01*
Y550236D01*
X1459923Y562208D01*
Y574269D01*
X1453862Y580330D01*
Y591359D01*
X1466377Y603874D01*
X1505418D01*
X1506893Y605349D01*
X1527423D01*
X1532616Y600156D01*
Y596236D01*
X1533834Y595018D01*
X1565249D01*
X1567703Y597472D01*
Y609743D01*
X1575010Y617050D01*
Y617990D01*
X1573500Y619500D01*
G01X1449922Y546664D02*
Y547102D01*
X1448951Y548073D01*
Y549821D01*
X1460923Y561793D01*
Y574684D01*
X1454862Y580745D01*
Y590944D01*
X1466792Y602874D01*
X1505833D01*
X1507308Y604349D01*
X1527008D01*
X1531616Y599741D01*
Y595821D01*
X1533419Y594018D01*
X1565664D01*
X1568703Y597057D01*
Y609328D01*
X1576010Y616635D01*
Y618510D01*
X1577000Y619500D01*
G01X1497273Y407610D02*
Y403807D01*
X1498220Y402860D01*
X1512120D01*
X1513770Y404510D01*
G01D02*
X1512060Y406220D01*
X1500050D01*
X1498660Y407610D01*
X1497273D01*
G01X1560747Y623576D02*
X1559500Y622329D01*
Y620461D01*
X1557299Y618260D01*
X1551881D01*
X1549195Y620946D01*
X1545675D01*
X1542029Y617300D01*
X1536384D01*
X1533224Y620460D01*
X1526160D01*
X1521840Y616140D01*
X1508426D01*
X1507160Y617406D01*
Y618630D01*
X1505679Y620111D01*
G01X1470356Y618000D02*
X1471636D01*
X1474609Y615027D01*
X1485948D01*
X1490556Y619635D01*
X1495554D01*
X1500207Y614982D01*
X1504092D01*
X1511225Y607849D01*
X1528459D01*
X1531207Y605101D01*
X1535447D01*
X1538520Y608174D01*
Y609420D01*
X1539710Y610610D01*
X1555620D01*
X1558600Y613590D01*
X1561120D01*
X1568248Y620718D01*
Y622118D01*
X1569495Y623365D01*
G01X1557575Y623559D02*
X1558500Y622634D01*
Y620876D01*
X1556884Y619260D01*
X1552296D01*
X1549610Y621946D01*
X1545260D01*
X1541614Y618300D01*
X1536799D01*
X1533639Y621460D01*
X1525745D01*
X1521425Y617140D01*
X1508841D01*
X1508160Y617821D01*
Y619420D01*
X1508550Y619810D01*
G01X1472932Y619131D02*
Y618119D01*
X1475024Y616027D01*
X1485533D01*
X1490141Y620635D01*
X1495969D01*
X1500622Y615982D01*
X1504507D01*
X1511640Y608849D01*
X1528874D01*
X1531622Y606101D01*
X1535032D01*
X1537520Y608589D01*
Y609835D01*
X1539295Y611610D01*
X1555205D01*
X1558185Y614590D01*
X1560705D01*
X1567248Y621133D01*
Y622654D01*
X1566520Y623382D01*
M02*
